;LEADER: 12 
;HEADER: 
;CODE  : ASCII 
;FILE  : 9127_F0T_Expander_BD_F_v02_0110_1240-1-18.drl for  ... layers TOP and BOTTOM
;DESIGN: 9127_F0T_Expander_BD_F_v02_0110_1240.brd
;   Holesize 1. = 8.000000 Tolerance = +0.000000/-8.000000 PLATED MILS Quantity = 10444
;   Holesize 2. = 9.840000 Tolerance = +2.000000/-2.000000 PLATED MILS Quantity = 128
;   Holesize 3. = 10.000000 Tolerance = +0.000000/-10.000000 PLATED MILS Quantity = 26196
;   Holesize 4. = 12.200000 Tolerance = +1.960000/-1.960000 PLATED MILS Quantity = 1360
;   Holesize 5. = 19.680000 Tolerance = +1.960000/-1.960000 PLATED MILS Quantity = 800
;   Holesize 6. = 22.000000 Tolerance = +3.000000/-3.000000 PLATED MILS Quantity = 160
;   Holesize 7. = 32.000000 Tolerance = +2.000000/-2.000000 PLATED MILS Quantity = 4
;   Holesize 8. = 39.990000 Tolerance = +2.000000/-2.000000 PLATED MILS Quantity = 48
;   Holesize 9. = 41.000000 Tolerance = +3.000000/-3.000000 PLATED MILS Quantity = 8
;   Holesize 10. = 44.000000 Tolerance = +2.000000/-2.000000 PLATED MILS Quantity = 32
;   Holesize 11. = 67.000000 Tolerance = +3.000000/-3.000000 PLATED MILS Quantity = 24
;   Holesize 12. = 79.000000 Tolerance = +3.000000/-3.000000 PLATED MILS Quantity = 32
;   Holesize 13. = 126.000000 Tolerance = +3.000000/-3.000000 PLATED MILS Quantity = 10
;   Holesize 14. = 166.000000 Tolerance = +3.000000/-3.000000 PLATED MILS Quantity = 1
;   Holesize 15. = 221.000000 Tolerance = +3.000000/-3.000000 PLATED MILS Quantity = 23
;   Holesize 16. = 30.000000 Tolerance = +3.140000/-0.000000 NON_PLATED MILS Quantity = 2
;   Holesize 17. = 41.000000 Tolerance = +2.000000/-2.000000 NON_PLATED MILS Quantity = 128
;   Holesize 18. = 44.000000 Tolerance = +1.960000/-1.960000 NON_PLATED MILS Quantity = 32
;   Holesize 19. = 44.000000 Tolerance = +2.000000/-2.000000 NON_PLATED MILS Quantity = 16
;   Holesize 20. = 52.000000 Tolerance = +2.000000/-2.000000 NON_PLATED MILS Quantity = 2
;   Holesize 21. = 122.000000 Tolerance = +2.000000/-2.000000 NON_PLATED MILS Quantity = 1
;   Holesize 22. = 125.000000 Tolerance = +2.000000/-0.000000 NON_PLATED MILS Quantity = 4
;   Holesize 23. = 125.000000 Tolerance = +2.000000/-2.000000 NON_PLATED MILS Quantity = 12
;   Holesize 24. = 134.000000 Tolerance = +2.000000/-2.000000 NON_PLATED MILS Quantity = 4
;   Holesize 25. = 178.000000 Tolerance = +2.000000/-2.000000 NON_PLATED MILS Quantity = 16
%
G90
X0044664Y0620661
X0048207Y0620661
X0051750Y0620661
X0044664Y0617861
X0048207Y0617861
X0051750Y0617861
X0055294Y0620661
X0055294Y0617861
X0167432Y1396583
X0167432Y1408495
X0155192Y1396583
X0159552Y1396583
X0155192Y1408495
X0159552Y1408495
X0167432Y1360099
X0167432Y1372385
X0167432Y1384297
X0155192Y1348187
X0159552Y1348187
X0155192Y1360099
X0159552Y1360099
X0155192Y1372385
X0155192Y1384297
X0159552Y1384297
X0159552Y1372385
X0167432Y1348187
X0106232Y1348187
X0110592Y1348187
X0106232Y1360099
X0110592Y1360099
X0130712Y1348187
X0122832Y1348187
X0118472Y1348187
X0130712Y1360099
X0122832Y1360099
X0118472Y1360099
X0147312Y1348187
X0142952Y1348187
X0135072Y1348187
X0142952Y1360099
X0147312Y1360099
X0135072Y1360099
X0081752Y1348187
X0073872Y1348187
X0081752Y1360099
X0073872Y1360099
X0081752Y1372385
X0081752Y1384297
X0073872Y1372385
X0073872Y1384297
X0093992Y1348187
X0098352Y1348187
X0086112Y1348187
X0093992Y1360099
X0098352Y1360099
X0086112Y1360099
X0130712Y1408495
X0122832Y1408495
X0118472Y1408495
X0142952Y1372385
X0142952Y1384297
X0147312Y1372385
X0147312Y1384297
X0135072Y1372385
X0135072Y1384297
X0142952Y1396583
X0147312Y1396583
X0135072Y1396583
X0142952Y1408495
X0147312Y1408495
X0135072Y1408495
X0110592Y1372385
X0106232Y1396583
X0110592Y1396583
X0106232Y1408495
X0110592Y1408495
X0130712Y1372385
X0130712Y1384297
X0122832Y1372385
X0122832Y1384297
X0118472Y1372385
X0118472Y1384297
X0130712Y1396583
X0122832Y1396583
X0118472Y1396583
X0093992Y1384297
X0093992Y1372385
X0098352Y1372385
X0098352Y1384297
X0086112Y1372385
X0086112Y1384297
X0098352Y1396583
X0093992Y1396583
X0086112Y1396583
X0098352Y1408495
X0093992Y1408495
X0086112Y1408495
X0106232Y1372385
X0106232Y1384297
X0110592Y1384297
X0152559Y1232283
X0152559Y1236023
X0145078Y1239763
X0160039Y1232283
X0148818Y1239763
X0167519Y1236023
X0163779Y1228543
X0148818Y1228543
X0156299Y1228543
X0167519Y1232283
X0156299Y1224803
X0163779Y1224803
X0145078Y1228543
X0160039Y1236023
X0167519Y1250984
X0163779Y1247243
X0160039Y1250984
X0163779Y1243503
X0156299Y1247243
X0145078Y1243503
X0141336Y1239762
X0141336Y1247242
X0141337Y1228542
X0145078Y1224803
X0148818Y1236023
X0148818Y1232283
X0145078Y1236023
X0145078Y1232283
X0148818Y1250984
X0148818Y1243503
X0145078Y1250984
X0163779Y1239763
X0163779Y1232283
X0167519Y1224803
X0167519Y1228543
X0163779Y1236023
X0156299Y1236023
X0156299Y1232283
X0152559Y1224803
X0160039Y1224803
X0148818Y1224803
X0152559Y1228543
X0160039Y1228543
X0163779Y1254724
X0156299Y1254724
X0160039Y1258465
X0152559Y1258465
X0167519Y1258465
X0163779Y1250984
X0167519Y1247243
X0167519Y1243503
X0167519Y1239763
X0156299Y1239763
X0152559Y1247243
X0160039Y1243503
X0160039Y1247243
X0156299Y1250984
X0152559Y1243503
X0152559Y1239763
X0160039Y1239763
X0148818Y1254724
X0156299Y1243503
X0160039Y1254724
X0167519Y1254724
X0152559Y1254724
X0152559Y1250984
X0145078Y1247243
X0148818Y1247243
X0154429Y1133169
X0161909Y1133169
X0165649Y1133169
X0143208Y1136909
X0146948Y1136909
X0150689Y1133169
X0165649Y1155610
X0143208Y1129429
X0150689Y1125688
X0146948Y1129429
X0154429Y1125688
X0143208Y1148129
X0146948Y1148129
X0165649Y1144389
X0143207Y1178051
X0146947Y1178051
X0156299Y1176180
X0160039Y1176180
X0143207Y1170570
X0146947Y1170570
X0165649Y1148129
X0152559Y1217322
X0167519Y1202362
X0167519Y1217322
X0163779Y1217322
X0167519Y1194881
X0163779Y1202362
X0167519Y1187401
X0163779Y1209842
X0163779Y1194881
X0152559Y1187401
X0167519Y1209842
X0152559Y1209842
X0163779Y1187401
X0148818Y1206102
X0156299Y1209842
X0152559Y1194881
X0145078Y1206102
X0148818Y1198621
X0148818Y1191141
X0152559Y1202362
X0145078Y1191141
X0156299Y1187401
X0145078Y1198621
X0156299Y1194881
X0156299Y1217322
X0145078Y1213582
X0148818Y1213582
X0156299Y1202362
X0167519Y1183661
X0163779Y1183661
X0160039Y1183661
X0156299Y1179921
X0150688Y1174310
X0150688Y1178051
X0154429Y1174310
X0158169Y1174310
X0146947Y1174310
X0141337Y1198622
X0148818Y1202362
X0148818Y1194881
X0145078Y1202362
X0145078Y1194881
X0141337Y1191142
X0148818Y1187401
X0145078Y1183661
X0145078Y1187401
X0140707Y1178050
X0146948Y1159350
X0146949Y1166830
X0143208Y1159350
X0140707Y1170569
X0146948Y1151870
X0146948Y1144389
X0143208Y1151870
X0143208Y1144389
X0146948Y1125688
X0143208Y1140649
X0143208Y1133169
X0143208Y1125688
X0139468Y1136909
X0146948Y1140649
X0146948Y1133169
X0141337Y1221063
X0141337Y1213583
X0148818Y1217322
X0148818Y1209842
X0145078Y1217322
X0145078Y1209842
X0141337Y1206103
X0150689Y1148129
X0154429Y1151869
X0158169Y1151869
X0150689Y1144389
X0161909Y1155610
X0161909Y1151870
X0161909Y1148129
X0161909Y1144389
X0158169Y1140649
X0165649Y1136909
X0161909Y1129429
X0165649Y1129429
X0161909Y1125688
X0165649Y1140649
X0150689Y1140649
X0154429Y1140649
X0150689Y1136909
X0150689Y1129429
X0154429Y1129429
X0158169Y1129429
X0158169Y1125688
X0161909Y1140649
X0158169Y1133169
X0165649Y1174310
X0165649Y1178050
X0161909Y1181791
X0165649Y1181791
X0161909Y1178051
X0161909Y1174310
X0163779Y1191141
X0167519Y1191141
X0160039Y1191141
X0156299Y1191141
X0152559Y1191141
X0148818Y1183661
X0152559Y1183661
X0156299Y1183661
X0160039Y1187401
X0165649Y1170570
X0165649Y1166830
X0161909Y1159350
X0150688Y1170570
X0154429Y1170570
X0150688Y1166830
X0154429Y1166830
X0158169Y1166830
X0150689Y1159350
X0150689Y1155610
X0154429Y1155610
X0158169Y1155610
X0150689Y1151870
X0160039Y1213582
X0163779Y1221062
X0163779Y1213582
X0152559Y1221062
X0156299Y1221062
X0160039Y1221062
X0152559Y1213582
X0156299Y1213582
X0160039Y1217322
X0160039Y1209842
X0167519Y1221062
X0160039Y1198621
X0163779Y1198621
X0167519Y1206102
X0163779Y1206102
X0152559Y1206102
X0156299Y1206102
X0160039Y1206102
X0152559Y1198621
X0156299Y1198621
X0160039Y1202362
X0160039Y1194881
X0167519Y1198621
X0167519Y1213582
X0148818Y1221062
X0145078Y1221062
X0143208Y1121948
X0150689Y1118208
X0143208Y1114468
X0150689Y1110728
X0143208Y1106988
X0150689Y1073326
X0154429Y1080807
X0158169Y1073326
X0161909Y1080807
X0165649Y1073326
X0146948Y1121948
X0154429Y1118208
X0146948Y1114468
X0154429Y1110728
X0146948Y1106988
X0154429Y1084547
X0158169Y1077066
X0161909Y1084547
X0165649Y1077066
X0161909Y1110728
X0143208Y1099507
X0143208Y1088287
X0150689Y1092027
X0154429Y1099507
X0158169Y1092027
X0161909Y1099507
X0165649Y1092027
X0165649Y1110728
X0146948Y1099507
X0146948Y1088287
X0150689Y1095767
X0154429Y1103247
X0158169Y1095767
X0161909Y1103247
X0165649Y1095767
X0161909Y1121948
X0161909Y1118208
X0165649Y1084547
X0143208Y1103247
X0146948Y1092027
X0146948Y1084547
X0146948Y1080806
X0146948Y1077066
X0143208Y1092027
X0143208Y1084547
X0146948Y1118208
X0146948Y1110728
X0143208Y1118208
X0143208Y1110728
X0146948Y1103247
X0146948Y1095767
X0143208Y1095767
X0150689Y1088287
X0154429Y1088287
X0158169Y1088287
X0150689Y1084547
X0158169Y1084547
X0150689Y1080807
X0158169Y1080807
X0154429Y1077066
X0150688Y1077066
X0161909Y1073326
X0154429Y1073326
X0161909Y1114468
X0165649Y1114468
X0150689Y1121948
X0154429Y1121948
X0158169Y1121948
X0158169Y1118208
X0150689Y1114468
X0154429Y1114468
X0158169Y1114468
X0158169Y1110728
X0154429Y1095767
X0150689Y1106988
X0154429Y1106988
X0161909Y1106988
X0165649Y1106988
X0165649Y1103247
X0165649Y1099507
X0161909Y1095767
X0158169Y1106988
X0150689Y1103247
X0158169Y1103247
X0150689Y1099507
X0158169Y1099507
X0161909Y1092027
X0161909Y1088287
X0165649Y1088287
X0165649Y1080807
X0161909Y1077066
X0154429Y1092027
X0251673Y1118208
X0169389Y1080807
X0169389Y1084547
X0169389Y1103247
X0195570Y1114468
X0210531Y1114468
X0206791Y1114468
X0191830Y1114468
X0199311Y1114468
X0203051Y1114468
X0184350Y1114468
X0188090Y1114468
X0218011Y1114468
X0221752Y1114468
X0225492Y1114468
X0247933Y1118208
X0251673Y1114468
X0240452Y1118208
X0259153Y1118208
X0236712Y1114468
X0247933Y1114468
X0244192Y1118208
X0236712Y1118208
X0244192Y1114468
X0240452Y1114468
X0255413Y1114468
X0255413Y1118208
X0262893Y1114468
X0259153Y1114468
X0262893Y1118208
X0223622Y1086417
X0204921Y1078936
X0208661Y1086417
X0264762Y1075196
X0264762Y1078936
X0242321Y1075196
X0257282Y1075196
X0238581Y1086416
X0268502Y1086416
X0261022Y1082677
X0253542Y1086416
X0246061Y1086417
X0268502Y1082676
X0234841Y1078935
X0238581Y1082676
X0234841Y1075195
X0246061Y1082677
X0249802Y1075196
X0257282Y1078936
X0253542Y1082676
X0261022Y1086417
X0242321Y1078936
X0249802Y1078936
X0201181Y1086417
X0178740Y1086417
X0197440Y1075196
X0216141Y1082677
X0197440Y1078936
X0227362Y1078936
X0212401Y1075196
X0201181Y1082677
X0223622Y1082677
X0231102Y1086417
X0231102Y1082677
X0216141Y1086417
X0182480Y1075196
X0193700Y1082677
X0174999Y1075196
X0178740Y1082677
X0193700Y1086417
X0208661Y1082677
X0189960Y1078936
X0182480Y1078936
X0212401Y1078936
X0219881Y1075196
X0174999Y1078936
X0204921Y1075196
X0227362Y1075196
X0219881Y1078936
X0186220Y1086417
X0186220Y1082677
X0189960Y1075196
X0201181Y1105117
X0189960Y1093897
X0231102Y1105117
X0178740Y1105117
X0204921Y1093897
X0201181Y1101376
X0186220Y1101376
X0178740Y1101376
X0174999Y1097637
X0227362Y1097637
X0219881Y1093897
X0193700Y1101376
X0182480Y1097637
X0216141Y1105117
X0212401Y1093897
X0208661Y1105117
X0264762Y1093897
X0268503Y1101376
X0261023Y1101376
X0261023Y1105117
X0257282Y1093897
X0242321Y1093897
X0238582Y1105117
X0253543Y1101376
X0253543Y1105117
X0246062Y1101376
X0249802Y1093897
X0257282Y1097637
X0249802Y1097637
X0238582Y1101376
X0234841Y1097637
X0242321Y1097637
X0246062Y1105117
X0234841Y1093897
X0268503Y1105117
X0264762Y1097637
X0268503Y1108858
X0264763Y1108858
X0261023Y1108858
X0257283Y1108858
X0253543Y1108858
X0249803Y1108858
X0246062Y1108858
X0242322Y1108858
X0238582Y1108858
X0234842Y1108858
X0231102Y1108858
X0227362Y1108858
X0223622Y1108858
X0219881Y1108858
X0216141Y1108858
X0212401Y1108858
X0208661Y1108858
X0204921Y1108858
X0201181Y1108858
X0197440Y1108858
X0193700Y1108858
X0189960Y1108858
X0186220Y1108858
X0182480Y1108858
X0171259Y1075196
X0178740Y1075196
X0182479Y1071455
X0174998Y1071455
X0182480Y1112598
X0180610Y1121948
X0180610Y1118208
X0180610Y1114468
X0169389Y1110728
X0173129Y1110728
X0178740Y1112598
X0176870Y1121948
X0176870Y1118208
X0176870Y1114468
X0169389Y1121948
X0178740Y1108858
X0182480Y1105117
X0182480Y1101377
X0174999Y1105117
X0171259Y1097637
X0171259Y1093897
X0174999Y1108858
X0169389Y1106988
X0174999Y1101377
X0178740Y1097637
X0182480Y1090157
X0182480Y1082677
X0182480Y1086417
X0171259Y1090157
X0178740Y1093897
X0174999Y1090157
X0171259Y1078936
X0174999Y1082677
X0174999Y1086417
X0178740Y1078936
X0178740Y1090157
X0193700Y1075196
X0186220Y1075196
X0189959Y1071455
X0197439Y1071455
X0195570Y1118208
X0184350Y1121948
X0188090Y1121948
X0191830Y1121948
X0184350Y1118208
X0188090Y1118208
X0191830Y1118208
X0197440Y1105117
X0197440Y1101377
X0193700Y1097637
X0186220Y1093897
X0189960Y1105117
X0186220Y1097637
X0189960Y1101377
X0197440Y1090157
X0197440Y1082677
X0197440Y1086417
X0193700Y1093897
X0186220Y1090157
X0189960Y1090157
X0186220Y1078936
X0193700Y1078936
X0189960Y1082677
X0189960Y1086417
X0193700Y1090157
X0195570Y1121948
X0201181Y1078936
X0204921Y1082677
X0204921Y1086417
X0201181Y1090157
X0208661Y1090157
X0216141Y1093897
X0212401Y1090157
X0216141Y1078936
X0212401Y1082677
X0212401Y1086417
X0216141Y1090157
X0208661Y1093897
X0201181Y1093897
X0204921Y1090157
X0208661Y1078936
X0212400Y1071455
X0204920Y1071455
X0216141Y1075196
X0208661Y1075196
X0201181Y1075196
X0214271Y1121948
X0214271Y1118208
X0210531Y1121948
X0214271Y1114468
X0214271Y1110728
X0210531Y1118208
X0206791Y1121948
X0203051Y1121948
X0203051Y1118208
X0206791Y1118208
X0199311Y1121948
X0199311Y1118208
X0216141Y1097637
X0212401Y1105117
X0212401Y1101377
X0204921Y1105117
X0201181Y1097637
X0208661Y1097637
X0204921Y1101377
X0231102Y1075196
X0223622Y1075196
X0227361Y1071455
X0219880Y1071455
X0229232Y1114468
X0229232Y1118208
X0229232Y1121948
X0221751Y1121948
X0218011Y1121948
X0221751Y1118208
X0218011Y1118208
X0225492Y1121948
X0225492Y1118208
X0223622Y1097637
X0219881Y1105117
X0219881Y1101377
X0227362Y1105117
X0227362Y1101377
X0231102Y1097637
X0231102Y1093897
X0231102Y1078936
X0231102Y1090157
X0223622Y1093897
X0223622Y1078936
X0219881Y1090157
X0219881Y1082677
X0219881Y1086417
X0223622Y1090157
X0227362Y1090157
X0227362Y1082677
X0227362Y1086417
X0242322Y1090157
X0234842Y1086417
X0234842Y1082677
X0242322Y1086417
X0242322Y1082677
X0238582Y1090157
X0238582Y1078936
X0238582Y1075196
X0242321Y1071455
X0234841Y1071454
X0244192Y1121948
X0240452Y1121948
X0236712Y1121948
X0234842Y1105117
X0242322Y1101377
X0238582Y1093897
X0238582Y1097637
X0234842Y1101377
X0242322Y1105117
X0246062Y1075196
X0257282Y1071455
X0249802Y1071455
X0261023Y1075196
X0253543Y1075196
X0261023Y1078936
X0261023Y1090157
X0257283Y1086417
X0257283Y1082677
X0264763Y1090157
X0257283Y1090157
X0246062Y1093897
X0253543Y1078936
X0249803Y1086417
X0249803Y1090157
X0246062Y1078936
X0249803Y1082677
X0246062Y1090157
X0253543Y1090157
X0259153Y1121948
X0262893Y1121948
X0247933Y1121948
X0251673Y1121948
X0255413Y1121948
X0264763Y1105117
X0264763Y1101377
X0261023Y1097637
X0261023Y1093897
X0257283Y1105117
X0253543Y1097637
X0257283Y1101377
X0253543Y1093897
X0246062Y1097637
X0249803Y1101377
X0249803Y1105117
X0264763Y1086417
X0268503Y1090157
X0268503Y1078936
X0264763Y1082677
X0268503Y1075196
X0264762Y1071455
X0266633Y1121948
X0268503Y1097637
X0268503Y1093897
X0234842Y1090157
X0182480Y1093897
X0197440Y1097637
X0186220Y1105117
X0223621Y1105117
X0189960Y1097637
X0212401Y1097637
X0174999Y1093897
X0223621Y1101376
X0219881Y1097637
X0227362Y1093897
X0231102Y1101376
X0197440Y1093897
X0208661Y1101376
X0193700Y1105117
X0216141Y1101376
X0204921Y1097637
X0191830Y1129429
X0191830Y1133169
X0169389Y1136909
X0173129Y1136909
X0184350Y1136909
X0251673Y1211711
X0247932Y1211711
X0189960Y1213582
X0188090Y1148129
X0184350Y1178051
X0184350Y1151870
X0188090Y1174310
X0188090Y1166830
X0184350Y1170570
X0184350Y1159350
X0188090Y1155610
X0188090Y1181791
X0238582Y1217322
X0204921Y1213582
X0251673Y1215452
X0266633Y1215452
X0259153Y1215452
X0221752Y1215452
X0221752Y1211712
X0225492Y1211712
X0229232Y1215452
X0229232Y1211712
X0169389Y1148129
X0189960Y1217322
X0186220Y1217322
X0210531Y1215452
X0208661Y1217322
X0197440Y1217322
X0218011Y1215452
X0201181Y1217322
X0214271Y1215452
X0203051Y1215452
X0195570Y1215452
X0208661Y1213582
X0214271Y1211712
X0201181Y1213582
X0247932Y1215451
X0236712Y1215452
X0236712Y1211712
X0262893Y1215452
X0242322Y1217322
X0255413Y1215452
X0240452Y1215452
X0244192Y1215452
X0169389Y1151870
X0169389Y1159350
X0195570Y1140649
X0184350Y1185531
X0176870Y1159350
X0176870Y1166830
X0176870Y1144389
X0176870Y1148129
X0176870Y1151870
X0184350Y1144389
X0176870Y1181791
X0176870Y1178051
X0176870Y1174310
X0191830Y1193011
X0191830Y1136909
X0203051Y1129429
X0210531Y1129429
X0214271Y1129429
X0203051Y1200491
X0206791Y1200491
X0199311Y1200491
X0210531Y1200491
X0214271Y1200491
X0206791Y1129429
X0199311Y1129429
X0229232Y1200491
X0225492Y1200491
X0221751Y1200491
X0218011Y1200491
X0225492Y1129429
X0221751Y1129429
X0218011Y1129429
X0229232Y1129429
X0240452Y1200491
X0236712Y1129429
X0240452Y1129429
X0244192Y1129429
X0244192Y1200491
X0236712Y1200491
X0251673Y1129429
X0255413Y1129429
X0262893Y1129429
X0259153Y1129429
X0247933Y1129429
X0255413Y1200491
X0247933Y1200491
X0251673Y1200491
X0262893Y1200491
X0259153Y1200491
X0266633Y1129429
X0266633Y1200491
X0210531Y1178051
X0214271Y1178051
X0199311Y1178051
X0203051Y1178051
X0206791Y1178051
X0210531Y1185531
X0214271Y1185531
X0206791Y1185531
X0199311Y1185531
X0203051Y1185531
X0199311Y1151870
X0203051Y1151870
X0206791Y1151870
X0210531Y1151870
X0214271Y1151870
X0210531Y1144389
X0214271Y1144389
X0199311Y1144389
X0203051Y1144389
X0206791Y1144389
X0229232Y1178051
X0218011Y1178051
X0221751Y1178051
X0225492Y1178051
X0229232Y1185531
X0221751Y1185531
X0218011Y1185531
X0225492Y1185531
X0225492Y1151870
X0218011Y1151870
X0221752Y1151870
X0229232Y1151870
X0229232Y1144389
X0218011Y1144389
X0221751Y1144389
X0225492Y1144389
X0244192Y1178051
X0236712Y1178051
X0240452Y1178051
X0244192Y1185531
X0236712Y1185531
X0240452Y1185531
X0244192Y1144389
X0236712Y1144389
X0240452Y1144389
X0244192Y1151869
X0236712Y1151869
X0240452Y1151869
X0259153Y1144389
X0262893Y1144389
X0251673Y1151869
X0255413Y1151869
X0247933Y1151869
X0262893Y1151869
X0259153Y1151869
X0262893Y1178051
X0259153Y1178051
X0255413Y1178051
X0247933Y1178051
X0251673Y1178051
X0262893Y1185531
X0259153Y1185531
X0251673Y1185531
X0255413Y1185531
X0247933Y1185531
X0262893Y1159350
X0262893Y1170570
X0255413Y1144389
X0247933Y1144389
X0251673Y1144389
X0266633Y1166830
X0266633Y1159350
X0266633Y1170570
X0266633Y1144389
X0266633Y1151869
X0266633Y1178051
X0266633Y1185531
X0210531Y1136909
X0214271Y1136909
X0199311Y1136909
X0203051Y1136909
X0206791Y1136909
X0206791Y1193011
X0203051Y1193011
X0199311Y1193011
X0210531Y1193011
X0214271Y1193011
X0229232Y1193011
X0225492Y1193011
X0221751Y1193011
X0218011Y1193011
X0229232Y1136909
X0218011Y1136909
X0221751Y1136909
X0225492Y1136909
X0244192Y1193011
X0236712Y1193011
X0240452Y1193011
X0244192Y1136909
X0236712Y1136909
X0240452Y1136909
X0262893Y1136909
X0259153Y1136909
X0247933Y1136909
X0251673Y1136909
X0255413Y1136909
X0259153Y1193011
X0262893Y1193011
X0247933Y1193011
X0255413Y1193011
X0251673Y1193011
X0266633Y1136909
X0266633Y1193011
X0195570Y1174310
X0195570Y1181791
X0191830Y1178051
X0191830Y1185531
X0195570Y1166830
X0191830Y1170570
X0191830Y1159350
X0195570Y1155610
X0195570Y1148129
X0191830Y1151869
X0191830Y1144389
X0210531Y1174310
X0203051Y1174310
X0199311Y1159350
X0206791Y1159350
X0199311Y1170570
X0203051Y1166830
X0206791Y1170570
X0214271Y1159350
X0210531Y1166830
X0214271Y1170570
X0203051Y1155610
X0210531Y1155610
X0218011Y1174310
X0225492Y1174310
X0229232Y1159350
X0229232Y1170570
X0221751Y1159350
X0218011Y1166830
X0221751Y1170570
X0225492Y1166830
X0225492Y1155610
X0218011Y1155610
X0244192Y1174310
X0236712Y1174310
X0244192Y1166830
X0240452Y1159350
X0240452Y1170570
X0236712Y1166830
X0244192Y1155610
X0236712Y1155610
X0259153Y1155610
X0251673Y1155610
X0259153Y1174310
X0251673Y1174310
X0259153Y1166830
X0247933Y1159350
X0255413Y1159350
X0247933Y1170570
X0255413Y1170570
X0251673Y1166830
X0266633Y1155610
X0266633Y1174310
X0174999Y1213582
X0174999Y1206102
X0171259Y1191141
X0171259Y1198621
X0174999Y1191141
X0171259Y1206102
X0171259Y1213582
X0174999Y1198621
X0191830Y1140649
X0173129Y1185531
X0176870Y1185531
X0197440Y1209842
X0186220Y1213582
X0186220Y1209842
X0186220Y1206102
X0186220Y1198621
X0182480Y1217322
X0182480Y1213582
X0182480Y1209842
X0182480Y1206102
X0182480Y1202362
X0182480Y1198621
X0182480Y1191141
X0182480Y1187401
X0178740Y1217322
X0197440Y1221062
X0201181Y1221062
X0204921Y1221062
X0208661Y1221062
X0212401Y1221062
X0216141Y1221062
X0219881Y1221062
X0223622Y1221062
X0219881Y1217322
X0227362Y1221062
X0231102Y1221062
X0268503Y1221062
X0193700Y1221062
X0189960Y1221062
X0186220Y1221062
X0182480Y1221062
X0178740Y1221062
X0178740Y1213582
X0178740Y1209842
X0178740Y1202362
X0178740Y1206102
X0178740Y1198621
X0178740Y1194881
X0178740Y1191141
X0178740Y1187401
X0238582Y1221062
X0234842Y1221062
X0180610Y1133169
X0180610Y1129429
X0180610Y1125688
X0180610Y1140649
X0169389Y1129428
X0173129Y1129428
X0169389Y1140649
X0173129Y1140649
X0176870Y1136909
X0176870Y1133169
X0176870Y1129429
X0176870Y1125688
X0176870Y1140649
X0169389Y1133169
X0173129Y1133169
X0174999Y1194881
X0174999Y1202362
X0171259Y1194881
X0171259Y1202362
X0180610Y1178051
X0174999Y1187401
X0171259Y1187401
X0173129Y1181791
X0173129Y1178051
X0173129Y1174310
X0180610Y1181791
X0180610Y1174310
X0180610Y1170570
X0180610Y1159350
X0180610Y1166830
X0173129Y1170570
X0173129Y1166830
X0173129Y1159350
X0176870Y1170570
X0180610Y1144389
X0180610Y1151870
X0180610Y1155610
X0173129Y1151870
X0173129Y1155610
X0173129Y1148129
X0169389Y1144389
X0173129Y1144389
X0180610Y1148129
X0180610Y1136909
X0174999Y1209842
X0171259Y1217322
X0174999Y1221062
X0171259Y1221062
X0174999Y1217322
X0171259Y1209842
X0191830Y1219192
X0195570Y1204232
X0195570Y1193011
X0195570Y1196751
X0195570Y1200491
X0184350Y1196751
X0184350Y1193011
X0191830Y1200491
X0191830Y1196751
X0191830Y1204232
X0188090Y1204232
X0188090Y1200491
X0188090Y1196751
X0188090Y1193011
X0195570Y1178051
X0195570Y1185531
X0191830Y1174310
X0191830Y1181791
X0195570Y1189271
X0188090Y1178051
X0188090Y1185531
X0195570Y1170570
X0195570Y1159350
X0191830Y1166830
X0188090Y1170570
X0188090Y1159350
X0195570Y1144389
X0195570Y1151869
X0191830Y1148129
X0191830Y1155610
X0188090Y1151870
X0188090Y1144389
X0195570Y1136909
X0195570Y1125688
X0195570Y1129429
X0195570Y1133169
X0184350Y1140649
X0188090Y1140649
X0188090Y1136909
X0184350Y1133169
X0188090Y1133169
X0184350Y1129429
X0188090Y1129429
X0184350Y1125688
X0188090Y1125688
X0191830Y1125688
X0193700Y1213582
X0195570Y1207972
X0189960Y1209842
X0191830Y1207972
X0193700Y1209842
X0214271Y1133169
X0210531Y1125688
X0214271Y1125688
X0214271Y1140649
X0210531Y1140649
X0210531Y1133169
X0199311Y1133169
X0203051Y1133169
X0206791Y1133169
X0206791Y1125688
X0203051Y1125688
X0199311Y1125688
X0206791Y1140649
X0203051Y1140649
X0199311Y1140649
X0214271Y1207972
X0210531Y1211712
X0210531Y1207972
X0199311Y1207972
X0203051Y1207972
X0206791Y1207972
X0214271Y1204232
X0210531Y1204232
X0210531Y1196751
X0214271Y1196751
X0206791Y1204232
X0203051Y1204232
X0199311Y1204232
X0199311Y1196751
X0203051Y1196751
X0206791Y1196751
X0214271Y1174310
X0206791Y1174310
X0199311Y1174310
X0210531Y1189271
X0214271Y1189271
X0210531Y1181791
X0214271Y1181791
X0199311Y1189271
X0203051Y1189271
X0206791Y1189271
X0199311Y1181791
X0203051Y1181791
X0206791Y1181791
X0210531Y1170570
X0210531Y1159350
X0214271Y1166830
X0203051Y1170570
X0199311Y1166830
X0203051Y1159350
X0206791Y1166830
X0214271Y1155610
X0206791Y1155610
X0199311Y1155610
X0210531Y1148129
X0214271Y1148129
X0206791Y1148129
X0199311Y1148129
X0203051Y1148129
X0229232Y1207972
X0218011Y1207972
X0221751Y1207972
X0218011Y1211712
X0225492Y1207972
X0218011Y1196751
X0221751Y1196751
X0221751Y1204232
X0225492Y1204232
X0225492Y1196751
X0229232Y1204232
X0229232Y1196751
X0218011Y1204232
X0229232Y1174310
X0221751Y1174310
X0229232Y1189271
X0229232Y1181791
X0218011Y1189271
X0221751Y1189271
X0218011Y1181791
X0221751Y1181791
X0225492Y1189271
X0225492Y1181791
X0229232Y1166830
X0218011Y1159350
X0221752Y1166830
X0218011Y1170570
X0225492Y1159350
X0225492Y1170570
X0229232Y1155610
X0221751Y1155610
X0229232Y1148129
X0218011Y1148129
X0221751Y1148129
X0225492Y1148129
X0229232Y1125688
X0229232Y1140649
X0229330Y1132677
X0218011Y1133169
X0221751Y1133169
X0221751Y1125688
X0218011Y1125688
X0221751Y1140649
X0218011Y1140649
X0225492Y1125688
X0225492Y1140649
X0225492Y1133169
X0244192Y1196751
X0244192Y1204232
X0240452Y1196751
X0236712Y1196751
X0236712Y1204232
X0240452Y1204232
X0240452Y1174310
X0244192Y1189271
X0244192Y1181791
X0240452Y1189271
X0236712Y1189271
X0236712Y1181791
X0240452Y1181791
X0244192Y1159350
X0244192Y1170570
X0236712Y1159350
X0236712Y1170570
X0240452Y1166830
X0240452Y1155610
X0244192Y1148129
X0240452Y1148129
X0236712Y1148129
X0244192Y1125688
X0244192Y1140649
X0244192Y1133169
X0240452Y1125688
X0236712Y1125688
X0240452Y1140649
X0236712Y1140649
X0240452Y1133169
X0236712Y1133464
X0236712Y1207972
X0244192Y1207972
X0244192Y1211712
X0242322Y1221062
X0240452Y1211712
X0240452Y1207972
X0255413Y1155610
X0247933Y1155610
X0255413Y1148129
X0251673Y1148129
X0247933Y1148129
X0262893Y1155610
X0262893Y1148129
X0259153Y1148129
X0259153Y1140649
X0262893Y1125688
X0259153Y1125688
X0262893Y1140649
X0262893Y1133169
X0259153Y1133169
X0255413Y1125688
X0251673Y1125688
X0247933Y1125688
X0255413Y1140649
X0251673Y1140649
X0247933Y1140649
X0255413Y1133169
X0251673Y1133169
X0247933Y1133169
X0257283Y1221062
X0261023Y1221062
X0259153Y1211712
X0262893Y1211712
X0259153Y1207972
X0262893Y1207972
X0253543Y1221062
X0246062Y1221062
X0249803Y1221062
X0255413Y1207972
X0255413Y1211712
X0251673Y1207972
X0247933Y1207972
X0262893Y1196751
X0259153Y1196751
X0262893Y1204232
X0259153Y1204232
X0255413Y1196751
X0251673Y1196751
X0247933Y1196751
X0251673Y1204232
X0255413Y1204232
X0247933Y1204232
X0247933Y1174310
X0255413Y1174310
X0259153Y1189271
X0262893Y1181791
X0259153Y1181791
X0262893Y1174310
X0262893Y1189271
X0255413Y1189271
X0251673Y1189271
X0247933Y1189271
X0255413Y1181791
X0251673Y1181791
X0247933Y1181791
X0259153Y1170570
X0259153Y1159350
X0251673Y1159350
X0247933Y1166830
X0255413Y1166830
X0251673Y1170570
X0262893Y1166830
X0266633Y1189271
X0266633Y1148129
X0266633Y1125688
X0266633Y1140649
X0266633Y1133169
X0264763Y1221062
X0266633Y1211712
X0266633Y1207972
X0266633Y1196751
X0266633Y1204232
X0266633Y1181791
X0186220Y1243503
X0186220Y1247243
X0189960Y1250984
X0189960Y1254724
X0193700Y1243503
X0193700Y1247243
X0197440Y1250984
X0197440Y1254724
X0178740Y1243503
X0174999Y1254724
X0227362Y1250984
X0204921Y1254724
X0201181Y1247243
X0171259Y1243503
X0174999Y1250984
X0212401Y1250984
X0227362Y1254724
X0201181Y1243503
X0219881Y1254724
X0212401Y1254724
X0208661Y1247243
X0219881Y1250984
X0204921Y1250984
X0216141Y1243503
X0171259Y1247243
X0208661Y1243503
X0223622Y1247243
X0182480Y1250984
X0216141Y1247243
X0223622Y1243503
X0182480Y1254724
X0178740Y1247243
X0264763Y1236023
X0234842Y1236023
X0249803Y1236023
X0253543Y1224803
X0268503Y1228543
X0261023Y1228543
X0253543Y1243503
X0242322Y1254724
X0231102Y1247243
X0238582Y1243503
X0234842Y1254724
X0249803Y1254724
X0257283Y1254724
X0253543Y1247243
X0257283Y1250984
X0246062Y1247243
X0234842Y1250984
X0189960Y1232283
X0242322Y1250984
X0227362Y1236023
X0231102Y1243503
X0193700Y1224803
X0261023Y1247243
X0249803Y1250984
X0204921Y1236023
X0246062Y1243503
X0261023Y1243503
X0238582Y1247243
X0216141Y1228543
X0201181Y1228543
X0223622Y1228543
X0208661Y1224803
X0227362Y1232283
X0174999Y1236023
X0186220Y1228543
X0223622Y1224803
X0216141Y1224803
X0212401Y1236023
X0189960Y1236023
X0208661Y1254724
X0182480Y1224803
X0182480Y1228543
X0171259Y1239763
X0171259Y1236023
X0174999Y1224803
X0171259Y1232283
X0174999Y1228543
X0174999Y1239763
X0178740Y1236023
X0178740Y1232283
X0171259Y1254724
X0178740Y1254724
X0182480Y1258465
X0175000Y1258465
X0174999Y1247243
X0174999Y1243503
X0178740Y1239763
X0178740Y1250984
X0171259Y1250984
X0182480Y1247243
X0182480Y1243503
X0182480Y1239763
X0189960Y1243503
X0193700Y1250984
X0189960Y1247243
X0186220Y1250984
X0189960Y1239763
X0197440Y1228543
X0186220Y1239763
X0193700Y1239763
X0186220Y1236023
X0193700Y1236023
X0189960Y1224803
X0186220Y1232283
X0189960Y1228543
X0193700Y1232283
X0197440Y1224803
X0186220Y1254724
X0193700Y1254724
X0197441Y1258465
X0189960Y1258465
X0197440Y1243503
X0197440Y1247243
X0204921Y1247243
X0201181Y1250984
X0204921Y1243503
X0204921Y1239763
X0197440Y1239763
X0208661Y1236023
X0201181Y1236023
X0204921Y1224803
X0201181Y1232283
X0204921Y1228543
X0208661Y1232283
X0216141Y1239763
X0216141Y1236023
X0212401Y1224803
X0216141Y1232283
X0212401Y1228543
X0208661Y1239763
X0216141Y1254724
X0201181Y1254724
X0204921Y1258465
X0212401Y1258465
X0212401Y1243503
X0216141Y1250984
X0212401Y1247243
X0212401Y1239763
X0201181Y1239763
X0227363Y1258465
X0219882Y1258465
X0227362Y1239763
X0231102Y1250984
X0219881Y1243503
X0219881Y1247243
X0223622Y1250984
X0219881Y1239763
X0227362Y1247243
X0227362Y1243503
X0231102Y1239763
X0231102Y1236023
X0231102Y1232283
X0223622Y1239763
X0223622Y1236023
X0219881Y1224803
X0219881Y1228543
X0223622Y1232283
X0227362Y1224803
X0227362Y1228543
X0231102Y1254724
X0223622Y1254724
X0246062Y1250984
X0242322Y1247243
X0242322Y1239763
X0242322Y1243503
X0234842Y1247243
X0234842Y1243503
X0238582Y1250984
X0234842Y1239763
X0242322Y1224803
X0242322Y1228543
X0238582Y1239763
X0238582Y1236023
X0234842Y1224803
X0234842Y1228543
X0238582Y1232283
X0242322Y1258465
X0234842Y1258465
X0238582Y1254724
X0261023Y1232283
X0253543Y1232283
X0261023Y1236023
X0257283Y1224803
X0257283Y1239763
X0264763Y1228543
X0246062Y1239763
X0253543Y1236023
X0246062Y1236023
X0246062Y1232283
X0249803Y1224803
X0257283Y1228543
X0249803Y1228543
X0261023Y1254724
X0257283Y1258465
X0249803Y1258465
X0261023Y1239763
X0261023Y1250984
X0257283Y1247243
X0257283Y1243503
X0249803Y1239763
X0253543Y1239763
X0246062Y1254724
X0249803Y1247243
X0253543Y1254724
X0253543Y1250984
X0249803Y1243503
X0268503Y1254724
X0264763Y1258465
X0264763Y1243503
X0268503Y1250984
X0264763Y1247243
X0264763Y1239763
X0268503Y1239763
X0264763Y1224803
X0268503Y1232283
X0268503Y1236023
X0208661Y1250984
X0178740Y1224803
X0197440Y1232283
X0171259Y1228543
X0219881Y1236023
X0193700Y1228543
X0208661Y1228543
X0174999Y1232283
X0212401Y1232283
X0182480Y1232283
X0201181Y1224803
X0219881Y1232283
X0186220Y1224803
X0204921Y1232283
X0197440Y1236023
X0182480Y1236023
X0246062Y1224803
X0171259Y1224803
X0234842Y1232283
X0178740Y1228543
X0257283Y1236023
X0257283Y1232283
X0246062Y1228543
X0249803Y1232283
X0268503Y1247243
X0268503Y1243503
X0242322Y1232283
X0231102Y1224803
X0264763Y1250984
X0242322Y1236023
X0264763Y1254724
X0253543Y1228543
X0261023Y1224803
X0231102Y1228543
X0268503Y1224803
X0238582Y1228543
X0238582Y1224803
X0264763Y1232283
X0239383Y1360099
X0239383Y1372385
X0239383Y1384297
X0251623Y1348187
X0259503Y1348187
X0263863Y1348187
X0251623Y1360099
X0259503Y1360099
X0263863Y1360099
X0247263Y1348187
X0239383Y1348187
X0247263Y1360099
X0251623Y1396583
X0259503Y1396583
X0263863Y1396583
X0251623Y1408495
X0259503Y1408495
X0263863Y1408495
X0179672Y1408495
X0171792Y1408495
X0196272Y1396583
X0191912Y1396583
X0184032Y1396583
X0196272Y1408495
X0191912Y1408495
X0184032Y1408495
X0204152Y1396583
X0204152Y1408495
X0247263Y1372385
X0247263Y1384297
X0251623Y1384297
X0251623Y1372385
X0259503Y1372385
X0259503Y1384297
X0263863Y1372385
X0263863Y1384297
X0191912Y1372385
X0191912Y1384297
X0196272Y1372385
X0196272Y1384297
X0184032Y1372385
X0184032Y1384297
X0204152Y1348187
X0204152Y1360099
X0204152Y1372385
X0204152Y1384297
X0179672Y1396583
X0171792Y1396583
X0179672Y1360099
X0171792Y1360099
X0179672Y1372385
X0179672Y1384297
X0171792Y1372385
X0171792Y1384297
X0196272Y1348187
X0191912Y1348187
X0184032Y1348187
X0191912Y1360099
X0196272Y1360099
X0184032Y1360099
X0179672Y1348187
X0171792Y1348187
X0227249Y1445013
X0227249Y1453293
X0227249Y1456013
X0227249Y1464293
X0213969Y1464293
X0213969Y1456013
X0213969Y1445013
X0213969Y1453293
X0308463Y1384297
X0332943Y1348187
X0337303Y1360099
X0332943Y1360099
X0345183Y1348187
X0345183Y1360099
X0283983Y1348187
X0296223Y1348187
X0288343Y1348187
X0283983Y1360099
X0296223Y1360099
X0288343Y1360099
X0300583Y1348187
X0308463Y1348187
X0300583Y1360099
X0308463Y1360099
X0325063Y1348187
X0312823Y1348187
X0320703Y1348187
X0325063Y1360099
X0312823Y1360099
X0320703Y1360099
X0337303Y1348187
X0271743Y1348187
X0276103Y1348187
X0271743Y1360099
X0276103Y1360099
X0361783Y1396583
X0361783Y1408495
X0357423Y1348187
X0349543Y1348187
X0357423Y1360099
X0349543Y1360099
X0361783Y1348187
X0361783Y1360099
X0337303Y1408495
X0332943Y1408495
X0357423Y1384297
X0357423Y1372385
X0349543Y1372385
X0349543Y1384297
X0345183Y1384297
X0345183Y1372385
X0357423Y1396583
X0349543Y1396583
X0345183Y1396583
X0357423Y1408495
X0349543Y1408495
X0345183Y1408495
X0361783Y1372385
X0361783Y1384297
X0312823Y1396583
X0320703Y1396583
X0325063Y1408495
X0312823Y1408495
X0320703Y1408495
X0337303Y1384297
X0337303Y1372385
X0332943Y1372385
X0332943Y1384297
X0337303Y1396583
X0332943Y1396583
X0300583Y1384297
X0300583Y1372385
X0308463Y1372385
X0300583Y1396583
X0308463Y1396583
X0300583Y1408495
X0308463Y1408495
X0325063Y1384297
X0325063Y1372385
X0312823Y1384297
X0312823Y1372385
X0320703Y1384297
X0320703Y1372385
X0325063Y1396583
X0276103Y1408495
X0283983Y1384297
X0283983Y1372385
X0296223Y1372385
X0296223Y1384297
X0288343Y1372385
X0288343Y1384297
X0283983Y1396583
X0296223Y1396583
X0288343Y1396583
X0283983Y1408495
X0296223Y1408495
X0288343Y1408495
X0271743Y1372385
X0271743Y1384297
X0276103Y1372385
X0276103Y1384297
X0271743Y1396583
X0276103Y1396583
X0271743Y1408495
X0302165Y1236023
X0320866Y1228543
X0313385Y1228543
X0317125Y1232283
X0305905Y1224803
X0324606Y1228543
X0324606Y1247243
X0302165Y1250984
X0302165Y1254724
X0313385Y1243503
X0305905Y1228543
X0309645Y1236023
X0290944Y1243503
X0305905Y1247243
X0313385Y1224803
X0320866Y1239763
X0298425Y1228543
X0290944Y1247243
X0290944Y1228543
X0294685Y1232283
X0305905Y1243503
X0298425Y1224803
X0290944Y1224803
X0298425Y1243503
X0309645Y1250984
X0317125Y1250984
X0320866Y1247243
X0313385Y1247243
X0298425Y1247243
X0294685Y1236023
X0317125Y1236023
X0324606Y1239763
X0294685Y1250984
X0309645Y1254724
X0317125Y1254724
X0309645Y1232283
X0302165Y1232283
X0294685Y1254724
X0287204Y1236023
X0283464Y1228543
X0279724Y1254724
X0287204Y1250984
X0283464Y1247243
X0328347Y1228543
X0320866Y1254724
X0279724Y1228543
X0275984Y1236023
X0275984Y1232283
X0275984Y1254724
X0272244Y1258465
X0279724Y1243503
X0275984Y1250984
X0272244Y1239763
X0272244Y1247243
X0272244Y1243503
X0275984Y1239763
X0272244Y1228543
X0272244Y1224803
X0287204Y1224803
X0283464Y1236023
X0287204Y1228543
X0283464Y1232283
X0290944Y1239763
X0290944Y1236023
X0290944Y1232283
X0283464Y1239763
X0279724Y1224803
X0290944Y1254724
X0283464Y1254724
X0287204Y1258465
X0279724Y1258465
X0290944Y1250984
X0294685Y1239763
X0287204Y1239763
X0279724Y1247243
X0287204Y1243503
X0287204Y1247243
X0283464Y1250984
X0279724Y1239763
X0309645Y1239763
X0305905Y1236023
X0309645Y1224803
X0309645Y1228543
X0305905Y1232283
X0298425Y1239763
X0302165Y1224803
X0294685Y1224803
X0302165Y1228543
X0294685Y1228543
X0298425Y1232283
X0298425Y1236023
X0305905Y1254724
X0298425Y1254724
X0302165Y1258465
X0294685Y1258465
X0309645Y1258465
X0305905Y1250984
X0313385Y1239763
X0302165Y1239763
X0305905Y1239763
X0302165Y1243503
X0294685Y1243503
X0302165Y1247243
X0298425Y1250984
X0294685Y1247243
X0317125Y1239763
X0309645Y1243503
X0309645Y1247243
X0313385Y1254724
X0317125Y1258465
X0324606Y1250984
X0324606Y1243503
X0317125Y1243503
X0317125Y1247243
X0313385Y1250984
X0320866Y1243503
X0320866Y1250984
X0328347Y1247243
X0328347Y1239762
X0324606Y1224803
X0324606Y1236023
X0324606Y1232283
X0313385Y1236023
X0317125Y1224803
X0317125Y1228543
X0313385Y1232283
X0320866Y1232283
X0320866Y1224803
X0320866Y1236023
X0279724Y1250984
X0283464Y1243503
X0275984Y1247243
X0287204Y1254724
X0275984Y1243503
X0272244Y1232283
X0275984Y1228543
X0283464Y1224803
X0272244Y1250984
X0272244Y1254724
X0287204Y1232283
X0279724Y1236023
X0279724Y1232283
X0272244Y1236023
X0275984Y1224803
X0270374Y1215452
X0281594Y1211712
X0285334Y1200491
X0281594Y1207972
X0277854Y1200491
X0274114Y1178051
X0277854Y1196751
X0277854Y1207972
X0277854Y1204232
X0281594Y1215452
X0281594Y1200491
X0285334Y1204232
X0274114Y1211712
X0285334Y1211712
X0285334Y1215452
X0285334Y1207972
X0315255Y1193011
X0326476Y1189271
X0315255Y1185531
X0326476Y1181791
X0315255Y1178051
X0326476Y1174310
X0315255Y1170570
X0326476Y1159350
X0315255Y1155610
X0326476Y1151870
X0315255Y1148129
X0326476Y1144389
X0315255Y1140649
X0326476Y1136909
X0311515Y1193011
X0322736Y1189271
X0311515Y1185531
X0322736Y1181791
X0311515Y1178051
X0322736Y1174310
X0311515Y1170570
X0322736Y1159350
X0311515Y1155610
X0322736Y1151870
X0311515Y1148129
X0322736Y1144389
X0311515Y1140649
X0322736Y1136909
X0307775Y1189271
X0307775Y1181791
X0307775Y1174310
X0296555Y1170570
X0296555Y1155610
X0307775Y1151869
X0307775Y1144389
X0304035Y1189271
X0304035Y1181791
X0304035Y1174310
X0292815Y1170570
X0292815Y1155610
X0304035Y1151869
X0292815Y1148129
X0304035Y1144389
X0292815Y1140649
X0285334Y1196751
X0285334Y1136909
X0289074Y1148129
X0285334Y1140649
X0277854Y1215452
X0274114Y1215452
X0289074Y1140649
X0285334Y1144389
X0285334Y1148129
X0281594Y1144389
X0289074Y1181791
X0285334Y1178051
X0313385Y1217322
X0294685Y1206102
X0324606Y1206102
X0324606Y1221062
X0302165Y1217322
X0320866Y1213582
X0320866Y1206102
X0317125Y1202362
X0324606Y1198621
X0298425Y1206102
X0313385Y1202362
X0294685Y1198621
X0320866Y1198621
X0302165Y1209842
X0313385Y1209842
X0305905Y1217322
X0302165Y1202362
X0320866Y1221062
X0324606Y1213582
X0317125Y1209842
X0294685Y1213582
X0317125Y1217322
X0305905Y1209842
X0305905Y1202362
X0298425Y1198621
X0298425Y1213582
X0274114Y1193011
X0274114Y1189271
X0274114Y1185531
X0274114Y1136909
X0274114Y1140649
X0274114Y1144389
X0281594Y1181791
X0274114Y1129429
X0274114Y1200491
X0270373Y1181791
X0285334Y1189271
X0289074Y1189271
X0285334Y1174310
X0285334Y1159350
X0285334Y1166830
X0285334Y1170570
X0285334Y1155610
X0270373Y1166830
X0270373Y1159350
X0270373Y1170570
X0277854Y1170570
X0277854Y1166830
X0277854Y1159350
X0277854Y1155610
X0277854Y1174310
X0307775Y1166830
X0304035Y1159350
X0304035Y1166830
X0320866Y1131299
X0317125Y1127558
X0320866Y1123818
X0324606Y1131299
X0313385Y1135039
X0317125Y1135039
X0324606Y1123818
X0313385Y1127558
X0298425Y1131299
X0294684Y1131299
X0298425Y1123818
X0302165Y1127559
X0302165Y1135039
X0294684Y1123818
X0305905Y1135039
X0305905Y1127559
X0290944Y1138779
X0290944Y1217322
X0290944Y1213582
X0290944Y1209842
X0290944Y1206102
X0290944Y1202362
X0290944Y1198621
X0290944Y1194881
X0290944Y1135039
X0290944Y1131299
X0290944Y1127558
X0290944Y1123818
X0272244Y1221062
X0275984Y1221062
X0279724Y1221062
X0283464Y1221062
X0287204Y1221062
X0290944Y1221062
X0270373Y1185531
X0270373Y1178051
X0274114Y1174310
X0274114Y1181791
X0277854Y1181791
X0274114Y1170570
X0274114Y1159350
X0274114Y1166830
X0270373Y1155610
X0277854Y1151870
X0277854Y1148129
X0277854Y1144389
X0270373Y1151869
X0270373Y1148129
X0270373Y1144389
X0274114Y1148129
X0274114Y1151869
X0274114Y1155610
X0277854Y1125688
X0277854Y1140649
X0277854Y1133169
X0277854Y1136909
X0270373Y1140649
X0270373Y1129429
X0270373Y1125688
X0270373Y1133169
X0270373Y1136909
X0274114Y1125688
X0277854Y1129429
X0277854Y1211712
X0270373Y1207972
X0270373Y1211712
X0274114Y1207972
X0277854Y1193011
X0270373Y1193011
X0270373Y1200491
X0270373Y1204232
X0270393Y1196732
X0274114Y1196751
X0274114Y1204232
X0270373Y1174310
X0277854Y1185531
X0277854Y1189271
X0277854Y1178051
X0270373Y1189271
X0285334Y1193011
X0281594Y1193011
X0290944Y1191141
X0281594Y1204232
X0281594Y1196751
X0292814Y1189271
X0292814Y1174310
X0281594Y1174310
X0281594Y1178051
X0285334Y1181791
X0281594Y1185531
X0281594Y1189271
X0289074Y1185531
X0289074Y1178051
X0289074Y1174310
X0285334Y1185531
X0292814Y1181791
X0292814Y1166830
X0292814Y1159350
X0281594Y1166830
X0281594Y1170570
X0289074Y1159350
X0289074Y1170570
X0289074Y1166830
X0281594Y1159350
X0292814Y1144389
X0292814Y1151869
X0289074Y1144389
X0289074Y1155610
X0289074Y1151869
X0285334Y1151869
X0281594Y1151869
X0281594Y1155610
X0281594Y1148129
X0281594Y1136909
X0281594Y1140649
X0294685Y1217322
X0298425Y1127558
X0302165Y1131299
X0294685Y1135039
X0298425Y1135039
X0300295Y1140649
X0305905Y1123818
X0305905Y1131299
X0304035Y1140649
X0307775Y1140649
X0311515Y1136909
X0309645Y1131299
X0309645Y1127558
X0309645Y1202362
X0305905Y1198621
X0311515Y1196751
X0307775Y1193011
X0309645Y1198621
X0298425Y1194881
X0298425Y1202362
X0302165Y1198621
X0304035Y1193011
X0294685Y1202362
X0294685Y1194881
X0311515Y1189271
X0307775Y1185531
X0311515Y1181791
X0307775Y1178051
X0311515Y1174310
X0300295Y1189271
X0304035Y1178051
X0304035Y1185531
X0298425Y1187401
X0296555Y1174310
X0300295Y1174310
X0300295Y1178051
X0300295Y1181791
X0300295Y1185531
X0311515Y1159350
X0307775Y1170570
X0311515Y1166830
X0300295Y1166830
X0300295Y1170570
X0304035Y1170570
X0296555Y1166830
X0300295Y1159350
X0296555Y1159350
X0307775Y1159350
X0307775Y1155610
X0311515Y1151869
X0307775Y1148129
X0311515Y1144389
X0296555Y1144389
X0300295Y1144389
X0300295Y1148129
X0300295Y1151869
X0300295Y1155610
X0304035Y1148129
X0304035Y1155610
X0296555Y1151869
X0309645Y1123818
X0313385Y1123818
X0309645Y1135039
X0302165Y1123818
X0294685Y1127558
X0305905Y1221062
X0294685Y1221062
X0309645Y1221062
X0309645Y1206102
X0309645Y1213582
X0305905Y1213582
X0309645Y1209842
X0309645Y1217322
X0298425Y1217322
X0302165Y1221062
X0298425Y1221062
X0302165Y1206102
X0298425Y1209842
X0294685Y1209842
X0302165Y1213582
X0305905Y1206102
X0322736Y1148129
X0326476Y1140649
X0324606Y1135039
X0324606Y1127558
X0317125Y1131299
X0313384Y1131299
X0318996Y1136909
X0315255Y1136909
X0318996Y1140649
X0322736Y1140649
X0320866Y1135039
X0320866Y1127558
X0328347Y1131300
X0317125Y1123818
X0328347Y1123819
X0324606Y1217322
X0324606Y1209842
X0317125Y1213582
X0313385Y1213582
X0317125Y1221062
X0313385Y1221062
X0320866Y1209842
X0320866Y1217322
X0328347Y1213582
X0328347Y1221062
X0324606Y1202362
X0326416Y1193011
X0317125Y1198621
X0313385Y1206102
X0317125Y1206102
X0313385Y1198621
X0318996Y1193011
X0320866Y1202362
X0322736Y1193011
X0328347Y1206102
X0328347Y1198621
X0322736Y1185531
X0322736Y1178051
X0326476Y1185531
X0326476Y1178051
X0318996Y1174310
X0315255Y1174310
X0318996Y1178051
X0318996Y1181791
X0318996Y1185531
X0318996Y1189271
X0315255Y1189271
X0315255Y1181791
X0326476Y1170570
X0326476Y1166830
X0318996Y1166830
X0318996Y1170570
X0315255Y1166830
X0318996Y1159350
X0315255Y1159350
X0322736Y1166830
X0322736Y1170570
X0326476Y1155610
X0326476Y1148129
X0318996Y1148129
X0318996Y1151869
X0315255Y1151869
X0318996Y1155610
X0315255Y1144389
X0318996Y1144389
X0322736Y1155610
X0277854Y1114468
X0274114Y1114468
X0281594Y1114468
X0285334Y1114468
X0270373Y1114468
X0281594Y1118208
X0285334Y1118208
X0309644Y1075196
X0320866Y1082676
X0302164Y1075196
X0320866Y1116338
X0317125Y1120078
X0298424Y1082676
X0313384Y1086417
X0317124Y1075196
X0298424Y1086416
X0313384Y1082677
X0313385Y1112598
X0324606Y1116338
X0317125Y1112598
X0320866Y1108858
X0309644Y1078936
X0294684Y1078936
X0317124Y1078936
X0305904Y1086417
X0302164Y1078936
X0324606Y1108858
X0294684Y1075196
X0324606Y1082676
X0305904Y1082677
X0313385Y1120078
X0272243Y1075196
X0283463Y1086416
X0279723Y1078936
X0272243Y1078936
X0279723Y1075196
X0283463Y1082676
X0287203Y1075196
X0290943Y1082677
X0287203Y1078936
X0275982Y1086417
X0275982Y1082677
X0290943Y1086417
X0275984Y1101376
X0317125Y1097637
X0287203Y1097637
X0290944Y1105117
X0302164Y1093897
X0279723Y1097637
X0324606Y1101377
X0272243Y1093897
X0279723Y1093897
X0305905Y1101376
X0309644Y1093897
X0290944Y1101376
X0283464Y1105117
X0313385Y1105117
X0275984Y1105117
X0302165Y1112598
X0294684Y1097637
X0272243Y1097637
X0305905Y1120078
X0324606Y1090157
X0287203Y1093897
X0305905Y1105117
X0302164Y1097637
X0294684Y1116338
X0298425Y1116338
X0320866Y1101377
X0309644Y1097637
X0305905Y1112598
X0298425Y1101376
X0317125Y1093897
X0294684Y1093897
X0283464Y1101376
X0298425Y1105117
X0320866Y1090157
X0313385Y1101377
X0302165Y1120078
X0290944Y1120078
X0290944Y1116338
X0290944Y1112598
X0294685Y1108858
X0290944Y1108858
X0287204Y1108858
X0283464Y1108858
X0279724Y1108858
X0275984Y1108858
X0272244Y1108858
X0324606Y1078936
X0272244Y1090157
X0272244Y1086417
X0275984Y1090157
X0272244Y1082677
X0275984Y1078936
X0275984Y1093897
X0275984Y1075196
X0279724Y1090157
X0272243Y1071455
X0277854Y1121948
X0277854Y1118208
X0270373Y1121948
X0270373Y1118208
X0274114Y1121948
X0274114Y1118208
X0279724Y1105117
X0275984Y1097637
X0279724Y1101377
X0272244Y1105117
X0272244Y1101377
X0283464Y1075196
X0287203Y1071455
X0279723Y1071455
X0294684Y1112598
X0294684Y1120078
X0294685Y1105117
X0294684Y1101377
X0290944Y1097637
X0287204Y1105117
X0283464Y1097637
X0287204Y1101377
X0283464Y1093897
X0290944Y1093897
X0290944Y1075196
X0290943Y1090157
X0283464Y1090157
X0283464Y1078936
X0279724Y1086417
X0287204Y1086417
X0287204Y1082677
X0279724Y1082677
X0290944Y1078936
X0287204Y1090157
X0305906Y1075196
X0298425Y1075196
X0302165Y1071455
X0309645Y1071455
X0294684Y1071455
X0305905Y1093897
X0309644Y1090157
X0309645Y1086417
X0305906Y1078936
X0309644Y1082677
X0305904Y1090157
X0298425Y1093897
X0302165Y1086417
X0302164Y1090157
X0294685Y1086417
X0294684Y1090157
X0298426Y1078936
X0302164Y1082677
X0294684Y1082677
X0298424Y1090157
X0298425Y1120078
X0305905Y1116338
X0309645Y1120078
X0309645Y1116338
X0309645Y1112598
X0313385Y1116338
X0298425Y1112598
X0302165Y1108858
X0298425Y1108858
X0302165Y1116338
X0305905Y1097637
X0309644Y1108858
X0309645Y1101377
X0309645Y1105117
X0305904Y1108857
X0302165Y1105117
X0298425Y1097637
X0302165Y1101377
X0328347Y1090158
X0328347Y1082677
X0313386Y1075196
X0320866Y1075196
X0317125Y1071455
X0313385Y1097637
X0317125Y1101377
X0317126Y1105117
X0317125Y1108858
X0313385Y1108858
X0320866Y1097637
X0320866Y1105117
X0328347Y1108859
X0328347Y1101378
X0324606Y1097637
X0324606Y1105117
X0324606Y1093897
X0324606Y1086417
X0313385Y1093897
X0320866Y1093897
X0313386Y1078936
X0317125Y1082677
X0317126Y1086417
X0317125Y1090157
X0313384Y1090157
X0320866Y1078936
X0320866Y1086417
X0320866Y1120078
X0320866Y1112598
X0328347Y1116339
X0324606Y1120078
X0324606Y1112598
X0317125Y1116338
X0422223Y0444629
X0425023Y0444629
X0422223Y0437543
X0422223Y0433999
X0422223Y0441086
X0425023Y0437543
X0425023Y0433999
X0425023Y0441086
X0369663Y1396583
X0369663Y1408495
X0369663Y1348187
X0369663Y1360099
X0369663Y1384297
X0369663Y1372385
X0462642Y1372385
X0462642Y1384297
X0450402Y1372385
X0450402Y1384297
X0438162Y1372385
X0438162Y1384297
X0446042Y1360099
X0458282Y1360099
X0438162Y1360099
X0446042Y1348187
X0458282Y1348187
X0438162Y1348187
X0462642Y1360099
X0462642Y1348187
X0450402Y1360099
X0450402Y1348187
X0450402Y1408495
X0450402Y1396583
X0462642Y1408495
X0462642Y1396583
X0446042Y1384297
X0458282Y1384297
X0446042Y1372385
X0458282Y1372385
X0458282Y1408495
X0458282Y1396583
X0568442Y1372385
X0560562Y1372385
X0568442Y1384297
X0560562Y1384297
X0548322Y1372385
X0556202Y1372385
X0548322Y1384297
X0556202Y1384297
X0536082Y1372385
X0536082Y1384297
X0523842Y1372385
X0523842Y1384297
X0507242Y1372385
X0495002Y1372385
X0507242Y1384297
X0495002Y1384297
X0482762Y1372385
X0482762Y1384297
X0474882Y1372385
X0470522Y1372385
X0474882Y1384297
X0470522Y1384297
X0543962Y1360099
X0556202Y1360099
X0531722Y1360099
X0511602Y1360099
X0519482Y1360099
X0523842Y1360099
X0499362Y1360099
X0487122Y1360099
X0470522Y1360099
X0543962Y1348187
X0556202Y1348187
X0531722Y1348187
X0511602Y1348187
X0519482Y1348187
X0523842Y1348187
X0499362Y1348187
X0487122Y1348187
X0470522Y1348187
X0560562Y1360099
X0560562Y1348187
X0548322Y1360099
X0548322Y1348187
X0536082Y1360099
X0536082Y1348187
X0487122Y1384297
X0487122Y1372385
X0474882Y1360099
X0474882Y1348187
X0499362Y1384297
X0499362Y1372385
X0511602Y1384297
X0511602Y1372385
X0474882Y1408495
X0474882Y1396583
X0487122Y1408495
X0487122Y1396583
X0499362Y1408495
X0499362Y1396583
X0511602Y1408495
X0511602Y1396583
X0523842Y1408495
X0523842Y1396583
X0536082Y1408495
X0536082Y1396583
X0548322Y1408495
X0548322Y1396583
X0560562Y1396583
X0560562Y1408495
X0519482Y1372385
X0519482Y1384297
X0482762Y1348187
X0531722Y1372385
X0531722Y1384297
X0482762Y1360099
X0495002Y1348187
X0543962Y1384297
X0543962Y1372385
X0495002Y1360099
X0470522Y1408495
X0470522Y1396583
X0482762Y1396583
X0482762Y1408495
X0507242Y1348187
X0495002Y1396583
X0495002Y1408495
X0507242Y1396583
X0507242Y1408495
X0507242Y1360099
X0519482Y1408495
X0519482Y1396583
X0531722Y1396583
X0531722Y1408495
X0543962Y1408495
X0543962Y1396583
X0568442Y1396583
X0568442Y1360099
X0568442Y1348187
X0556202Y1396583
X0556202Y1408495
X0568442Y1408495
X0505293Y0617861
X0501750Y0617861
X0505293Y0620661
X0501750Y0620661
X0512380Y0620661
X0508836Y0617861
X0508836Y0620661
X0512380Y0617861
X0607776Y1110728
X0607776Y1073326
X0604035Y1106988
X0604035Y1114468
X0626476Y1080807
X0600295Y1114468
X0622736Y1073326
X0600295Y1121948
X0600295Y1106988
X0626476Y1103247
X0604035Y1088287
X0622736Y1095767
X0611516Y1099507
X0600295Y1088287
X0622736Y1092027
X0604035Y1099507
X0618996Y1099507
X0611516Y1103247
X0630216Y1114468
X0618996Y1110728
X0615256Y1092027
X0600295Y1099507
X0618996Y1103247
X0615256Y1095767
X0607776Y1095767
X0607776Y1092027
X0622736Y1110728
X0626476Y1114468
X0611516Y1110728
X0611516Y1084547
X0611516Y1080807
X0604035Y1121948
X0626476Y1084547
X0622736Y1077066
X0615256Y1077066
X0618996Y1080807
X0615256Y1073326
X0618996Y1084547
X0607776Y1118208
X0611516Y1118208
X0652657Y1114468
X0667618Y1114468
X0663878Y1114468
X0648917Y1114468
X0656398Y1114468
X0660138Y1114468
X0641437Y1114468
X0645177Y1114468
X0618996Y1121948
X0618996Y1118208
X0622736Y1118208
X0658268Y1086417
X0635827Y1082677
X0665748Y1086417
X0650787Y1086417
X0647047Y1075196
X0654527Y1078936
X0635827Y1086417
X0658268Y1082677
X0632086Y1075196
X0654527Y1075196
X0650787Y1082677
X0639567Y1078936
X0647047Y1078936
X0665748Y1082677
X0643307Y1082677
X0643307Y1086417
X0632086Y1078936
X0639567Y1075196
X0662008Y1078936
X0662008Y1075196
X0650787Y1101376
X0643307Y1101376
X0635827Y1101376
X0658268Y1101376
X0639567Y1093897
X0658268Y1105117
X0647047Y1097637
X0665748Y1101376
X0643307Y1105117
X0662008Y1093897
X0632086Y1093897
X0635827Y1105117
X0639567Y1097637
X0654527Y1097637
X0647047Y1093897
X0665748Y1105117
X0632086Y1108858
X0639567Y1108858
X0635827Y1108858
X0643307Y1108858
X0647047Y1108858
X0650787Y1108858
X0654527Y1108858
X0658268Y1108858
X0662008Y1108858
X0665748Y1108858
X0632085Y1071455
X0639566Y1071455
X0647046Y1071455
X0654526Y1071455
X0662007Y1071455
X0658268Y1078936
X0665748Y1097637
X0658268Y1097637
X0662008Y1090157
X0662008Y1086417
X0662008Y1082677
X0658268Y1090157
X0662008Y1105117
X0665748Y1075196
X0658268Y1075196
X0632086Y1086417
X0632086Y1082677
X0635827Y1097637
X0639567Y1082677
X0639567Y1086417
X0632086Y1090157
X0647047Y1090157
X0650787Y1090157
X0628346Y1075196
X0650787Y1093897
X0635827Y1078936
X0643307Y1093897
X0643307Y1078936
X0647047Y1086417
X0647047Y1082677
X0628346Y1090157
X0643307Y1097637
X0650787Y1097637
X0654527Y1101377
X0654527Y1105117
X0647047Y1101377
X0647047Y1105117
X0628346Y1078936
X0650787Y1075196
X0654527Y1090157
X0654527Y1086417
X0654527Y1082677
X0639567Y1090157
X0635827Y1090157
X0628346Y1093897
X0643307Y1090157
X0628346Y1097637
X0650787Y1078936
X0639567Y1105117
X0635827Y1075196
X0632086Y1105117
X0632086Y1101377
X0643307Y1075196
X0635827Y1093897
X0639567Y1101377
X0665748Y1090157
X0604035Y1118208
X0604035Y1110728
X0600295Y1118208
X0600295Y1110728
X0604035Y1095767
X0600295Y1095767
X0600295Y1103247
X0604035Y1103247
X0604035Y1092027
X0604035Y1084547
X0604035Y1080806
X0604035Y1077066
X0600295Y1092027
X0600295Y1084547
X0618996Y1106988
X0618996Y1077066
X0611516Y1092027
X0607776Y1088287
X0611516Y1088287
X0615256Y1088287
X0607776Y1084547
X0615256Y1084547
X0607776Y1080807
X0615256Y1080807
X0611516Y1077066
X0607775Y1077066
X0618996Y1092027
X0618996Y1088287
X0618996Y1073326
X0611516Y1073326
X0618996Y1114468
X0607776Y1121948
X0611516Y1121948
X0615256Y1121948
X0615256Y1118208
X0607776Y1114468
X0611516Y1114468
X0615256Y1114468
X0615256Y1110728
X0618996Y1095767
X0615256Y1106988
X0607776Y1103247
X0615256Y1103247
X0607776Y1099507
X0615256Y1099507
X0611516Y1095767
X0607776Y1106988
X0611516Y1106988
X0622736Y1088287
X0622736Y1084547
X0622736Y1080807
X0626476Y1073326
X0633957Y1121948
X0633957Y1118208
X0633957Y1114468
X0626476Y1121948
X0626476Y1118208
X0630216Y1118208
X0622736Y1114468
X0626476Y1110728
X0630216Y1110728
X0633957Y1110728
X0630216Y1103247
X0626476Y1099507
X0626476Y1095767
X0622736Y1106988
X0626476Y1106988
X0622736Y1103247
X0622736Y1099507
X0630216Y1099507
X0626476Y1092027
X0626476Y1088287
X0626476Y1077066
X0652657Y1121948
X0652657Y1118208
X0637697Y1110728
X0637697Y1121948
X0641437Y1121948
X0645177Y1121948
X0648917Y1121948
X0637697Y1118208
X0641437Y1118208
X0645177Y1118208
X0648917Y1118208
X0637697Y1114468
X0667618Y1121948
X0667618Y1118208
X0663878Y1121948
X0660138Y1121948
X0660138Y1118208
X0663878Y1118208
X0656398Y1121948
X0656398Y1118208
X0665748Y1078936
X0658268Y1093897
X0665748Y1093897
X0662008Y1101377
X0654527Y1093897
X0650787Y1105117
X0632086Y1097637
X0662008Y1097637
X0648917Y1133169
X0648917Y1129429
X0641437Y1136909
X0622736Y1155610
X0607776Y1133169
X0604035Y1129429
X0600295Y1129429
X0604035Y1136909
X0607776Y1125688
X0600295Y1136909
X0611516Y1125688
X0645177Y1215452
X0641437Y1159350
X0645177Y1166830
X0645177Y1148129
X0645177Y1155610
X0641437Y1151870
X0645177Y1174310
X0641437Y1170570
X0645177Y1181791
X0641437Y1178051
X0660138Y1211712
X0648917Y1215452
X0667618Y1215452
X0641437Y1215452
X0663878Y1215452
X0600294Y1178051
X0604034Y1178051
X0611516Y1178051
X0615256Y1178051
X0656398Y1215452
X0660138Y1215452
X0656398Y1211712
X0600294Y1170570
X0663878Y1211712
X0604034Y1170570
X0652657Y1219192
X0652657Y1215452
X0626476Y1151870
X0626476Y1159350
X0622736Y1148129
X0652657Y1140649
X0600295Y1148129
X0604035Y1148129
X0622736Y1144389
X0626476Y1148129
X0633957Y1159350
X0633957Y1166830
X0633957Y1144389
X0633957Y1148129
X0633957Y1151870
X0641437Y1185531
X0641437Y1144389
X0667618Y1136909
X0656398Y1136909
X0660138Y1136909
X0663878Y1136909
X0667618Y1193011
X0656398Y1193011
X0660138Y1193011
X0663878Y1193011
X0656398Y1151870
X0660138Y1151870
X0663878Y1151870
X0667618Y1151870
X0656398Y1144389
X0660138Y1144389
X0663878Y1144389
X0667618Y1144389
X0656398Y1178051
X0660138Y1178051
X0663878Y1178051
X0667618Y1178051
X0663878Y1185531
X0656398Y1185531
X0660138Y1185531
X0667618Y1185531
X0648917Y1193011
X0633957Y1181791
X0633957Y1178051
X0633957Y1174310
X0648917Y1136909
X0663878Y1129429
X0656398Y1129429
X0660138Y1129429
X0667618Y1129429
X0660138Y1200491
X0663878Y1200491
X0656398Y1200491
X0667618Y1200491
X0652657Y1174310
X0652657Y1181791
X0648917Y1178051
X0648917Y1185531
X0652657Y1166830
X0648917Y1170570
X0648917Y1159350
X0648917Y1151869
X0648917Y1144389
X0652657Y1155610
X0652657Y1148129
X0667618Y1155610
X0660138Y1155610
X0660138Y1174310
X0667618Y1174310
X0667618Y1166830
X0656398Y1159350
X0663878Y1159350
X0656398Y1170570
X0660138Y1166830
X0663878Y1170570
X0632086Y1198621
X0624606Y1202362
X0624606Y1209842
X0620866Y1194881
X0628346Y1198621
X0632086Y1213582
X0628346Y1213582
X0632086Y1191141
X0624606Y1217322
X0620866Y1202362
X0624606Y1187401
X0624606Y1194881
X0632086Y1206102
X0602165Y1213582
X0620866Y1217322
X0602165Y1206102
X0620866Y1187401
X0613386Y1209842
X0613386Y1202362
X0620866Y1209842
X0609646Y1202362
X0602165Y1198621
X0605905Y1213582
X0628346Y1206102
X0609646Y1194881
X0602165Y1191141
X0609646Y1187401
X0628346Y1191141
X0605905Y1198621
X0613386Y1194881
X0605905Y1191141
X0605905Y1206102
X0609646Y1209842
X0613386Y1187401
X0609646Y1217322
X0605905Y1221062
X0602165Y1221062
X0648917Y1140649
X0613386Y1217322
X0635827Y1217322
X0635827Y1213582
X0635827Y1209842
X0635827Y1206102
X0635827Y1202362
X0635827Y1198621
X0635827Y1194881
X0635827Y1191141
X0635827Y1187401
X0624606Y1183661
X0598424Y1191142
X0598424Y1198622
X0598424Y1206103
X0598424Y1213583
X0598424Y1221063
X0609646Y1198621
X0609646Y1206102
X0602165Y1209842
X0605905Y1209842
X0602165Y1217322
X0605905Y1217322
X0605905Y1194881
X0602165Y1194881
X0605905Y1202362
X0602165Y1202362
X0605905Y1187401
X0602165Y1187401
X0602165Y1183661
X0605905Y1183661
X0665748Y1221062
X0662008Y1221062
X0658268Y1221062
X0654527Y1221062
X0650787Y1221062
X0643307Y1221062
X0647047Y1221062
X0639567Y1221062
X0635827Y1221062
X0613386Y1206102
X0609646Y1183661
X0620866Y1183661
X0613386Y1179921
X0617126Y1183661
X0632086Y1217322
X0632086Y1221062
X0624606Y1221062
X0628346Y1221062
X0628346Y1217322
X0617126Y1217322
X0617126Y1221062
X0620866Y1221062
X0628346Y1209842
X0632086Y1209842
X0624606Y1213582
X0628346Y1194881
X0632086Y1194881
X0624606Y1198621
X0624606Y1206102
X0628346Y1202362
X0632086Y1202362
X0624606Y1191141
X0628346Y1187401
X0632086Y1187401
X0620866Y1213582
X0617126Y1209842
X0617126Y1213582
X0620866Y1191141
X0617126Y1191141
X0620866Y1198621
X0617126Y1198621
X0617126Y1194881
X0617126Y1206102
X0620866Y1206102
X0617126Y1202362
X0617126Y1187401
X0613386Y1213582
X0609646Y1213582
X0609646Y1221062
X0613386Y1221062
X0613386Y1191141
X0609646Y1191141
X0613386Y1198621
X0613386Y1183661
X0597795Y1170570
X0604035Y1159350
X0604036Y1166830
X0600295Y1159350
X0604035Y1151870
X0604035Y1144389
X0600295Y1151870
X0600295Y1144389
X0604035Y1140649
X0604035Y1133169
X0604035Y1125688
X0600295Y1140649
X0600295Y1133169
X0600295Y1125688
X0597795Y1178050
X0604034Y1174310
X0615256Y1174310
X0611516Y1174310
X0607775Y1178051
X0607775Y1174310
X0618996Y1178051
X0618996Y1174310
X0618996Y1159350
X0607775Y1170570
X0611516Y1170570
X0607775Y1166830
X0611516Y1166830
X0615256Y1166830
X0607776Y1159350
X0607776Y1155610
X0611516Y1155610
X0615256Y1155610
X0607776Y1151870
X0607776Y1148129
X0611516Y1151869
X0615256Y1151869
X0607776Y1144389
X0618996Y1155610
X0618996Y1151870
X0618996Y1148129
X0618996Y1144389
X0618996Y1133169
X0618996Y1129429
X0618996Y1125688
X0618996Y1140649
X0607776Y1140649
X0611516Y1140649
X0615256Y1140649
X0607776Y1136909
X0607776Y1129429
X0611516Y1129429
X0615256Y1129429
X0615256Y1125688
X0633957Y1170570
X0630216Y1170570
X0630216Y1166830
X0630216Y1159350
X0622736Y1170570
X0622736Y1166830
X0630216Y1151870
X0630216Y1155610
X0630216Y1148129
X0626476Y1144389
X0630216Y1144389
X0626476Y1136909
X0630216Y1136909
X0622736Y1129429
X0626476Y1129428
X0630216Y1129428
X0622736Y1140649
X0626476Y1140649
X0630216Y1140649
X0633957Y1136909
X0633957Y1133169
X0633957Y1129429
X0633957Y1125688
X0633957Y1140649
X0622736Y1178050
X0630216Y1181791
X0630216Y1178051
X0630216Y1174310
X0628346Y1183661
X0633957Y1185531
X0622736Y1174310
X0645177Y1133169
X0637697Y1129429
X0641437Y1129429
X0645177Y1129429
X0637697Y1125688
X0641437Y1125688
X0645177Y1125688
X0648917Y1125688
X0637697Y1140649
X0652657Y1136909
X0652657Y1125688
X0652657Y1129429
X0652657Y1133169
X0641437Y1140649
X0645177Y1140649
X0637697Y1136909
X0652657Y1207972
X0641437Y1207972
X0645177Y1207972
X0648917Y1207972
X0648917Y1211712
X0645177Y1211712
X0652657Y1196751
X0652657Y1200491
X0641437Y1196751
X0641437Y1193011
X0648917Y1200491
X0648917Y1196751
X0648917Y1204232
X0645177Y1204232
X0641437Y1204232
X0641437Y1200491
X0645177Y1200491
X0645177Y1196751
X0645177Y1193011
X0637697Y1193011
X0652657Y1204232
X0652657Y1193011
X0652657Y1178051
X0652657Y1185531
X0648917Y1174310
X0648917Y1181791
X0652657Y1189271
X0637697Y1181791
X0645177Y1178051
X0637697Y1174310
X0637697Y1178051
X0637697Y1185531
X0645177Y1185531
X0637697Y1189271
X0652657Y1170570
X0652657Y1159350
X0648917Y1166830
X0637697Y1170570
X0637697Y1159350
X0645177Y1159350
X0637697Y1166830
X0645177Y1170570
X0652657Y1144389
X0652657Y1151869
X0648917Y1148129
X0648917Y1155610
X0645177Y1151870
X0637697Y1148129
X0637697Y1144389
X0645177Y1144389
X0637697Y1151870
X0637697Y1155610
X0645177Y1136909
X0637697Y1133169
X0641437Y1133169
X0641437Y1211712
X0641437Y1219192
X0648917Y1219192
X0652657Y1211712
X0667618Y1170570
X0667618Y1159350
X0660138Y1170570
X0656398Y1166830
X0660138Y1159350
X0663878Y1166830
X0663878Y1155610
X0656398Y1155610
X0663878Y1148129
X0656398Y1148129
X0660138Y1148129
X0667618Y1148129
X0667618Y1125688
X0667618Y1140649
X0667618Y1133169
X0656398Y1133169
X0660138Y1133169
X0663878Y1133169
X0663878Y1125688
X0660138Y1125688
X0656398Y1125688
X0663878Y1140649
X0660138Y1140649
X0656398Y1140649
X0667618Y1211712
X0667618Y1207972
X0656398Y1207972
X0660138Y1207972
X0663878Y1207972
X0667618Y1204232
X0667618Y1196751
X0663878Y1204232
X0660138Y1204232
X0656398Y1204232
X0656398Y1196751
X0660138Y1196751
X0663878Y1196751
X0663878Y1174310
X0656398Y1174310
X0667618Y1189271
X0667618Y1181791
X0656398Y1189271
X0660138Y1189271
X0663878Y1189271
X0656398Y1181791
X0660138Y1181791
X0663878Y1181791
X0643307Y1243503
X0643307Y1247243
X0647047Y1250984
X0647047Y1254724
X0650787Y1243503
X0650787Y1247243
X0654527Y1250984
X0654527Y1254724
X0639567Y1254724
X0658268Y1243503
X0628346Y1247243
X0665748Y1243503
X0662008Y1250984
X0628346Y1243503
X0635827Y1247243
X0658268Y1247243
X0632086Y1250984
X0635827Y1243503
X0639567Y1250984
X0632086Y1254724
X0665748Y1247243
X0662008Y1254724
X0654527Y1232283
X0613386Y1224803
X0609646Y1236023
X0635827Y1224803
X0624606Y1236023
X0624606Y1232283
X0650787Y1224803
X0602165Y1239763
X0632086Y1236023
X0632086Y1232283
X0658268Y1228543
X0635827Y1228543
X0665748Y1228543
X0650787Y1228543
X0605905Y1239763
X0643307Y1228543
X0647047Y1232283
X0658268Y1224803
X0643307Y1224803
X0617126Y1232283
X0613386Y1228543
X0628346Y1228543
X0628346Y1224803
X0617126Y1236023
X0662008Y1236023
X0639567Y1232283
X0602165Y1228543
X0609646Y1232283
X0620866Y1224803
X0620866Y1228543
X0665748Y1224803
X0662008Y1232283
X0654527Y1236023
X0605905Y1228543
X0647047Y1236023
X0639567Y1236023
X0602165Y1247243
X0609646Y1250984
X0613386Y1243503
X0617126Y1254724
X0613386Y1247243
X0609646Y1254724
X0624606Y1250984
X0620866Y1247243
X0620866Y1243503
X0617126Y1250984
X0605905Y1247243
X0624606Y1254724
X0609646Y1258465
X0617126Y1258465
X0624606Y1258465
X0632087Y1258465
X0639567Y1258465
X0647047Y1258465
X0654528Y1258465
X0662008Y1258465
X0598424Y1228542
X0598423Y1247242
X0598423Y1239762
X0602165Y1232283
X0602165Y1236023
X0602165Y1224803
X0658268Y1250984
X0658268Y1254724
X0662008Y1247243
X0662008Y1243503
X0665748Y1254724
X0665748Y1250984
X0665748Y1239763
X0658268Y1239763
X0662008Y1239763
X0665748Y1232283
X0665748Y1236023
X0662008Y1224803
X0662008Y1228543
X0658268Y1232283
X0658268Y1236023
X0643307Y1250984
X0643307Y1254724
X0647047Y1247243
X0650787Y1250984
X0650787Y1254724
X0654527Y1247243
X0654527Y1243503
X0643307Y1239763
X0647047Y1239763
X0650787Y1239763
X0654527Y1239763
X0647047Y1243503
X0654527Y1228543
X0654527Y1224803
X0650787Y1232283
X0647047Y1224803
X0647047Y1228543
X0650787Y1236023
X0643307Y1232283
X0643307Y1236023
X0624606Y1247243
X0628346Y1254724
X0635827Y1250984
X0635827Y1254724
X0639567Y1247243
X0624606Y1239763
X0624606Y1243503
X0628346Y1250984
X0628346Y1239763
X0632086Y1239763
X0635827Y1239763
X0639567Y1239763
X0639567Y1243503
X0632086Y1243503
X0632086Y1247243
X0639567Y1228543
X0639567Y1224803
X0635827Y1232283
X0635827Y1236023
X0628346Y1232283
X0613386Y1236023
X0613386Y1232283
X0609646Y1228543
X0609646Y1224803
X0617126Y1224803
X0617126Y1228543
X0620866Y1232283
X0620866Y1236023
X0605905Y1250984
X0605905Y1254724
X0605905Y1243503
X0605905Y1236023
X0605905Y1232283
X0605905Y1224803
X0602165Y1250984
X0628346Y1236023
X0624606Y1228543
X0624606Y1224803
X0632086Y1224803
X0632086Y1228543
X0613386Y1250984
X0613386Y1254724
X0609646Y1247243
X0617126Y1247243
X0620866Y1250984
X0620866Y1254724
X0609646Y1239763
X0609646Y1243503
X0613386Y1239763
X0620866Y1239763
X0617126Y1239763
X0617126Y1243503
X0602165Y1243503
X0636288Y1384297
X0636288Y1372385
X0656408Y1360099
X0656408Y1348187
X0668648Y1360099
X0668648Y1348187
X0660768Y1384297
X0668648Y1384297
X0660768Y1372385
X0668648Y1372385
X0648528Y1384297
X0648528Y1372385
X0660768Y1360099
X0660768Y1348187
X0648528Y1360099
X0648528Y1348187
X0624048Y1408495
X0624048Y1396583
X0636288Y1408495
X0636288Y1396583
X0648528Y1408495
X0648528Y1396583
X0660768Y1408495
X0660768Y1396583
X0631928Y1396583
X0631928Y1408495
X0656408Y1372385
X0644168Y1372385
X0644168Y1384297
X0644168Y1396583
X0644168Y1408495
X0656408Y1384297
X0656408Y1396583
X0656408Y1408495
X0668648Y1396583
X0668648Y1408495
X0754328Y1360099
X0754328Y1348187
X0742088Y1360099
X0742088Y1348187
X0721968Y1360099
X0729848Y1360099
X0721968Y1348187
X0729848Y1348187
X0709728Y1360099
X0717608Y1360099
X0709728Y1348187
X0717608Y1348187
X0697488Y1360099
X0697488Y1348187
X0685248Y1360099
X0685248Y1348187
X0766568Y1384297
X0758688Y1384297
X0766568Y1372385
X0758688Y1372385
X0746448Y1384297
X0754328Y1384297
X0746448Y1372385
X0754328Y1372385
X0734208Y1384297
X0734208Y1372385
X0717608Y1384297
X0717608Y1372385
X0705368Y1384297
X0693128Y1384297
X0705368Y1372385
X0693128Y1372385
X0680888Y1384297
X0680888Y1372385
X0673008Y1384297
X0673008Y1372385
X0758688Y1360099
X0758688Y1348187
X0734208Y1408401
X0734208Y1396489
X0746448Y1360099
X0746448Y1348187
X0734208Y1360099
X0734208Y1348187
X0721968Y1408401
X0721968Y1396489
X0685248Y1384297
X0685248Y1372385
X0673008Y1360099
X0673008Y1348187
X0697488Y1372385
X0673008Y1396583
X0709728Y1372385
X0685248Y1396583
X0721968Y1372385
X0697488Y1396583
X0709728Y1396583
X0697488Y1384297
X0673008Y1408495
X0709728Y1384297
X0685248Y1408495
X0721968Y1384297
X0697488Y1408495
X0709728Y1408495
X0680888Y1360099
X0693128Y1360099
X0680888Y1348187
X0693128Y1348187
X0705368Y1360099
X0705368Y1348187
X0729848Y1408401
X0729848Y1396489
X0680888Y1396583
X0680888Y1408495
X0742088Y1372385
X0693128Y1396583
X0693128Y1408495
X0729848Y1384297
X0729848Y1372385
X0742088Y1384297
X0705368Y1396583
X0705368Y1408495
X0742088Y1408401
X0742088Y1396489
X0766568Y1360099
X0766568Y1348187
X0717608Y1396583
X0717608Y1408495
X0755512Y1247243
X0748031Y1243503
X0759252Y1250984
X0766732Y1254724
X0748031Y1247243
X0759252Y1254724
X0751772Y1254724
X0751772Y1250984
X0762992Y1247243
X0762992Y1243503
X0755512Y1243503
X0766732Y1250984
X0755512Y1224803
X0759252Y1236023
X0762992Y1224803
X0748031Y1228543
X0759252Y1232283
X0766732Y1236023
X0766732Y1232283
X0751772Y1232283
X0762992Y1228543
X0751772Y1236023
X0755512Y1228543
X0748031Y1224803
X0680709Y1243503
X0669488Y1254724
X0676968Y1250984
X0676968Y1254724
X0684449Y1250984
X0684449Y1254724
X0673228Y1247243
X0669488Y1250984
X0680709Y1247243
X0673228Y1243503
X0729331Y1232283
X0706890Y1232283
X0729331Y1236023
X0710630Y1224803
X0718110Y1224803
X0740551Y1228543
X0740551Y1224803
X0736811Y1236023
X0695669Y1224803
X0744291Y1232283
X0725590Y1224803
X0703149Y1224803
X0714370Y1232283
X0721850Y1232283
X0695669Y1228543
X0691929Y1232283
X0699409Y1236023
X0733071Y1224803
X0721850Y1236023
X0680709Y1228543
X0669488Y1236023
X0688189Y1224803
X0673228Y1224803
X0676968Y1232283
X0684449Y1236023
X0680709Y1224803
X0673228Y1228543
X0695669Y1243503
X0699409Y1250984
X0695669Y1247243
X0703149Y1247243
X0710630Y1243503
X0684449Y1232283
X0706890Y1254724
X0691929Y1254724
X0710630Y1247243
X0714370Y1250984
X0714370Y1254724
X0676968Y1236023
X0703149Y1243503
X0688189Y1243503
X0688189Y1247243
X0691929Y1250984
X0669488Y1232283
X0706890Y1250984
X0699409Y1254724
X0736811Y1250984
X0736811Y1254724
X0744291Y1250984
X0725590Y1247243
X0733071Y1243503
X0729331Y1254724
X0725590Y1243503
X0740551Y1247243
X0740551Y1243503
X0721850Y1254724
X0718110Y1247243
X0721850Y1250984
X0718110Y1243503
X0744291Y1254724
X0733071Y1247243
X0729331Y1250984
X0744291Y1224803
X0669488Y1258465
X0676969Y1258465
X0684450Y1258465
X0691929Y1258465
X0699409Y1258465
X0706890Y1258465
X0714370Y1258465
X0721850Y1258465
X0729331Y1258465
X0736811Y1258465
X0744291Y1258465
X0751772Y1258465
X0759252Y1258465
X0766732Y1258465
X0740551Y1250984
X0740551Y1254724
X0744291Y1247243
X0748031Y1250984
X0748031Y1254724
X0740551Y1239763
X0744291Y1239763
X0744291Y1243503
X0748031Y1239763
X0740551Y1232283
X0744291Y1228543
X0740551Y1236023
X0748031Y1232283
X0748031Y1236023
X0721850Y1247243
X0725590Y1250984
X0725590Y1254724
X0733071Y1254724
X0733071Y1250984
X0729331Y1247243
X0736811Y1247243
X0721850Y1239763
X0729331Y1239763
X0725590Y1239763
X0721850Y1243503
X0729331Y1243503
X0733071Y1239763
X0736811Y1239763
X0736811Y1243503
X0721850Y1228543
X0721850Y1224803
X0725590Y1232283
X0725590Y1236023
X0733071Y1232283
X0733071Y1236023
X0729331Y1228543
X0729331Y1224803
X0736811Y1228543
X0736811Y1224803
X0718110Y1254724
X0706890Y1239763
X0706890Y1243503
X0706890Y1247243
X0710630Y1239763
X0710630Y1250984
X0710630Y1254724
X0714370Y1247243
X0714370Y1243503
X0718110Y1239763
X0718110Y1250984
X0714370Y1239763
X0706890Y1228543
X0706890Y1224803
X0714370Y1228543
X0714370Y1224803
X0710630Y1232283
X0718110Y1232283
X0718110Y1236023
X0710630Y1236023
X0695669Y1254724
X0695669Y1250984
X0691929Y1247243
X0691929Y1243503
X0691929Y1239763
X0695669Y1239763
X0703149Y1239763
X0699409Y1239763
X0699409Y1243503
X0699409Y1247243
X0703149Y1250984
X0703149Y1254724
X0695669Y1232283
X0695669Y1236023
X0699409Y1228543
X0699409Y1224803
X0703149Y1232283
X0703149Y1236023
X0691929Y1228543
X0691929Y1224803
X0688189Y1239763
X0684449Y1239763
X0684449Y1243503
X0684449Y1247243
X0688189Y1250984
X0688189Y1254724
X0673228Y1250984
X0673228Y1254724
X0676968Y1247243
X0676968Y1243503
X0680709Y1250984
X0680709Y1254724
X0680709Y1239763
X0676968Y1239763
X0673228Y1239763
X0688189Y1232283
X0688189Y1236023
X0684449Y1228543
X0684449Y1224803
X0680709Y1232283
X0680709Y1236023
X0676968Y1228543
X0676968Y1224803
X0673228Y1232283
X0673228Y1236023
X0669488Y1243503
X0669488Y1247243
X0669488Y1239763
X0669488Y1224803
X0669488Y1228543
X0751772Y1228543
X0751772Y1224803
X0751772Y1239763
X0751772Y1243503
X0751772Y1247243
X0762992Y1236023
X0762992Y1232283
X0766732Y1228543
X0766732Y1224803
X0755512Y1236023
X0755512Y1232283
X0759252Y1228543
X0759252Y1224803
X0766732Y1239763
X0762992Y1239763
X0759252Y1239763
X0755512Y1239763
X0766732Y1243503
X0766732Y1247243
X0762992Y1254724
X0762992Y1250984
X0759252Y1243503
X0759252Y1247243
X0755512Y1254724
X0755512Y1250984
X0736811Y1232283
X0733071Y1228543
X0703149Y1228543
X0744291Y1236023
X0699409Y1232283
X0710630Y1228543
X0691929Y1236023
X0714370Y1236023
X0725590Y1228543
X0718110Y1228543
X0688189Y1228543
X0706890Y1236023
X0727461Y1215452
X0738681Y1211712
X0742421Y1200491
X0738681Y1207972
X0734941Y1207972
X0734941Y1200491
X0734941Y1204232
X0734941Y1196751
X0731201Y1178051
X0761122Y1174310
X0749902Y1148129
X0749902Y1155610
X0764862Y1181791
X0761122Y1181791
X0764862Y1144389
X0764862Y1151869
X0753642Y1155610
X0761122Y1151869
X0753642Y1170570
X0749902Y1140649
X0764862Y1174310
X0749902Y1170570
X0761122Y1144389
X0768602Y1148129
X0768602Y1178051
X0768602Y1140649
X0768602Y1155610
X0768602Y1170570
X0768602Y1193011
X0768602Y1185531
X0738681Y1215452
X0708760Y1211711
X0705019Y1211711
X0742421Y1207972
X0742421Y1215452
X0731201Y1211712
X0742421Y1211712
X0695669Y1217322
X0742421Y1204232
X0738681Y1200491
X0675098Y1215452
X0705019Y1215451
X0671358Y1215452
X0701279Y1215452
X0746161Y1140649
X0742421Y1144389
X0742421Y1148129
X0738681Y1144389
X0742421Y1178051
X0746161Y1181791
X0693799Y1211712
X0671358Y1211712
X0693799Y1215452
X0697539Y1215452
X0719980Y1215452
X0699409Y1217322
X0712500Y1215452
X0755512Y1206102
X0759252Y1209842
X0751772Y1198621
X0759252Y1217322
X0759252Y1202362
X0751772Y1206102
X0755512Y1198621
X0755512Y1213582
X0762992Y1209842
X0751772Y1213582
X0762992Y1217322
X0762992Y1202362
X0742421Y1196751
X0742421Y1136909
X0746161Y1148129
X0742421Y1140649
X0708760Y1215452
X0723720Y1215452
X0716240Y1215452
X0678839Y1215452
X0678839Y1211712
X0682579Y1211712
X0686319Y1215452
X0686319Y1211712
X0734941Y1215452
X0731201Y1215452
X0731201Y1144389
X0731201Y1140649
X0731201Y1136909
X0731201Y1193011
X0731201Y1185531
X0731201Y1189271
X0686319Y1136909
X0671358Y1136909
X0675098Y1136909
X0678838Y1136909
X0682579Y1136909
X0686319Y1193011
X0671358Y1193011
X0675098Y1193011
X0678838Y1193011
X0682579Y1193011
X0693799Y1193011
X0697539Y1193011
X0701279Y1193011
X0701279Y1136909
X0693799Y1136909
X0697539Y1136909
X0716240Y1193011
X0705020Y1193011
X0712500Y1193011
X0708760Y1193011
X0712500Y1136909
X0708760Y1136909
X0705020Y1136909
X0716240Y1136909
X0734941Y1170570
X0734941Y1166830
X0734941Y1159350
X0734941Y1155610
X0723720Y1136909
X0719980Y1136909
X0723720Y1193011
X0719980Y1193011
X0734941Y1174310
X0761122Y1159350
X0761122Y1166830
X0764862Y1166830
X0686319Y1151870
X0686319Y1144389
X0675098Y1144389
X0678838Y1144389
X0671358Y1144389
X0682579Y1144389
X0671358Y1178051
X0675098Y1178051
X0678838Y1178051
X0682579Y1178051
X0686319Y1178051
X0678838Y1185531
X0671358Y1185531
X0675098Y1185531
X0682579Y1185531
X0686319Y1185531
X0682579Y1151870
X0671358Y1151870
X0675098Y1151870
X0678839Y1151870
X0693799Y1178051
X0697539Y1178051
X0701279Y1178051
X0693799Y1185531
X0697539Y1185531
X0701279Y1185531
X0693799Y1144389
X0697539Y1144389
X0701279Y1144389
X0693799Y1151869
X0697539Y1151869
X0701279Y1151869
X0708760Y1178051
X0705020Y1178051
X0712500Y1178051
X0716240Y1178051
X0705020Y1185531
X0712500Y1185531
X0708760Y1185531
X0716240Y1185531
X0716240Y1144389
X0708760Y1144389
X0705020Y1144389
X0712500Y1144389
X0705020Y1151869
X0712500Y1151869
X0708760Y1151869
X0716240Y1151869
X0723720Y1170570
X0727460Y1170570
X0719980Y1170570
X0727460Y1166830
X0723720Y1166830
X0723720Y1159350
X0727460Y1159350
X0719980Y1159350
X0719980Y1144389
X0723720Y1144389
X0723720Y1151869
X0719980Y1151869
X0723720Y1185531
X0723720Y1178051
X0719980Y1178051
X0719980Y1185531
X0731201Y1200491
X0738681Y1181791
X0727460Y1181791
X0731201Y1129429
X0682579Y1129429
X0678838Y1129429
X0671358Y1129429
X0675098Y1129429
X0686319Y1129429
X0682579Y1200491
X0678838Y1200491
X0671358Y1200491
X0675098Y1200491
X0686319Y1200491
X0693799Y1200491
X0697539Y1200491
X0701279Y1200491
X0693799Y1129429
X0697539Y1129429
X0701279Y1129429
X0716240Y1200491
X0708760Y1200491
X0705020Y1200491
X0712500Y1200491
X0716240Y1129429
X0712500Y1129429
X0708760Y1129429
X0705020Y1129429
X0723720Y1129429
X0719980Y1129429
X0723720Y1200491
X0719980Y1200491
X0742421Y1174310
X0742421Y1170570
X0742421Y1166830
X0742421Y1159350
X0742421Y1155610
X0746161Y1189271
X0675098Y1155610
X0682579Y1155610
X0675098Y1174310
X0682579Y1174310
X0686319Y1159350
X0686319Y1170570
X0678838Y1159350
X0671358Y1159350
X0675098Y1166830
X0671358Y1170570
X0678838Y1170570
X0682579Y1166830
X0693799Y1174310
X0701279Y1174310
X0701279Y1166830
X0697539Y1159350
X0697539Y1170570
X0693799Y1166830
X0693799Y1155610
X0701279Y1155610
X0708760Y1174310
X0716240Y1174310
X0708760Y1166830
X0712500Y1170570
X0705020Y1170570
X0712500Y1159350
X0705020Y1159350
X0716240Y1166830
X0716240Y1155610
X0708760Y1155610
X0723720Y1174310
X0723720Y1155610
X0742421Y1189271
X0759252Y1127559
X0759252Y1135039
X0762992Y1127559
X0755512Y1131299
X0751771Y1123818
X0755512Y1123818
X0762992Y1135039
X0751771Y1131299
X0748031Y1123818
X0748031Y1127558
X0748031Y1131299
X0748031Y1135039
X0748031Y1138779
X0764862Y1189271
X0688189Y1221062
X0684449Y1221062
X0680709Y1221062
X0676968Y1221062
X0673228Y1221062
X0669488Y1221062
X0691929Y1221062
X0751772Y1135039
X0751772Y1127558
X0759252Y1123818
X0748031Y1198621
X0748031Y1202362
X0748031Y1206102
X0748031Y1209842
X0748031Y1213582
X0748031Y1217322
X0744291Y1221062
X0748031Y1221062
X0740551Y1221062
X0729331Y1221062
X0725590Y1221062
X0721850Y1221062
X0718110Y1221062
X0714370Y1221062
X0710630Y1221062
X0706890Y1221062
X0703149Y1221062
X0736811Y1221062
X0733071Y1221062
X0699409Y1221062
X0695669Y1221062
X0755512Y1135039
X0759252Y1131299
X0755512Y1127558
X0751772Y1202362
X0751772Y1209842
X0751772Y1217322
X0751772Y1221062
X0759252Y1198621
X0762992Y1198621
X0766732Y1198621
X0766732Y1202362
X0755512Y1202362
X0759252Y1206102
X0762992Y1206102
X0766732Y1206102
X0755512Y1209842
X0766732Y1209842
X0766732Y1213582
X0762992Y1213582
X0759252Y1213582
X0755512Y1217322
X0755512Y1221062
X0759252Y1221062
X0762992Y1221062
X0766732Y1217322
X0766732Y1221062
X0766732Y1127558
X0766732Y1135039
X0762992Y1123818
X0766732Y1123818
X0766732Y1131299
X0762992Y1131299
X0678838Y1155610
X0671358Y1155610
X0686319Y1155610
X0671358Y1148129
X0675098Y1148129
X0678838Y1148129
X0682579Y1148129
X0686319Y1148129
X0686319Y1125688
X0686319Y1140649
X0671358Y1133169
X0675098Y1133169
X0678838Y1133169
X0678838Y1125688
X0671358Y1125688
X0675098Y1125688
X0678838Y1140649
X0675098Y1140649
X0671358Y1140649
X0682579Y1125688
X0682579Y1140649
X0682579Y1133169
X0686319Y1207972
X0671358Y1207972
X0675098Y1207972
X0678838Y1207972
X0678838Y1219192
X0675098Y1211712
X0682579Y1207972
X0686319Y1204232
X0686319Y1196751
X0675098Y1204232
X0671358Y1204232
X0671358Y1196751
X0675098Y1196751
X0678838Y1196751
X0678838Y1204232
X0682579Y1204232
X0682579Y1196751
X0686319Y1174310
X0678838Y1174310
X0671358Y1174310
X0678838Y1181791
X0682579Y1189271
X0682579Y1181791
X0686319Y1189271
X0686319Y1181791
X0671358Y1189271
X0675098Y1189271
X0678838Y1189271
X0671358Y1181791
X0675098Y1181791
X0686319Y1166830
X0675098Y1159350
X0671358Y1166830
X0678839Y1166830
X0675098Y1170570
X0682579Y1159350
X0682579Y1170570
X0701279Y1211712
X0701279Y1207972
X0697539Y1211712
X0697539Y1207972
X0693799Y1207972
X0701279Y1204232
X0701279Y1196751
X0697539Y1196751
X0693799Y1196751
X0693799Y1204232
X0697539Y1204232
X0697539Y1174310
X0697539Y1181791
X0701279Y1181791
X0701279Y1189271
X0697539Y1189271
X0693799Y1189271
X0693799Y1181791
X0701279Y1170570
X0701279Y1159350
X0693799Y1159350
X0693799Y1170570
X0697539Y1166830
X0697539Y1155610
X0693799Y1148129
X0701279Y1148129
X0697539Y1148129
X0701279Y1133169
X0701279Y1140649
X0701279Y1125688
X0697539Y1125688
X0693799Y1125688
X0697539Y1140649
X0693799Y1140649
X0686417Y1132677
X0697539Y1133169
X0693799Y1133464
X0705020Y1207972
X0708760Y1207972
X0712500Y1211712
X0712500Y1207972
X0716240Y1207972
X0716240Y1211712
X0705020Y1204232
X0712500Y1204232
X0708760Y1204232
X0705020Y1196751
X0708760Y1196751
X0712500Y1196751
X0716240Y1204232
X0716240Y1196751
X0712500Y1174310
X0705020Y1174310
X0705020Y1181791
X0708760Y1181791
X0712500Y1181791
X0705020Y1189271
X0708760Y1189271
X0712500Y1189271
X0716240Y1181791
X0716240Y1189271
X0708760Y1170570
X0712500Y1166830
X0705020Y1166830
X0708760Y1159350
X0716240Y1159350
X0716240Y1170570
X0705020Y1155610
X0712500Y1155610
X0705020Y1148129
X0708760Y1148129
X0712500Y1148129
X0716240Y1148129
X0705020Y1133169
X0708760Y1133169
X0712500Y1133169
X0705020Y1140649
X0708760Y1140649
X0712500Y1140649
X0705020Y1125688
X0708760Y1125688
X0712500Y1125688
X0716240Y1133169
X0716240Y1125688
X0716240Y1140649
X0727460Y1174310
X0731201Y1181791
X0731201Y1174310
X0719980Y1189271
X0723720Y1189271
X0727460Y1178051
X0719980Y1174310
X0719980Y1181791
X0723720Y1181791
X0727460Y1189271
X0734941Y1178051
X0734941Y1189271
X0734941Y1185531
X0734941Y1181791
X0727460Y1185531
X0731201Y1166830
X0731201Y1159350
X0719980Y1166830
X0731201Y1170570
X0727460Y1155610
X0719980Y1155610
X0734941Y1144389
X0734941Y1148129
X0734941Y1151870
X0731201Y1155610
X0731201Y1151869
X0731201Y1148129
X0719980Y1148129
X0723720Y1148129
X0727460Y1144389
X0727460Y1148129
X0727460Y1151869
X0731201Y1125688
X0727460Y1136909
X0719980Y1133169
X0723720Y1133169
X0727460Y1133169
X0719980Y1140649
X0723720Y1140649
X0727460Y1125688
X0727460Y1129429
X0719980Y1125688
X0723720Y1125688
X0727460Y1140649
X0734941Y1136909
X0734941Y1133169
X0734941Y1140649
X0734941Y1125688
X0734941Y1129429
X0731201Y1207972
X0727460Y1211712
X0719980Y1207972
X0719980Y1211712
X0723720Y1207972
X0723720Y1211712
X0727460Y1207972
X0734941Y1211712
X0723720Y1204232
X0727460Y1200491
X0719980Y1196751
X0723720Y1196751
X0727460Y1193011
X0734941Y1193011
X0731201Y1204232
X0731201Y1196751
X0727480Y1196732
X0727460Y1204232
X0719980Y1204232
X0738681Y1151869
X0742421Y1151869
X0746161Y1151869
X0746161Y1155610
X0746161Y1144389
X0738681Y1140649
X0738681Y1136909
X0742421Y1193011
X0738681Y1196751
X0738681Y1193011
X0748031Y1194881
X0751772Y1194881
X0738681Y1204232
X0742421Y1185531
X0746161Y1174310
X0746161Y1178051
X0746161Y1185531
X0738681Y1189271
X0738681Y1185531
X0742421Y1181791
X0738681Y1178051
X0738681Y1174310
X0749901Y1174310
X0748031Y1191141
X0749901Y1181791
X0746161Y1159350
X0738681Y1170570
X0749901Y1159350
X0749901Y1166830
X0738681Y1159350
X0746161Y1166830
X0746161Y1170570
X0738681Y1166830
X0749901Y1151869
X0749901Y1144389
X0738681Y1148129
X0738681Y1155610
X0753642Y1159350
X0757382Y1159350
X0753642Y1166830
X0761122Y1170570
X0757382Y1170570
X0757382Y1166830
X0764862Y1170570
X0764862Y1159350
X0753642Y1151869
X0761122Y1155610
X0761122Y1148129
X0757382Y1155610
X0757382Y1151869
X0757382Y1148129
X0757382Y1144389
X0753642Y1144389
X0764862Y1148129
X0764862Y1155610
X0764862Y1140649
X0761122Y1140649
X0757382Y1140649
X0755512Y1194881
X0762992Y1191141
X0759252Y1191141
X0753642Y1189271
X0761122Y1185531
X0761122Y1178051
X0755512Y1187401
X0764862Y1178051
X0764862Y1185531
X0757382Y1185531
X0757382Y1181791
X0757382Y1178051
X0757382Y1174310
X0753642Y1174310
X0753642Y1181791
X0768602Y1174310
X0768602Y1181791
X0768602Y1166830
X0768602Y1159350
X0768602Y1144389
X0768602Y1151869
X0766732Y1194881
X0708760Y1118208
X0712500Y1118208
X0701279Y1118208
X0719980Y1114468
X0719980Y1118208
X0697539Y1114468
X0697539Y1118208
X0705020Y1118208
X0716240Y1114468
X0727460Y1114468
X0712500Y1114468
X0705020Y1114468
X0701279Y1114468
X0693799Y1118208
X0742421Y1114468
X0716240Y1118208
X0693799Y1114468
X0708760Y1114468
X0734941Y1114468
X0731201Y1114468
X0738681Y1114468
X0675098Y1114468
X0678839Y1114468
X0682579Y1114468
X0742421Y1118208
X0738681Y1118208
X0751771Y1078936
X0762991Y1082677
X0755511Y1082676
X0759251Y1078936
X0755511Y1086416
X0766731Y1078936
X0759251Y1075196
X0766731Y1075196
X0762991Y1086417
X0751771Y1075196
X0748030Y1082677
X0725589Y1082676
X0729330Y1075196
X0744290Y1075196
X0714369Y1075196
X0721849Y1075196
X0710629Y1082676
X0733069Y1082677
X0736810Y1078936
X0718109Y1082677
X0695668Y1082676
X0729330Y1078936
X0703148Y1086417
X0691928Y1075195
X0740550Y1082676
X0710629Y1086416
X0721849Y1078936
X0703148Y1082677
X0740550Y1086416
X0748030Y1086417
X0714369Y1078936
X0718109Y1086417
X0733069Y1086417
X0706889Y1078936
X0699408Y1075196
X0736810Y1075196
X0725589Y1086416
X0695668Y1086416
X0699408Y1078936
X0706889Y1075196
X0744290Y1078936
X0691928Y1078935
X0669488Y1075196
X0669488Y1078936
X0680709Y1082677
X0673228Y1082677
X0673228Y1086417
X0684449Y1078936
X0680709Y1086417
X0684449Y1075196
X0688189Y1082677
X0688189Y1086417
X0676968Y1075196
X0676968Y1078936
X0680708Y1101376
X0673228Y1101376
X0680708Y1105117
X0676968Y1097637
X0684449Y1097637
X0669488Y1097637
X0688189Y1101376
X0751771Y1093897
X0710630Y1101376
X0699408Y1093897
X0748031Y1101376
X0766731Y1093897
X0755512Y1101376
X0703149Y1101376
X0766731Y1097637
X0740551Y1101376
X0736810Y1093897
X0729330Y1093897
X0762992Y1120078
X0733071Y1101376
X0759252Y1120078
X0744290Y1097637
X0729330Y1097637
X0721849Y1093897
X0751771Y1116338
X0755512Y1116338
X0691928Y1097637
X0721849Y1097637
X0762992Y1112598
X0706889Y1097637
X0740551Y1105117
X0759251Y1093897
X0691928Y1093897
X0725590Y1105117
X0714369Y1093897
X0759251Y1097637
X0755512Y1105117
X0695669Y1105117
X0762992Y1105117
X0762992Y1101376
X0744290Y1093897
X0748031Y1105117
X0710630Y1105117
X0751771Y1097637
X0759252Y1112598
X0718110Y1101376
X0699408Y1097637
X0718110Y1105117
X0736810Y1097637
X0695669Y1101376
X0733071Y1105117
X0703149Y1105117
X0725590Y1101376
X0706889Y1093897
X0714369Y1097637
X0669488Y1108858
X0673228Y1108858
X0676968Y1108858
X0680709Y1108858
X0684449Y1108858
X0688189Y1108858
X0691929Y1108858
X0695669Y1108858
X0699409Y1108858
X0703149Y1108858
X0706890Y1108858
X0710630Y1108858
X0714370Y1108858
X0718110Y1108858
X0721850Y1108858
X0725590Y1108858
X0729331Y1108858
X0733071Y1108858
X0736811Y1108858
X0740551Y1108858
X0744291Y1108858
X0748031Y1108858
X0748031Y1112598
X0748031Y1116338
X0748031Y1120078
X0669487Y1071455
X0676967Y1071455
X0684448Y1071455
X0691928Y1071454
X0699408Y1071455
X0706889Y1071455
X0714369Y1071455
X0721849Y1071455
X0729330Y1071455
X0736810Y1071455
X0744290Y1071455
X0751771Y1071455
X0759252Y1071455
X0766732Y1071455
X0751771Y1120078
X0751771Y1112598
X0755512Y1120078
X0759252Y1116338
X0751772Y1108858
X0759252Y1108858
X0755512Y1108858
X0748031Y1075196
X0669488Y1105117
X0669488Y1101377
X0673228Y1093897
X0673228Y1097637
X0721850Y1086417
X0725590Y1078936
X0721850Y1090157
X0725590Y1090157
X0729331Y1090157
X0733071Y1078936
X0733071Y1090157
X0736811Y1082677
X0736811Y1090157
X0733071Y1075196
X0710630Y1075196
X0718110Y1075196
X0691929Y1105117
X0695669Y1097637
X0703149Y1075196
X0676968Y1086417
X0695669Y1075196
X0703149Y1090157
X0699409Y1082677
X0703149Y1078936
X0695669Y1078936
X0691929Y1090157
X0699409Y1086417
X0699409Y1090157
X0695669Y1090157
X0691929Y1086417
X0691929Y1082677
X0703149Y1097637
X0703149Y1093897
X0676968Y1082677
X0699409Y1101377
X0680709Y1078936
X0673228Y1078936
X0673228Y1090157
X0718110Y1090157
X0710630Y1090157
X0714370Y1090157
X0714370Y1086417
X0714370Y1082677
X0718110Y1078936
X0706890Y1090157
X0706890Y1086417
X0706890Y1082677
X0710630Y1078936
X0718110Y1093897
X0718110Y1097637
X0710630Y1093897
X0710630Y1097637
X0714370Y1101377
X0714370Y1105117
X0706890Y1105117
X0706890Y1101377
X0725590Y1075196
X0736811Y1086417
X0729331Y1082677
X0729331Y1086417
X0721850Y1082677
X0736811Y1101377
X0733071Y1097637
X0736811Y1105117
X0733071Y1093897
X0729331Y1105117
X0740551Y1075196
X0680709Y1097637
X0676968Y1101377
X0755512Y1093897
X0755513Y1078936
X0766731Y1082677
X0766732Y1101377
X0759252Y1101377
X0673228Y1075196
X0688189Y1075196
X0684449Y1086417
X0755512Y1097637
X0684449Y1082677
X0725590Y1093897
X0766732Y1105117
X0762993Y1078936
X0688189Y1090157
X0684449Y1090157
X0759252Y1105117
X0762992Y1093897
X0688189Y1078936
X0762992Y1097637
X0680709Y1093897
X0680709Y1075196
X0766732Y1112598
X0766732Y1116338
X0766731Y1108858
X0762991Y1108857
X0691929Y1101377
X0721850Y1105117
X0766732Y1086417
X0766732Y1120078
X0762992Y1116338
X0721850Y1101377
X0699409Y1105117
X0725590Y1097637
X0755511Y1090157
X0676968Y1090157
X0729331Y1101377
X0759252Y1086417
X0688189Y1093897
X0684449Y1105117
X0684449Y1101377
X0676968Y1105117
X0680709Y1090157
X0762991Y1090157
X0759251Y1090157
X0762993Y1075196
X0755512Y1075196
X0744291Y1105117
X0686319Y1114468
X0686319Y1118208
X0686319Y1121948
X0671358Y1121948
X0678838Y1121948
X0675098Y1121948
X0678838Y1118208
X0675098Y1118208
X0671358Y1118208
X0671358Y1114468
X0682579Y1121948
X0682579Y1118208
X0751772Y1105117
X0740551Y1093897
X0701279Y1121948
X0697539Y1121948
X0693799Y1121948
X0748031Y1097637
X0748031Y1093897
X0712500Y1121948
X0708760Y1121948
X0705020Y1121948
X0716240Y1121948
X0751771Y1101377
X0731201Y1118208
X0731201Y1121948
X0727460Y1118208
X0723720Y1121948
X0719980Y1121948
X0727460Y1121948
X0734941Y1118208
X0734941Y1121948
X0740551Y1090157
X0740551Y1078936
X0744291Y1086417
X0744291Y1090157
X0751771Y1082677
X0748031Y1078936
X0744291Y1082677
X0751771Y1090157
X0748030Y1090157
X0751772Y1086417
X0669488Y1082677
X0669488Y1086417
X0669488Y1090157
X0695669Y1093897
X0766731Y1090157
X0759251Y1082677
X0688189Y1097637
X0740551Y1097637
X0744291Y1101377
X0676968Y1093897
X0669488Y1093897
X0684449Y1093897
X0688189Y1105117
X0673228Y1105117
X0777953Y1082676
X0774212Y1120078
X0777953Y1116338
X0770471Y1082677
X0774211Y1075196
X0770471Y1086417
X0781693Y1108858
X0770472Y1120078
X0777953Y1108858
X0774211Y1078936
X0781693Y1116338
X0770472Y1112598
X0781693Y1082676
X0774212Y1112598
X0777953Y1090157
X0781693Y1090157
X0774212Y1093897
X0770472Y1105117
X0774212Y1097637
X0777953Y1101377
X0781693Y1101377
X0770472Y1101377
X0774212Y1071455
X0785434Y1082677
X0785434Y1090158
X0785434Y1101378
X0785434Y1108859
X0785434Y1116339
X0777953Y1112598
X0774212Y1116338
X0770472Y1116338
X0774212Y1108858
X0770472Y1108858
X0781693Y1120078
X0777953Y1120078
X0781693Y1112598
X0777953Y1086417
X0781693Y1086417
X0770471Y1090157
X0770473Y1075196
X0774212Y1082677
X0774213Y1086417
X0770473Y1078936
X0781693Y1078936
X0777953Y1078936
X0781693Y1105117
X0774212Y1090157
X0777953Y1097637
X0781693Y1097637
X0781693Y1093897
X0770472Y1093897
X0777953Y1075196
X0774213Y1105117
X0777953Y1105117
X0774212Y1101377
X0777953Y1093897
X0770472Y1097637
X0779823Y1181791
X0783563Y1159350
X0783563Y1181791
X0772342Y1140649
X0783563Y1144389
X0772342Y1170570
X0779823Y1174310
X0779823Y1144389
X0779823Y1151870
X0783563Y1151870
X0772342Y1193011
X0772342Y1155610
X0783563Y1174310
X0772342Y1148129
X0772342Y1185531
X0779823Y1189271
X0779823Y1159350
X0772342Y1178051
X0783563Y1189271
X0777953Y1198621
X0770472Y1202362
X0777953Y1213582
X0774212Y1217322
X0774212Y1202362
X0770472Y1217322
X0781693Y1206102
X0781693Y1221062
X0777953Y1221062
X0774212Y1209842
X0781693Y1213582
X0770472Y1209842
X0781693Y1198621
X0777953Y1206102
X0777953Y1131299
X0774212Y1135039
X0777953Y1123818
X0774212Y1127558
X0781693Y1123818
X0781693Y1131299
X0770472Y1135039
X0770472Y1127558
X0785434Y1198621
X0785434Y1206102
X0785434Y1213582
X0785434Y1221062
X0785434Y1123819
X0785434Y1131300
X0772342Y1189271
X0770472Y1138779
X0781693Y1135039
X0777953Y1135039
X0770471Y1131299
X0774212Y1131299
X0777953Y1127558
X0781693Y1127558
X0770472Y1198621
X0774212Y1198621
X0770472Y1206102
X0774212Y1206102
X0777953Y1202362
X0781693Y1202362
X0770472Y1213582
X0774212Y1213582
X0777953Y1209842
X0781693Y1209842
X0770472Y1221062
X0774212Y1221062
X0777953Y1217322
X0781693Y1217322
X0774212Y1123818
X0770472Y1123818
X0779823Y1140649
X0776083Y1140649
X0783563Y1178051
X0783563Y1185531
X0779823Y1178051
X0779823Y1185531
X0772342Y1181791
X0776083Y1185531
X0776083Y1181791
X0776083Y1178051
X0772342Y1174310
X0776083Y1174310
X0779823Y1170570
X0779823Y1166830
X0772342Y1159350
X0776083Y1159350
X0772342Y1166830
X0776083Y1170570
X0776083Y1166830
X0783563Y1166830
X0783563Y1170570
X0779823Y1148129
X0779823Y1155610
X0776083Y1144389
X0772342Y1144389
X0776083Y1155610
X0772342Y1151869
X0776083Y1151869
X0776083Y1148129
X0783563Y1148129
X0783563Y1155610
X0783563Y1140649
X0779823Y1193011
X0776083Y1193011
X0772342Y1196751
X0776083Y1196751
X0783503Y1193011
X0774212Y1254724
X0774212Y1250984
X0770472Y1247243
X0781693Y1247243
X0770472Y1243503
X0777953Y1247243
X0781693Y1239763
X0774212Y1236023
X0777953Y1239763
X0774212Y1232283
X0777953Y1228543
X0770472Y1224803
X0781693Y1228543
X0770472Y1228543
X0774212Y1258465
X0785434Y1228543
X0785434Y1239762
X0785434Y1247243
X0781693Y1236023
X0777953Y1236023
X0777953Y1232283
X0781693Y1232283
X0770472Y1232283
X0770472Y1236023
X0774212Y1228543
X0774212Y1224803
X0777953Y1224803
X0781693Y1224803
X0777953Y1254724
X0774212Y1239763
X0770472Y1239763
X0781693Y1243503
X0777953Y1243503
X0774212Y1243503
X0774212Y1247243
X0777953Y1250984
X0781693Y1250984
X0770472Y1254724
X0770472Y1250984
X0770928Y1360099
X0770928Y1348187
X0778808Y1360099
X0778808Y1348187
X0958837Y0620661
X0962380Y0620661
X0958837Y0617861
X0962380Y0617861
X0965923Y0620661
X0965923Y0617861
X0917549Y0460970
X0920349Y0460970
X0917549Y0457427
X0917549Y0453884
X0920349Y0457427
X0920349Y0453884
X0917549Y0450340
X0920349Y0450340
X0969467Y0617861
X0969467Y0620661
X1061121Y1099507
X1064862Y1095767
X1068602Y1103247
X1057381Y1099507
X1061121Y1088287
X1057381Y1088287
X1064862Y1073326
X1068602Y1080807
X1061121Y1121948
X1057381Y1121948
X1061121Y1106988
X1057381Y1106988
X1064862Y1118208
X1064862Y1110728
X1068602Y1118208
X1068602Y1084547
X1068602Y1110728
X1061121Y1114468
X1057381Y1114468
X1064862Y1092027
X1068602Y1099507
X1068602Y1077066
X1061121Y1077066
X1061121Y1080806
X1064862Y1080807
X1064862Y1084547
X1061121Y1084547
X1068602Y1088287
X1064862Y1088287
X1068602Y1092027
X1061121Y1092027
X1064861Y1077066
X1068602Y1073326
X1057381Y1110728
X1057381Y1118208
X1061121Y1110728
X1068602Y1114468
X1064862Y1114468
X1061121Y1118208
X1068602Y1121948
X1064862Y1121948
X1057381Y1103247
X1057381Y1095767
X1064862Y1099507
X1064862Y1103247
X1061121Y1103247
X1068602Y1106988
X1064862Y1106988
X1068602Y1095767
X1061121Y1095767
X1057381Y1084547
X1057381Y1092027
X1061121Y1136909
X1064862Y1133169
X1057381Y1136909
X1061121Y1129429
X1057381Y1129429
X1068602Y1125688
X1064862Y1125688
X1057380Y1178051
X1061120Y1178051
X1068602Y1178051
X1057380Y1170570
X1061120Y1170570
X1057381Y1148129
X1061121Y1148129
X1059251Y1191141
X1066732Y1202362
X1059251Y1213582
X1066732Y1187401
X1059251Y1206102
X1066732Y1209842
X1062991Y1213582
X1062991Y1206102
X1062991Y1191141
X1066732Y1194881
X1059251Y1198621
X1062991Y1198621
X1062991Y1221062
X1066732Y1217322
X1059251Y1221062
X1055510Y1191142
X1055510Y1198622
X1055510Y1206103
X1055510Y1213583
X1055510Y1221063
X1066732Y1183661
X1062991Y1183661
X1059251Y1183661
X1066732Y1221062
X1062991Y1217322
X1062991Y1209842
X1066732Y1213582
X1062991Y1202362
X1062991Y1194881
X1066732Y1206102
X1066732Y1198621
X1066732Y1191141
X1062991Y1187401
X1059251Y1217322
X1059251Y1209842
X1059251Y1202362
X1059251Y1194881
X1059251Y1187401
X1068602Y1129429
X1064862Y1129429
X1061121Y1133169
X1064862Y1136909
X1068602Y1140649
X1064862Y1140649
X1061121Y1140649
X1064861Y1174310
X1061120Y1174310
X1064861Y1178051
X1068602Y1174310
X1068602Y1181791
X1064861Y1181791
X1061120Y1181791
X1057381Y1159350
X1061122Y1166830
X1064862Y1159350
X1061121Y1159350
X1068602Y1166830
X1064861Y1166830
X1068602Y1170570
X1064861Y1170570
X1057381Y1144389
X1057381Y1151870
X1064862Y1144389
X1061121Y1144389
X1068602Y1151869
X1064862Y1148129
X1064862Y1151870
X1061121Y1151870
X1068602Y1155610
X1064862Y1155610
X1057381Y1125688
X1057381Y1133169
X1057381Y1140649
X1061121Y1125688
X1054881Y1178050
X1054881Y1170570
X1062991Y1228543
X1066732Y1250984
X1062991Y1239763
X1066732Y1232283
X1059251Y1239763
X1062991Y1247243
X1066732Y1236023
X1059251Y1228543
X1059251Y1247243
X1066732Y1254724
X1066732Y1258465
X1055510Y1228542
X1055509Y1247242
X1055509Y1239762
X1062991Y1243503
X1062991Y1254724
X1062991Y1250984
X1066732Y1243503
X1066732Y1239763
X1066732Y1247243
X1062991Y1224803
X1062991Y1232283
X1062991Y1236023
X1066732Y1224803
X1066732Y1228543
X1059251Y1250984
X1059251Y1243503
X1059251Y1224803
X1059251Y1236023
X1059251Y1232283
X1060353Y1360099
X1064713Y1360099
X1060353Y1348187
X1064713Y1348187
X1052473Y1360099
X1052473Y1348187
X1060353Y1372385
X1060353Y1384297
X1064713Y1384297
X1064713Y1372385
X1052473Y1372385
X1052473Y1384297
X1064713Y1408495
X1064713Y1396583
X1158273Y1408495
X1162633Y1408495
X1158273Y1396583
X1162633Y1396583
X1158273Y1372385
X1158273Y1384297
X1162633Y1384297
X1162633Y1372385
X1158273Y1360099
X1162633Y1360099
X1158273Y1348187
X1162633Y1348187
X1146033Y1408495
X1150393Y1408495
X1146033Y1396583
X1150393Y1396583
X1146033Y1384297
X1146033Y1372385
X1150393Y1372385
X1150393Y1384297
X1146033Y1360099
X1150393Y1360099
X1146033Y1348187
X1150393Y1348187
X1125913Y1408495
X1133793Y1408495
X1138153Y1408495
X1125913Y1396583
X1133793Y1396583
X1138153Y1396583
X1125913Y1372385
X1125913Y1384297
X1133793Y1372385
X1133793Y1384297
X1138153Y1372385
X1138153Y1384297
X1125913Y1360099
X1133793Y1360099
X1138153Y1360099
X1125913Y1348187
X1133793Y1348187
X1138153Y1348187
X1109313Y1408495
X1121553Y1408495
X1113673Y1408495
X1109313Y1396583
X1121553Y1396583
X1113673Y1396583
X1109313Y1372385
X1109313Y1384297
X1121553Y1384297
X1121553Y1372385
X1113673Y1384297
X1113673Y1372385
X1109313Y1360099
X1121553Y1360099
X1113673Y1360099
X1109313Y1348187
X1121553Y1348187
X1113673Y1348187
X1097073Y1408495
X1101433Y1408495
X1097073Y1396583
X1101433Y1396583
X1097073Y1384297
X1097073Y1372385
X1101433Y1372385
X1101433Y1384297
X1097073Y1360099
X1101433Y1360099
X1097073Y1348187
X1101433Y1348187
X1076953Y1408495
X1084833Y1408495
X1089193Y1408495
X1076953Y1396583
X1084833Y1396583
X1089193Y1396583
X1076953Y1372385
X1076953Y1384297
X1084833Y1372385
X1084833Y1384297
X1089193Y1372385
X1089193Y1384297
X1076953Y1360099
X1084833Y1360099
X1089193Y1360099
X1076953Y1348187
X1084833Y1348187
X1089193Y1348187
X1072593Y1408495
X1072593Y1396583
X1072593Y1372385
X1072593Y1384297
X1072593Y1360099
X1072593Y1348187
X1156495Y1250984
X1149015Y1250984
X1152755Y1247243
X1145275Y1243503
X1156495Y1254724
X1152755Y1243503
X1163976Y1254724
X1167716Y1243503
X1160235Y1243503
X1145275Y1247243
X1160235Y1247243
X1163976Y1250984
X1167716Y1247243
X1149015Y1254724
X1104133Y1250984
X1111613Y1250984
X1085432Y1247243
X1100393Y1247243
X1134054Y1254724
X1134054Y1250984
X1130314Y1243503
X1137795Y1247243
X1115354Y1247243
X1126574Y1250984
X1141535Y1250984
X1107873Y1247243
X1100393Y1243503
X1107873Y1243503
X1115354Y1243503
X1130314Y1247243
X1089172Y1250984
X1092913Y1243503
X1089172Y1254724
X1137795Y1243503
X1122834Y1247243
X1096653Y1250984
X1119094Y1254724
X1092913Y1247243
X1085432Y1243503
X1141535Y1254724
X1111613Y1254724
X1104133Y1254724
X1119094Y1250984
X1122834Y1243503
X1096653Y1254724
X1126574Y1254724
X1130314Y1224803
X1167716Y1228543
X1085432Y1228543
X1141535Y1232283
X1152755Y1224803
X1085432Y1224803
X1145275Y1228543
X1122834Y1228543
X1111613Y1236023
X1070472Y1224803
X1092913Y1228543
X1130314Y1228543
X1077952Y1228543
X1096653Y1232283
X1137795Y1224803
X1074212Y1232283
X1107873Y1228543
X1126574Y1236023
X1077952Y1224803
X1074212Y1236023
X1115354Y1224803
X1081692Y1254724
X1119094Y1236023
X1111613Y1232283
X1077952Y1247243
X1100393Y1224803
X1115354Y1228543
X1081692Y1250984
X1096653Y1236023
X1089172Y1236023
X1107873Y1224803
X1126574Y1232283
X1070472Y1243503
X1104133Y1232283
X1141535Y1236023
X1092913Y1224803
X1104133Y1236023
X1081692Y1236023
X1081692Y1232283
X1134054Y1232283
X1137795Y1228543
X1134054Y1236023
X1089172Y1232283
X1100393Y1228543
X1077952Y1243503
X1119094Y1232283
X1070472Y1228543
X1074212Y1254724
X1070472Y1247243
X1074212Y1250984
X1074212Y1258465
X1081692Y1258465
X1089173Y1258465
X1096653Y1258465
X1104133Y1258465
X1111614Y1258465
X1126574Y1258465
X1119094Y1258465
X1134055Y1258465
X1141536Y1258465
X1149015Y1258465
X1156495Y1258465
X1163976Y1258465
X1160235Y1254724
X1160235Y1250984
X1160235Y1239763
X1167716Y1254724
X1167716Y1250984
X1167716Y1239763
X1163976Y1247243
X1163976Y1243503
X1163976Y1239763
X1160235Y1236023
X1160235Y1232283
X1167716Y1236023
X1167716Y1232283
X1163976Y1224803
X1163976Y1228543
X1145275Y1254724
X1145275Y1250984
X1145275Y1239763
X1156495Y1247243
X1156495Y1243503
X1156495Y1239763
X1152755Y1239763
X1149015Y1239763
X1149015Y1243503
X1149015Y1247243
X1152755Y1250984
X1152755Y1254724
X1145275Y1236023
X1145275Y1232283
X1149015Y1224803
X1149015Y1228543
X1156495Y1224803
X1156495Y1228543
X1152755Y1236023
X1152755Y1232283
X1130314Y1239763
X1134054Y1239763
X1137795Y1239763
X1137795Y1254724
X1137795Y1250984
X1134054Y1243503
X1134054Y1247243
X1130314Y1254724
X1130314Y1250984
X1141535Y1247243
X1141535Y1243503
X1141535Y1239763
X1130314Y1236023
X1130314Y1232283
X1134054Y1224803
X1134054Y1228543
X1137795Y1236023
X1137795Y1232283
X1141535Y1224803
X1141535Y1228543
X1111613Y1239763
X1111613Y1243503
X1111613Y1247243
X1119094Y1239763
X1115354Y1239763
X1126574Y1239763
X1122834Y1239763
X1122834Y1250984
X1122834Y1254724
X1126574Y1247243
X1126574Y1243503
X1119094Y1243503
X1119094Y1247243
X1115354Y1254724
X1115354Y1250984
X1111613Y1224803
X1111613Y1228543
X1115354Y1236023
X1115354Y1232283
X1119094Y1228543
X1119094Y1224803
X1122834Y1236023
X1122834Y1232283
X1126574Y1228543
X1126574Y1224803
X1096653Y1243503
X1096653Y1239763
X1096653Y1247243
X1104133Y1243503
X1107873Y1239763
X1104133Y1239763
X1100393Y1239763
X1107873Y1254724
X1107873Y1250984
X1104133Y1247243
X1100393Y1254724
X1100393Y1250984
X1096653Y1224803
X1096653Y1228543
X1100393Y1236023
X1100393Y1232283
X1107873Y1236023
X1104133Y1228543
X1104133Y1224803
X1107873Y1232283
X1092913Y1239763
X1092913Y1254724
X1092913Y1250984
X1092913Y1236023
X1092913Y1232283
X1089172Y1247243
X1089172Y1243503
X1089172Y1239763
X1085432Y1239763
X1085432Y1250984
X1081692Y1243503
X1081692Y1239763
X1085432Y1254724
X1081692Y1247243
X1089172Y1228543
X1089172Y1224803
X1081692Y1224803
X1081692Y1228543
X1085432Y1236023
X1085432Y1232283
X1074212Y1243503
X1074212Y1239763
X1077952Y1239763
X1070472Y1239763
X1077952Y1254724
X1077952Y1250984
X1074212Y1247243
X1070472Y1254724
X1070472Y1250984
X1077952Y1236023
X1077952Y1232283
X1074212Y1228543
X1074212Y1224803
X1070472Y1232283
X1070472Y1236023
X1156495Y1236023
X1163976Y1236023
X1156495Y1232283
X1145275Y1224803
X1152755Y1228543
X1149015Y1232283
X1149015Y1236023
X1160235Y1228543
X1167716Y1224803
X1163976Y1232283
X1160235Y1224803
X1122834Y1224803
X1106003Y1133169
X1106003Y1129429
X1098523Y1136909
X1079822Y1155610
X1102263Y1215452
X1102263Y1155610
X1098523Y1170570
X1102263Y1148129
X1102263Y1181791
X1098523Y1159350
X1098523Y1151870
X1098523Y1178051
X1102263Y1174310
X1102263Y1166830
X1165846Y1211711
X1162105Y1211711
X1152755Y1217322
X1117224Y1211712
X1128444Y1211712
X1156495Y1217322
X1154625Y1215452
X1158365Y1215452
X1150885Y1215452
X1132184Y1215452
X1162105Y1215451
X1115354Y1217322
X1128444Y1215452
X1111613Y1217322
X1150885Y1211712
X1113484Y1211712
X1109743Y1215452
X1117224Y1215452
X1120964Y1211712
X1098523Y1215452
X1120964Y1215452
X1106003Y1215452
X1124704Y1215452
X1072342Y1178051
X1083562Y1159350
X1083562Y1151870
X1079822Y1148129
X1109743Y1140649
X1165846Y1215452
X1135925Y1215452
X1135925Y1211712
X1139665Y1211712
X1143405Y1215452
X1143405Y1211712
X1079822Y1144389
X1083562Y1148129
X1091043Y1144389
X1091043Y1148129
X1091043Y1151870
X1091043Y1159350
X1091043Y1166830
X1098523Y1144389
X1098523Y1185531
X1120964Y1136909
X1117224Y1136909
X1113484Y1136909
X1124704Y1136909
X1124704Y1193011
X1113484Y1193011
X1117224Y1193011
X1120964Y1193011
X1128444Y1136909
X1132184Y1136909
X1135924Y1136909
X1139665Y1136909
X1139665Y1193011
X1135924Y1193011
X1132184Y1193011
X1128444Y1193011
X1150885Y1136909
X1154625Y1136909
X1143405Y1136909
X1143405Y1193011
X1154625Y1193011
X1150885Y1193011
X1162106Y1136909
X1158365Y1136909
X1165846Y1136909
X1162106Y1193011
X1158365Y1193011
X1165846Y1193011
X1091043Y1174310
X1091043Y1178051
X1091043Y1181791
X1106003Y1136909
X1106003Y1193011
X1124704Y1129429
X1117224Y1129429
X1113484Y1129429
X1120964Y1129429
X1124704Y1200491
X1113484Y1200491
X1120964Y1200491
X1117224Y1200491
X1139665Y1129429
X1135924Y1129429
X1128444Y1129429
X1132184Y1129429
X1139665Y1200491
X1135924Y1200491
X1128444Y1200491
X1132184Y1200491
X1143405Y1129429
X1150885Y1129429
X1154625Y1129429
X1150885Y1200491
X1154625Y1200491
X1143405Y1200491
X1158365Y1129429
X1162106Y1129429
X1165846Y1129429
X1158365Y1200491
X1162106Y1200491
X1165846Y1200491
X1106003Y1159350
X1106003Y1170570
X1106003Y1144389
X1106003Y1151869
X1106003Y1185531
X1106003Y1178051
X1124704Y1174310
X1117224Y1174310
X1109743Y1181791
X1109743Y1174310
X1124704Y1166830
X1120964Y1170570
X1117224Y1166830
X1113484Y1170570
X1109743Y1166830
X1120964Y1159350
X1113484Y1159350
X1117224Y1155610
X1109743Y1148129
X1109743Y1155610
X1124704Y1155610
X1135924Y1159350
X1128444Y1159350
X1132184Y1166830
X1128444Y1170570
X1135924Y1170570
X1139665Y1166830
X1132184Y1155610
X1139665Y1155610
X1132184Y1174310
X1139665Y1174310
X1150885Y1174310
X1154625Y1170570
X1150885Y1166830
X1143405Y1159350
X1154625Y1159350
X1143405Y1170570
X1150885Y1155610
X1162106Y1159350
X1162106Y1170570
X1158365Y1166830
X1165846Y1166830
X1158365Y1155610
X1165846Y1155610
X1158365Y1174310
X1165846Y1174310
X1124704Y1185531
X1117224Y1185531
X1113484Y1185531
X1120964Y1185531
X1124704Y1178051
X1120964Y1178051
X1117224Y1178051
X1113484Y1178051
X1124704Y1151870
X1120964Y1151870
X1117224Y1151870
X1113484Y1151870
X1120964Y1144389
X1117224Y1144389
X1113484Y1144389
X1124704Y1144389
X1139665Y1151870
X1128444Y1151870
X1132184Y1151870
X1135925Y1151870
X1139665Y1144389
X1132184Y1144389
X1135924Y1144389
X1128444Y1144389
X1135924Y1185531
X1128444Y1185531
X1132184Y1185531
X1139665Y1185531
X1128444Y1178051
X1132184Y1178051
X1135924Y1178051
X1139665Y1178051
X1150885Y1178051
X1154625Y1178051
X1150885Y1185531
X1154625Y1185531
X1143405Y1185531
X1143405Y1178051
X1143405Y1151870
X1150885Y1144389
X1154625Y1144389
X1154625Y1151869
X1150885Y1151869
X1143405Y1144389
X1162106Y1144389
X1158365Y1144389
X1165846Y1144389
X1165846Y1151869
X1162106Y1151869
X1158365Y1151869
X1162106Y1178051
X1158365Y1178051
X1165846Y1178051
X1165846Y1185531
X1162106Y1185531
X1158365Y1185531
X1070472Y1202362
X1070472Y1209842
X1070472Y1194881
X1070472Y1187401
X1085432Y1213582
X1085432Y1191141
X1085432Y1206102
X1081692Y1187401
X1077952Y1217322
X1089172Y1213582
X1081692Y1217322
X1081692Y1194881
X1085432Y1198621
X1081692Y1209842
X1081692Y1202362
X1077952Y1187401
X1077952Y1209842
X1089172Y1198621
X1089172Y1191141
X1089172Y1206102
X1077952Y1202362
X1077952Y1194881
X1070472Y1217322
X1106003Y1140649
X1091043Y1185531
X1092913Y1221062
X1096653Y1221062
X1100393Y1221062
X1104133Y1221062
X1107873Y1221062
X1111613Y1221062
X1115354Y1221062
X1119094Y1221062
X1122834Y1221062
X1126574Y1221062
X1130314Y1221062
X1134054Y1221062
X1137795Y1221062
X1141535Y1221062
X1145275Y1221062
X1152755Y1221062
X1156495Y1221062
X1160235Y1221062
X1163976Y1221062
X1167716Y1221062
X1092913Y1217322
X1092913Y1213582
X1092913Y1209842
X1092913Y1206102
X1092913Y1202362
X1092913Y1198621
X1092913Y1194881
X1092913Y1191141
X1092913Y1187401
X1074212Y1183661
X1085432Y1187401
X1089172Y1187401
X1085432Y1183661
X1081692Y1183661
X1077952Y1183661
X1070472Y1183661
X1149015Y1221062
X1085432Y1217322
X1085432Y1221062
X1081692Y1221062
X1089172Y1221062
X1089172Y1217322
X1070472Y1221062
X1077952Y1221062
X1074212Y1221062
X1089172Y1209842
X1085432Y1209842
X1089172Y1202362
X1085432Y1202362
X1089172Y1194881
X1085432Y1194881
X1081692Y1213582
X1081692Y1191141
X1081692Y1206102
X1081692Y1198621
X1070472Y1213582
X1074212Y1213582
X1074212Y1209842
X1077952Y1213582
X1074212Y1217322
X1070472Y1206102
X1070472Y1198621
X1070472Y1191141
X1074212Y1202362
X1077952Y1206102
X1074212Y1206102
X1074212Y1194881
X1074212Y1198621
X1077952Y1198621
X1074212Y1191141
X1077952Y1191141
X1074212Y1187401
X1076082Y1174310
X1076082Y1178051
X1076082Y1181791
X1076082Y1159350
X1076082Y1144389
X1076082Y1148129
X1076082Y1151870
X1076082Y1155610
X1076082Y1140649
X1076082Y1125688
X1076082Y1129429
X1076082Y1133169
X1087302Y1144389
X1083562Y1144389
X1087302Y1148129
X1087302Y1155610
X1087302Y1151870
X1091043Y1129429
X1091043Y1133169
X1091043Y1136909
X1087302Y1140649
X1083562Y1140649
X1079822Y1140649
X1087302Y1129428
X1083562Y1129428
X1079822Y1129429
X1087302Y1136909
X1083562Y1136909
X1091043Y1140649
X1091043Y1125688
X1087302Y1174310
X1087302Y1178051
X1087302Y1181791
X1083562Y1181791
X1081692Y1179921
X1079822Y1178050
X1079822Y1174310
X1091043Y1170570
X1079822Y1166830
X1079822Y1170570
X1087302Y1159350
X1087302Y1166830
X1087302Y1170570
X1106003Y1166830
X1094783Y1166830
X1102263Y1159350
X1094783Y1159350
X1094783Y1170570
X1102263Y1170570
X1106003Y1155610
X1106003Y1148129
X1102263Y1144389
X1094783Y1144389
X1094783Y1148129
X1102263Y1151870
X1094783Y1155610
X1094783Y1151870
X1094783Y1140649
X1106003Y1125688
X1102263Y1125688
X1098523Y1125688
X1094783Y1125688
X1102263Y1129429
X1098523Y1129429
X1094783Y1129429
X1102263Y1133169
X1098523Y1133169
X1094783Y1133169
X1102263Y1136909
X1094783Y1136909
X1102263Y1140649
X1098523Y1140649
X1102263Y1193011
X1102263Y1196751
X1102263Y1200491
X1098523Y1200491
X1098523Y1204232
X1102263Y1204232
X1106003Y1204232
X1106003Y1196751
X1106003Y1200491
X1098523Y1193011
X1098523Y1196751
X1106003Y1174310
X1106003Y1181791
X1094783Y1178051
X1094783Y1174310
X1102263Y1185531
X1094783Y1181791
X1102263Y1178051
X1106003Y1219192
X1098523Y1219192
X1098523Y1211712
X1102263Y1211712
X1106003Y1211712
X1106003Y1207972
X1102263Y1207972
X1098523Y1207972
X1124704Y1148129
X1117224Y1148129
X1113484Y1148129
X1120964Y1148129
X1109743Y1133169
X1109743Y1129429
X1113484Y1140649
X1117224Y1140649
X1120964Y1140649
X1113484Y1125688
X1117224Y1125688
X1120964Y1125688
X1109743Y1125688
X1120964Y1133169
X1117224Y1133169
X1113484Y1133169
X1124704Y1133169
X1124704Y1140649
X1124704Y1125688
X1109743Y1136909
X1113484Y1174310
X1109743Y1185531
X1120964Y1174310
X1109743Y1178051
X1124704Y1181791
X1124704Y1189271
X1120964Y1181791
X1117224Y1181791
X1113484Y1181791
X1120964Y1189271
X1117224Y1189271
X1113484Y1189271
X1109743Y1189271
X1124704Y1159350
X1124704Y1170570
X1109743Y1159350
X1120964Y1166830
X1117224Y1159350
X1113484Y1166830
X1109743Y1170570
X1117224Y1170570
X1109743Y1151869
X1120964Y1155610
X1109743Y1144389
X1113484Y1155610
X1124704Y1207972
X1124704Y1211712
X1109743Y1207972
X1109743Y1211712
X1120964Y1207972
X1117224Y1207972
X1113484Y1207972
X1120964Y1196751
X1117224Y1196751
X1113484Y1196751
X1109743Y1200491
X1109743Y1196751
X1109743Y1193011
X1109743Y1204232
X1113484Y1204232
X1117224Y1204232
X1120964Y1204232
X1124704Y1196751
X1124704Y1204232
X1139665Y1140649
X1139665Y1133169
X1139665Y1189271
X1139665Y1181791
X1132184Y1159350
X1128444Y1166830
X1135925Y1166830
X1132184Y1170570
X1139665Y1159350
X1139665Y1170570
X1135924Y1155610
X1128444Y1155610
X1139665Y1148129
X1128444Y1148129
X1132184Y1148129
X1135924Y1148129
X1128444Y1133169
X1132184Y1133169
X1135924Y1133169
X1135924Y1125688
X1128444Y1125688
X1132184Y1125688
X1135924Y1140649
X1132184Y1140649
X1128444Y1140649
X1139665Y1125688
X1128444Y1207972
X1132184Y1207972
X1135924Y1207972
X1134054Y1217322
X1132184Y1211712
X1139665Y1207972
X1132184Y1204232
X1128444Y1204232
X1128444Y1196751
X1132184Y1196751
X1135924Y1196751
X1135924Y1204232
X1139665Y1204232
X1139665Y1196751
X1135924Y1174310
X1128444Y1174310
X1128444Y1189271
X1132184Y1189271
X1135924Y1189271
X1128444Y1181791
X1132184Y1181791
X1135924Y1181791
X1150885Y1125688
X1154625Y1140649
X1150885Y1140649
X1143405Y1125688
X1143405Y1140649
X1143503Y1132677
X1154625Y1133169
X1150885Y1133464
X1154625Y1125688
X1154625Y1174310
X1143405Y1174310
X1143405Y1189271
X1154625Y1189271
X1150885Y1189271
X1150885Y1181791
X1154625Y1181791
X1143405Y1181791
X1150885Y1159350
X1143405Y1166830
X1150885Y1170570
X1154625Y1166830
X1154625Y1155610
X1143405Y1155610
X1154625Y1148129
X1150885Y1148129
X1143405Y1148129
X1143405Y1207972
X1154625Y1211712
X1154625Y1207972
X1150885Y1207972
X1143405Y1204232
X1143405Y1196751
X1154625Y1196751
X1150885Y1204232
X1154625Y1204232
X1150885Y1196751
X1165846Y1159350
X1162106Y1166830
X1158365Y1159350
X1165846Y1170570
X1158365Y1170570
X1162106Y1155610
X1165846Y1148129
X1162106Y1148129
X1158365Y1148129
X1158365Y1133169
X1165846Y1125688
X1162106Y1125688
X1158365Y1125688
X1165846Y1140649
X1162106Y1140649
X1158365Y1140649
X1165846Y1133169
X1162106Y1133169
X1165846Y1196751
X1162106Y1196751
X1158365Y1196751
X1165846Y1204232
X1158365Y1204232
X1162106Y1204232
X1162106Y1174310
X1165846Y1189271
X1162106Y1189271
X1158365Y1189271
X1165846Y1181791
X1162106Y1181791
X1158365Y1181791
X1165846Y1207972
X1162106Y1207972
X1158365Y1207972
X1158365Y1211712
X1072342Y1166830
X1072342Y1151869
X1072342Y1155610
X1072342Y1125688
X1072342Y1129429
X1072342Y1140649
X1072342Y1174310
X1072342Y1181791
X1076082Y1110728
X1083562Y1103247
X1087302Y1114468
X1076082Y1099507
X1072342Y1092027
X1083562Y1114468
X1083562Y1080807
X1079822Y1073326
X1072342Y1073326
X1076082Y1080807
X1076082Y1084547
X1079822Y1077066
X1072342Y1077066
X1083562Y1084547
X1079822Y1092027
X1079822Y1110728
X1072342Y1095767
X1079822Y1095767
X1076082Y1103247
X1165846Y1118208
X1150885Y1114468
X1158365Y1114468
X1165846Y1114468
X1158365Y1118208
X1162106Y1118208
X1154625Y1114468
X1162106Y1114468
X1150885Y1118208
X1154625Y1118208
X1109743Y1114468
X1124704Y1114468
X1120964Y1114468
X1106003Y1114468
X1113484Y1114468
X1117224Y1114468
X1098523Y1114468
X1102263Y1114468
X1132184Y1114468
X1135925Y1114468
X1139665Y1114468
X1076082Y1118208
X1076082Y1121948
X1079822Y1118208
X1167715Y1082676
X1152754Y1082676
X1160234Y1082677
X1152754Y1086416
X1149014Y1075195
X1156494Y1078936
X1163975Y1078936
X1167715Y1086416
X1163975Y1075196
X1160234Y1086417
X1149014Y1078935
X1156494Y1075196
X1096653Y1078936
X1137795Y1082677
X1141535Y1078936
X1137795Y1086417
X1134054Y1075196
X1130314Y1082677
X1130314Y1086417
X1122834Y1082677
X1119094Y1075196
X1089172Y1078936
X1126574Y1078936
X1145275Y1082677
X1092913Y1086417
X1115354Y1086417
X1141535Y1075196
X1134054Y1078936
X1100393Y1086417
X1111613Y1078936
X1092913Y1082677
X1089172Y1075196
X1115354Y1082677
X1126574Y1075196
X1104133Y1075196
X1119094Y1078936
X1107873Y1086417
X1096653Y1075196
X1107873Y1082677
X1104133Y1078936
X1122834Y1086417
X1145275Y1086417
X1111613Y1075196
X1100393Y1082677
X1107873Y1101376
X1115354Y1105117
X1122834Y1101376
X1167716Y1101376
X1163975Y1097637
X1152755Y1105117
X1163975Y1093897
X1149014Y1093897
X1156494Y1097637
X1152755Y1101376
X1167716Y1105117
X1156494Y1093897
X1149014Y1097637
X1160235Y1101376
X1160235Y1105117
X1089172Y1108858
X1092913Y1108858
X1096653Y1108858
X1100393Y1108858
X1104133Y1108858
X1107873Y1108858
X1111613Y1108858
X1115354Y1108858
X1119094Y1108858
X1122834Y1108858
X1126574Y1108858
X1130314Y1108858
X1134054Y1108858
X1137795Y1108858
X1141535Y1108858
X1145275Y1108858
X1149015Y1108858
X1152755Y1108858
X1156495Y1108858
X1160235Y1108858
X1163976Y1108858
X1167716Y1108858
X1089171Y1071455
X1096652Y1071455
X1104132Y1071455
X1111612Y1071455
X1119093Y1071455
X1126573Y1071455
X1134053Y1071455
X1141534Y1071455
X1149014Y1071454
X1156494Y1071455
X1163975Y1071455
X1089172Y1105117
X1163976Y1105117
X1156495Y1105117
X1149015Y1105117
X1141535Y1105117
X1134054Y1105117
X1111613Y1105117
X1126574Y1105117
X1119094Y1105117
X1096653Y1105117
X1104133Y1105117
X1160235Y1097637
X1160235Y1093897
X1167716Y1093897
X1167716Y1097637
X1163976Y1101377
X1160235Y1090157
X1160235Y1078936
X1167716Y1090157
X1163976Y1090157
X1163976Y1086417
X1163976Y1082677
X1167716Y1078936
X1160235Y1075196
X1167716Y1075196
X1145275Y1097637
X1145275Y1093897
X1156495Y1101377
X1152755Y1097637
X1152755Y1093897
X1149015Y1101377
X1145275Y1078936
X1145275Y1090157
X1156495Y1082677
X1152755Y1078936
X1149015Y1090157
X1156495Y1086417
X1156495Y1090157
X1152755Y1090157
X1149015Y1086417
X1149015Y1082677
X1145275Y1075196
X1152755Y1075196
X1141535Y1101377
X1134054Y1101377
X1137795Y1097637
X1137795Y1093897
X1130314Y1093897
X1130314Y1097637
X1141535Y1090157
X1141535Y1086417
X1141535Y1082677
X1137795Y1078936
X1137795Y1090157
X1134054Y1090157
X1134054Y1086417
X1134054Y1082677
X1130314Y1078936
X1130314Y1090157
X1137795Y1075196
X1130314Y1075196
X1111613Y1101377
X1126574Y1101377
X1119094Y1101377
X1115354Y1097637
X1122834Y1097637
X1115354Y1093897
X1122834Y1093897
X1111613Y1090157
X1111613Y1086417
X1111613Y1082677
X1122834Y1078936
X1126574Y1082677
X1126574Y1086417
X1126574Y1090157
X1122834Y1090157
X1119094Y1090157
X1119094Y1086417
X1119094Y1082677
X1115354Y1078936
X1115354Y1090157
X1122834Y1075196
X1115354Y1075196
X1096653Y1101377
X1100393Y1093897
X1100393Y1097637
X1104133Y1101377
X1107873Y1097637
X1107873Y1093897
X1096653Y1090157
X1096653Y1086417
X1096653Y1082677
X1100393Y1090157
X1100393Y1078936
X1107873Y1078936
X1107873Y1090157
X1104133Y1082677
X1104133Y1090157
X1104133Y1086417
X1100393Y1075196
X1107873Y1075196
X1089172Y1101377
X1092913Y1097637
X1092913Y1093897
X1092913Y1090157
X1089172Y1090157
X1092913Y1078936
X1089172Y1086417
X1089172Y1082677
X1092913Y1075196
X1076082Y1114468
X1076082Y1095767
X1076082Y1106988
X1076082Y1077066
X1076082Y1088287
X1076082Y1092027
X1076082Y1073326
X1083562Y1073326
X1079822Y1099507
X1079822Y1103247
X1083562Y1106988
X1079822Y1106988
X1087302Y1106988
X1083562Y1095767
X1083562Y1099507
X1079822Y1080807
X1079822Y1084547
X1079822Y1088287
X1083562Y1077066
X1083562Y1088287
X1083562Y1092027
X1091043Y1114468
X1091043Y1118208
X1091043Y1121948
X1091043Y1110728
X1087302Y1110728
X1083562Y1110728
X1079822Y1114468
X1087302Y1118208
X1083562Y1118208
X1083562Y1121948
X1094783Y1114468
X1106003Y1118208
X1102263Y1118208
X1098523Y1118208
X1094783Y1118208
X1106003Y1121948
X1102263Y1121948
X1098523Y1121948
X1094783Y1121948
X1094783Y1110728
X1120964Y1121948
X1124704Y1118208
X1124704Y1121948
X1113484Y1118208
X1109743Y1118208
X1113484Y1121948
X1109743Y1121948
X1120964Y1118208
X1117224Y1118208
X1117224Y1121948
X1139665Y1118208
X1128444Y1121948
X1135924Y1121948
X1132184Y1121948
X1135924Y1118208
X1132184Y1118208
X1128444Y1118208
X1130314Y1112598
X1128444Y1114468
X1139665Y1121948
X1154625Y1121948
X1143405Y1114468
X1143405Y1118208
X1143405Y1121948
X1150885Y1121948
X1158365Y1121948
X1162106Y1121948
X1165846Y1121948
X1072342Y1080807
X1072342Y1084547
X1072342Y1088287
X1072342Y1110728
X1072342Y1114468
X1072342Y1118208
X1072342Y1121948
X1072342Y1103247
X1072342Y1106988
X1072342Y1099507
X1137794Y1101376
X1119094Y1093897
X1122834Y1105117
X1126574Y1097637
X1141535Y1097637
X1107873Y1105117
X1089172Y1093897
X1145275Y1101376
X1092913Y1101376
X1096653Y1093897
X1100393Y1101376
X1137794Y1105117
X1134054Y1097637
X1130314Y1101376
X1111613Y1097637
X1104133Y1093897
X1100393Y1105117
X1096653Y1097637
X1134054Y1093897
X1130314Y1105117
X1111613Y1093897
X1104133Y1097637
X1141535Y1093897
X1115354Y1101376
X1119094Y1097637
X1089172Y1097637
X1126574Y1093897
X1092913Y1105117
X1145275Y1105117
X1169586Y1118208
X1199507Y1114468
X1184546Y1114468
X1173326Y1118208
X1177066Y1118208
X1173326Y1114468
X1169586Y1114468
X1177066Y1114468
X1192027Y1114468
X1188287Y1114468
X1195767Y1114468
X1195767Y1118208
X1199507Y1118208
X1186416Y1078936
X1197636Y1086416
X1182675Y1082676
X1201376Y1075196
X1186416Y1075196
X1171455Y1078936
X1201376Y1078936
X1205116Y1086417
X1171455Y1075196
X1193896Y1078936
X1178935Y1078936
X1175195Y1082677
X1197636Y1082676
X1190155Y1082677
X1182675Y1086416
X1205116Y1082677
X1193896Y1075196
X1178935Y1075196
X1175195Y1086417
X1190155Y1086417
X1220077Y1082677
X1227557Y1082677
X1208857Y1075196
X1216337Y1078936
X1208857Y1078936
X1223817Y1075196
X1227558Y1120078
X1231297Y1075196
X1238779Y1082676
X1235039Y1116338
X1223817Y1078936
X1235039Y1108858
X1231298Y1112598
X1227557Y1086417
X1235039Y1082676
X1231298Y1120078
X1238779Y1116338
X1216337Y1075196
X1231297Y1078936
X1220077Y1086417
X1212597Y1086416
X1238779Y1108858
X1227558Y1112598
X1212597Y1082676
X1231298Y1097637
X1220078Y1120078
X1223817Y1097637
X1186416Y1097637
X1220078Y1112598
X1190157Y1105117
X1208857Y1097637
X1238779Y1090157
X1201376Y1097637
X1223817Y1093897
X1175196Y1101376
X1193896Y1093897
X1220078Y1101376
X1190157Y1101376
X1216337Y1097637
X1216338Y1112598
X1205117Y1101376
X1216338Y1120078
X1238779Y1101377
X1182676Y1101376
X1178935Y1093897
X1212598Y1116338
X1175196Y1105117
X1197637Y1101376
X1208857Y1116338
X1171455Y1097637
X1182676Y1105117
X1208857Y1093897
X1186416Y1093897
X1227558Y1105117
X1171455Y1093897
X1212598Y1105117
X1235039Y1101377
X1212598Y1101376
X1205117Y1105117
X1231298Y1093897
X1216337Y1093897
X1178935Y1097637
X1220078Y1105117
X1197637Y1105117
X1235039Y1090157
X1193896Y1097637
X1201376Y1093897
X1227558Y1101377
X1171456Y1108858
X1175196Y1108858
X1178936Y1108858
X1182676Y1108858
X1186417Y1108858
X1190157Y1108858
X1193897Y1108858
X1197637Y1108858
X1201377Y1108858
X1205117Y1108858
X1205117Y1116338
X1205117Y1120078
X1208858Y1108858
X1171455Y1071455
X1178935Y1071455
X1186416Y1071455
X1193896Y1071455
X1201376Y1071455
X1208857Y1071455
X1216338Y1071455
X1223818Y1071455
X1231298Y1071455
X1242520Y1082677
X1242520Y1090158
X1242520Y1101378
X1242520Y1108859
X1242520Y1116339
X1238779Y1120078
X1235039Y1120078
X1238779Y1112598
X1235039Y1112598
X1231298Y1116338
X1227558Y1116338
X1231298Y1108858
X1227558Y1108858
X1238779Y1105117
X1235039Y1105117
X1223818Y1120078
X1223818Y1112598
X1220078Y1116338
X1223818Y1116338
X1223817Y1108858
X1220077Y1108857
X1208857Y1120078
X1208857Y1112598
X1212598Y1120078
X1216338Y1116338
X1216338Y1108858
X1212598Y1108858
X1231299Y1105117
X1208858Y1105117
X1223818Y1105117
X1216338Y1105117
X1193897Y1105117
X1201377Y1105117
X1186417Y1105117
X1178936Y1105117
X1171456Y1105117
X1235039Y1097637
X1238779Y1097637
X1238779Y1093897
X1235039Y1093897
X1231298Y1101377
X1227558Y1097637
X1227558Y1093897
X1238779Y1078936
X1231298Y1090157
X1227557Y1090157
X1231299Y1086417
X1235039Y1086417
X1238779Y1086417
X1231298Y1082677
X1227559Y1078936
X1235039Y1078936
X1235039Y1075196
X1227559Y1075196
X1208857Y1101377
X1216338Y1101377
X1223818Y1101377
X1220078Y1097637
X1212598Y1097637
X1220078Y1093897
X1212598Y1093897
X1208857Y1090157
X1208858Y1086417
X1208857Y1082677
X1223817Y1090157
X1220077Y1090157
X1216337Y1090157
X1212597Y1090157
X1223818Y1086417
X1216338Y1086417
X1216337Y1082677
X1223817Y1082677
X1212599Y1078936
X1220079Y1078936
X1220079Y1075196
X1212598Y1075196
X1193897Y1101377
X1205117Y1097637
X1205117Y1093897
X1197637Y1093897
X1201377Y1101377
X1197637Y1097637
X1193897Y1090157
X1193897Y1086417
X1193897Y1082677
X1205116Y1090157
X1205117Y1078936
X1201377Y1082677
X1201377Y1086417
X1201377Y1090157
X1197637Y1090157
X1197637Y1078936
X1205117Y1075196
X1197637Y1075196
X1190157Y1097637
X1190157Y1093897
X1182676Y1093897
X1182676Y1097637
X1186417Y1101377
X1178936Y1101377
X1190157Y1090157
X1190157Y1078936
X1186417Y1082677
X1186417Y1086417
X1186417Y1090157
X1182676Y1090157
X1178936Y1086417
X1178936Y1082677
X1182676Y1078936
X1178936Y1090157
X1190157Y1075196
X1182676Y1075196
X1175196Y1093897
X1175196Y1097637
X1171456Y1101377
X1175196Y1090157
X1171456Y1090157
X1171456Y1086417
X1171456Y1082677
X1175196Y1078936
X1175196Y1075196
X1173326Y1121948
X1169586Y1121948
X1184546Y1121948
X1177066Y1121948
X1180806Y1121948
X1184546Y1118208
X1188287Y1121948
X1188287Y1118208
X1192027Y1121948
X1192027Y1118208
X1184547Y1215452
X1195767Y1211712
X1199507Y1200491
X1195767Y1207972
X1192027Y1204232
X1192027Y1207972
X1192027Y1200491
X1192027Y1196751
X1188287Y1178051
X1240649Y1159350
X1229428Y1155610
X1225688Y1178051
X1236909Y1174310
X1236909Y1159350
X1229428Y1193011
X1236909Y1144389
X1229428Y1185531
X1225688Y1193011
X1229428Y1178051
X1236909Y1189271
X1240649Y1189271
X1225688Y1185531
X1225688Y1155610
X1240649Y1144389
X1229428Y1148129
X1236909Y1181791
X1229428Y1140649
X1240649Y1181791
X1225688Y1140649
X1225688Y1170570
X1240649Y1151870
X1236909Y1136909
X1229428Y1170570
X1225688Y1148129
X1236909Y1151870
X1240649Y1174310
X1240649Y1136909
X1206988Y1170570
X1221948Y1144389
X1221948Y1189271
X1221948Y1151869
X1206988Y1140649
X1218208Y1181791
X1210728Y1155610
X1221948Y1174310
X1206988Y1148129
X1221948Y1181791
X1206988Y1155610
X1210728Y1170570
X1218208Y1174310
X1218208Y1151869
X1218208Y1144389
X1218208Y1189271
X1195767Y1215452
X1199507Y1207972
X1199507Y1215452
X1188287Y1211712
X1199507Y1211712
X1195767Y1200491
X1199507Y1204232
X1203247Y1140649
X1199507Y1144389
X1199507Y1148129
X1177066Y1215452
X1169586Y1215452
X1195767Y1144389
X1203247Y1181791
X1199507Y1178051
X1227558Y1217322
X1235039Y1206102
X1227558Y1202362
X1231298Y1217322
X1235039Y1198621
X1216338Y1209842
X1208858Y1213582
X1208858Y1206102
X1212598Y1213582
X1216338Y1217322
X1212598Y1206102
X1220078Y1209842
X1220078Y1202362
X1216338Y1202362
X1208858Y1198621
X1212598Y1198621
X1220078Y1217322
X1235039Y1221062
X1238779Y1213582
X1238779Y1198621
X1231298Y1202362
X1227558Y1209842
X1238779Y1206102
X1231298Y1209842
X1238779Y1221062
X1235039Y1213582
X1199507Y1196751
X1199507Y1136909
X1203247Y1148129
X1199507Y1140649
X1180806Y1215452
X1173326Y1215452
X1192027Y1215452
X1188287Y1215452
X1188287Y1144389
X1188287Y1140649
X1188287Y1136909
X1188287Y1193011
X1188287Y1189271
X1188287Y1185531
X1169586Y1136909
X1173326Y1136909
X1173326Y1193011
X1169586Y1193011
X1177066Y1136909
X1180806Y1136909
X1180806Y1193011
X1177066Y1193011
X1192027Y1159350
X1192027Y1155610
X1192027Y1174310
X1192027Y1170570
X1192027Y1166830
X1221948Y1166830
X1218208Y1159350
X1218208Y1166830
X1188287Y1129429
X1188287Y1200491
X1184546Y1181791
X1195767Y1181791
X1173326Y1129429
X1169586Y1129429
X1169586Y1200491
X1173326Y1200491
X1177066Y1129429
X1180806Y1129429
X1177066Y1200491
X1180806Y1200491
X1199507Y1159350
X1199507Y1166830
X1199507Y1170570
X1199507Y1155610
X1199507Y1174310
X1169586Y1159350
X1169586Y1170570
X1173326Y1155610
X1173326Y1174310
X1173326Y1166830
X1180806Y1155610
X1180806Y1174310
X1199507Y1189271
X1203247Y1189271
X1169586Y1144389
X1173326Y1144389
X1169586Y1151869
X1173326Y1151869
X1173326Y1178051
X1169586Y1178051
X1173326Y1185531
X1169586Y1185531
X1184546Y1159350
X1180806Y1159350
X1177066Y1159350
X1180806Y1166830
X1184546Y1166830
X1177066Y1170570
X1184546Y1170570
X1180806Y1170570
X1180806Y1144389
X1177066Y1144389
X1177066Y1151869
X1180806Y1151869
X1180806Y1178051
X1180806Y1185531
X1177066Y1178051
X1177066Y1185531
X1238779Y1123818
X1227558Y1135039
X1231298Y1127558
X1235039Y1131299
X1238779Y1131299
X1227558Y1127558
X1235039Y1123818
X1231298Y1135039
X1220078Y1127559
X1220078Y1135039
X1208857Y1131299
X1212598Y1131299
X1208857Y1123818
X1216338Y1135039
X1212598Y1123818
X1216338Y1127559
X1171456Y1221062
X1175196Y1221062
X1178936Y1221062
X1182676Y1221062
X1186417Y1221062
X1190157Y1221062
X1193897Y1221062
X1197637Y1221062
X1201377Y1221062
X1205117Y1221062
X1205117Y1217322
X1205117Y1213582
X1205117Y1209842
X1205117Y1206102
X1205117Y1202362
X1205117Y1198621
X1205117Y1123818
X1205117Y1127558
X1205117Y1131299
X1205117Y1135039
X1242520Y1198621
X1242520Y1206102
X1242520Y1213582
X1242520Y1221062
X1242520Y1123819
X1242520Y1131300
X1208858Y1135039
X1212598Y1135039
X1238779Y1135039
X1235039Y1135039
X1223818Y1135039
X1227557Y1131299
X1231298Y1131299
X1235039Y1127558
X1238779Y1127558
X1231298Y1123818
X1227558Y1123818
X1220078Y1131299
X1223818Y1131299
X1223818Y1127558
X1208858Y1127558
X1216338Y1131299
X1212598Y1127558
X1220078Y1123818
X1223818Y1123818
X1216338Y1123818
X1227558Y1213582
X1231298Y1213582
X1235039Y1209842
X1238779Y1209842
X1227558Y1221062
X1231298Y1221062
X1235039Y1217322
X1238779Y1217322
X1227558Y1198621
X1231298Y1198621
X1227558Y1206102
X1231298Y1206102
X1235039Y1202362
X1238779Y1202362
X1208858Y1209842
X1208858Y1217322
X1208858Y1221062
X1212598Y1209842
X1223818Y1209842
X1223818Y1213582
X1220078Y1213582
X1216338Y1213582
X1212598Y1217322
X1212598Y1221062
X1216338Y1221062
X1220078Y1221062
X1223818Y1217322
X1223818Y1221062
X1208858Y1202362
X1216338Y1198621
X1220078Y1198621
X1223818Y1198621
X1223818Y1202362
X1212598Y1202362
X1216338Y1206102
X1220078Y1206102
X1223818Y1206102
X1173326Y1170570
X1173326Y1159350
X1169586Y1166830
X1169586Y1155610
X1169586Y1148129
X1173326Y1148129
X1173326Y1140649
X1173326Y1125688
X1173326Y1133169
X1169586Y1125688
X1169586Y1140649
X1169586Y1133169
X1169586Y1207972
X1169586Y1211712
X1173326Y1196751
X1173326Y1204232
X1169586Y1196751
X1169586Y1204232
X1169586Y1174310
X1173326Y1181791
X1169586Y1189271
X1169586Y1181791
X1173326Y1189271
X1173326Y1211712
X1173326Y1207972
X1188287Y1170570
X1188287Y1159350
X1188287Y1166830
X1177066Y1166830
X1184546Y1155610
X1177066Y1155610
X1184546Y1151869
X1184546Y1148129
X1184546Y1144389
X1180806Y1148129
X1177066Y1148129
X1188287Y1148129
X1188287Y1151869
X1188287Y1155610
X1184546Y1140649
X1180806Y1125688
X1177066Y1125688
X1184546Y1129429
X1184546Y1125688
X1180806Y1140649
X1177066Y1140649
X1184546Y1133169
X1180806Y1133169
X1177066Y1133169
X1184546Y1136909
X1188287Y1125688
X1184546Y1207972
X1180806Y1211712
X1180806Y1207972
X1177066Y1211712
X1177066Y1207972
X1184546Y1211712
X1188287Y1207972
X1184566Y1196732
X1188287Y1196751
X1188287Y1204232
X1184546Y1193011
X1180806Y1196751
X1177066Y1196751
X1184546Y1200491
X1180806Y1204232
X1177066Y1204232
X1184546Y1204232
X1184546Y1174310
X1184546Y1189271
X1180806Y1181791
X1177066Y1181791
X1184546Y1185531
X1177066Y1174310
X1184546Y1178051
X1180806Y1189271
X1177066Y1189271
X1188287Y1174310
X1188287Y1181791
X1195767Y1166830
X1203247Y1159350
X1203247Y1170570
X1203247Y1166830
X1195767Y1159350
X1195767Y1170570
X1192027Y1151870
X1203247Y1144389
X1203247Y1155610
X1203247Y1151869
X1199507Y1151869
X1195767Y1151869
X1192027Y1148129
X1195767Y1155610
X1192027Y1144389
X1195767Y1148129
X1192027Y1129429
X1192027Y1125688
X1195767Y1136909
X1192027Y1140649
X1192027Y1133169
X1195767Y1140649
X1192027Y1136909
X1192027Y1193011
X1195767Y1193011
X1195767Y1196751
X1203247Y1193011
X1199507Y1193011
X1195767Y1204232
X1195767Y1174310
X1195767Y1178051
X1199507Y1181791
X1195767Y1185531
X1192027Y1185531
X1195767Y1189271
X1192027Y1189271
X1192027Y1178051
X1203247Y1185531
X1203247Y1178051
X1203247Y1174310
X1199507Y1185531
X1192027Y1181791
X1192027Y1211712
X1206987Y1136909
X1214468Y1140649
X1218208Y1140649
X1221948Y1159350
X1221948Y1170570
X1214468Y1166830
X1214468Y1170570
X1218208Y1170570
X1206987Y1166830
X1210728Y1166830
X1214468Y1159350
X1210728Y1159350
X1206987Y1159350
X1221948Y1148129
X1210728Y1144389
X1206987Y1144389
X1214468Y1144389
X1214468Y1148129
X1214468Y1151869
X1214468Y1155610
X1218208Y1148129
X1218208Y1155610
X1206987Y1151869
X1210728Y1151869
X1221948Y1155610
X1221948Y1140649
X1221948Y1193011
X1214468Y1193011
X1218208Y1193011
X1212598Y1194881
X1208858Y1194881
X1210728Y1174310
X1214468Y1174310
X1214468Y1178051
X1214468Y1181791
X1214468Y1185531
X1206987Y1189271
X1206987Y1174310
X1221948Y1185531
X1221948Y1178051
X1214468Y1189271
X1218208Y1178051
X1218208Y1185531
X1210728Y1189271
X1206987Y1181791
X1210728Y1181791
X1233169Y1166830
X1233169Y1170570
X1229428Y1166830
X1225688Y1159350
X1233169Y1159350
X1229428Y1159350
X1225688Y1166830
X1236909Y1166830
X1236909Y1170570
X1233169Y1148129
X1233169Y1151869
X1229428Y1151869
X1233169Y1155610
X1229428Y1144389
X1225688Y1151869
X1225688Y1144389
X1233169Y1144389
X1236909Y1155610
X1236909Y1148129
X1233169Y1136909
X1229428Y1136909
X1233169Y1140649
X1236909Y1140649
X1236909Y1193011
X1233169Y1196751
X1229428Y1196751
X1223818Y1194881
X1233169Y1193011
X1225688Y1189271
X1225688Y1181791
X1225688Y1174310
X1233169Y1174310
X1229428Y1174310
X1233169Y1178051
X1233169Y1181791
X1233169Y1185531
X1233169Y1189271
X1229428Y1189271
X1229428Y1181791
X1236909Y1185531
X1236909Y1178051
X1240649Y1185531
X1240649Y1178051
X1240649Y1170570
X1240649Y1166830
X1240649Y1155610
X1240649Y1148129
X1240649Y1140649
X1243149Y1136909
X1240589Y1193011
X1216338Y1250984
X1235039Y1247243
X1231298Y1250984
X1216338Y1254724
X1227558Y1243503
X1208858Y1250984
X1208858Y1236023
X1235039Y1239763
X1220078Y1228543
X1223818Y1232283
X1235039Y1228543
X1212598Y1224803
X1216338Y1232283
X1216338Y1236023
X1231298Y1236023
X1223818Y1236023
X1205117Y1224803
X1227558Y1224803
X1205117Y1228543
X1208858Y1232283
X1227558Y1228543
X1238779Y1228543
X1212598Y1228543
X1220078Y1224803
X1238779Y1239763
X1231298Y1232283
X1223818Y1250984
X1205117Y1247243
X1208858Y1254724
X1212598Y1247243
X1205117Y1243503
X1238779Y1247243
X1223818Y1254724
X1231298Y1254724
X1220078Y1243503
X1220078Y1247243
X1212598Y1243503
X1227558Y1247243
X1171456Y1254724
X1171456Y1250984
X1171456Y1236023
X1201377Y1232283
X1175196Y1247243
X1186417Y1254724
X1190157Y1247243
X1193897Y1254724
X1197637Y1243503
X1201377Y1254724
X1193897Y1250984
X1182676Y1243503
X1186417Y1250984
X1178936Y1250984
X1197637Y1247243
X1182676Y1247243
X1175196Y1243503
X1201377Y1250984
X1178936Y1254724
X1190157Y1243503
X1171456Y1258465
X1178936Y1258465
X1186417Y1258465
X1193897Y1258465
X1201377Y1258465
X1208858Y1258465
X1216338Y1258465
X1223818Y1258465
X1231298Y1258465
X1242520Y1228543
X1242520Y1239762
X1242520Y1247243
X1225688Y1222932
X1235039Y1254724
X1231298Y1239763
X1227558Y1239763
X1238779Y1243503
X1235039Y1243503
X1231298Y1243503
X1231298Y1247243
X1235039Y1250984
X1238779Y1250984
X1227558Y1254724
X1227558Y1250984
X1238779Y1236023
X1235039Y1236023
X1235039Y1232283
X1238779Y1232283
X1227558Y1232283
X1227558Y1236023
X1231298Y1228543
X1231298Y1224803
X1235039Y1224803
X1238779Y1224803
X1208858Y1239763
X1208858Y1243503
X1208858Y1247243
X1223818Y1239763
X1220078Y1239763
X1216338Y1239763
X1212598Y1239763
X1223818Y1243503
X1223818Y1247243
X1220078Y1254724
X1220078Y1250984
X1216338Y1243503
X1216338Y1247243
X1212598Y1254724
X1212598Y1250984
X1208858Y1228543
X1208858Y1224803
X1220078Y1236023
X1220078Y1232283
X1223818Y1228543
X1223818Y1224803
X1212598Y1236023
X1212598Y1232283
X1216338Y1228543
X1216338Y1224803
X1193897Y1243503
X1193897Y1239763
X1193897Y1247243
X1205117Y1239763
X1201377Y1243503
X1201377Y1239763
X1197637Y1239763
X1205117Y1254724
X1205117Y1250984
X1201377Y1247243
X1197637Y1254724
X1197637Y1250984
X1193897Y1224803
X1193897Y1228543
X1205117Y1236023
X1205117Y1232283
X1201377Y1224803
X1197637Y1236023
X1201377Y1228543
X1197637Y1232283
X1190157Y1239763
X1186417Y1243503
X1178936Y1243503
X1182676Y1239763
X1186417Y1239763
X1178936Y1239763
X1186417Y1247243
X1190157Y1250984
X1190157Y1254724
X1182676Y1254724
X1182676Y1250984
X1178936Y1247243
X1186417Y1224803
X1186417Y1228543
X1190157Y1236023
X1190157Y1232283
X1182676Y1236023
X1182676Y1232283
X1178936Y1224803
X1178936Y1228543
X1171456Y1239763
X1175196Y1250984
X1175196Y1239763
X1171456Y1243503
X1171456Y1247243
X1175196Y1254724
X1175196Y1236023
X1175196Y1232283
X1171456Y1224803
X1171456Y1228543
X1197637Y1228543
X1193897Y1232283
X1190157Y1224803
X1201377Y1236023
X1175196Y1224803
X1190157Y1228543
X1193897Y1236023
X1171456Y1232283
X1182676Y1224803
X1197637Y1224803
X1178936Y1232283
X1175196Y1228543
X1186417Y1232283
X1178936Y1236023
X1186417Y1236023
X1182676Y1228543
X1174873Y1408495
X1182753Y1408495
X1174873Y1396583
X1182753Y1396583
X1174873Y1372385
X1174873Y1384297
X1182753Y1372385
X1182753Y1384297
X1174873Y1360099
X1182753Y1360099
X1174873Y1348187
X1182753Y1348187
X1170513Y1408495
X1170513Y1396583
X1170513Y1384297
X1170513Y1372385
X1170513Y1360099
X1170513Y1348187
X1260446Y1408495
X1264806Y1408495
X1260446Y1396583
X1264806Y1396583
X1260446Y1384297
X1260446Y1372385
X1264806Y1384297
X1264806Y1372385
X1260446Y1360099
X1264806Y1360099
X1260446Y1348187
X1264806Y1348187
X1248206Y1408495
X1240326Y1408495
X1252566Y1408495
X1248206Y1396583
X1240326Y1396583
X1252566Y1396583
X1248206Y1384297
X1248206Y1372385
X1240326Y1372385
X1240326Y1384297
X1252566Y1384297
X1252566Y1372385
X1248206Y1360099
X1240326Y1360099
X1252566Y1360099
X1248206Y1348187
X1240326Y1348187
X1252566Y1348187
X1228086Y1384297
X1228086Y1372385
X1235966Y1384297
X1235966Y1372385
X1228086Y1360099
X1235966Y1360099
X1228086Y1348187
X1235966Y1348187
X1358366Y1408495
X1358366Y1396583
X1358366Y1384297
X1358366Y1372385
X1358366Y1360099
X1358366Y1348187
X1346126Y1408495
X1338246Y1408495
X1350486Y1408495
X1346126Y1396583
X1338246Y1396583
X1350486Y1396583
X1346126Y1372385
X1346126Y1384297
X1338246Y1372385
X1338246Y1384297
X1350486Y1384297
X1350486Y1372385
X1346126Y1360099
X1338246Y1360099
X1350486Y1360099
X1346126Y1348187
X1338246Y1348187
X1350486Y1348187
X1321646Y1408495
X1326006Y1408495
X1333886Y1408495
X1321646Y1396583
X1326006Y1396583
X1333886Y1396583
X1321646Y1372385
X1321646Y1384297
X1326006Y1384297
X1326006Y1372385
X1333886Y1384297
X1333886Y1372385
X1321646Y1360099
X1326006Y1360099
X1333886Y1360099
X1321646Y1348187
X1326006Y1348187
X1333886Y1348187
X1309406Y1408495
X1313766Y1408495
X1309406Y1396583
X1313766Y1396583
X1309406Y1384297
X1309406Y1372385
X1313766Y1384297
X1313766Y1372385
X1309406Y1360099
X1313766Y1360099
X1309406Y1348187
X1313766Y1348187
X1297166Y1408495
X1289286Y1408495
X1301526Y1408495
X1297166Y1396583
X1289286Y1396583
X1301526Y1396583
X1297166Y1372385
X1297166Y1384297
X1289286Y1372385
X1289286Y1384297
X1301526Y1384297
X1301526Y1372385
X1297166Y1360099
X1289286Y1360099
X1301526Y1360099
X1297166Y1348187
X1289286Y1348187
X1301526Y1348187
X1272686Y1408495
X1277046Y1408495
X1284926Y1408495
X1272686Y1396583
X1277046Y1396583
X1284926Y1396583
X1272686Y1372385
X1272686Y1384297
X1277046Y1384297
X1277046Y1372385
X1284926Y1384297
X1284926Y1372385
X1272686Y1360099
X1277046Y1360099
X1284926Y1360099
X1272686Y1348187
X1277046Y1348187
X1284926Y1348187
X1336396Y0444629
X1339196Y0444629
X1336396Y0437543
X1336396Y0433999
X1336396Y0441086
X1339196Y0437543
X1339196Y0433999
X1339196Y0441086
X1415924Y0617861
X1415924Y0620661
X1419467Y0620661
X1426554Y0617861
X1426554Y0620661
X1423010Y0617861
X1419467Y0617861
X1423010Y0620661
X1459130Y1348187
X1459130Y1360099
X1459130Y1372385
X1459130Y1384297
X1467010Y1348187
X1467010Y1360099
X1467010Y1372385
X1467010Y1384297
X1564930Y1360099
X1564930Y1372385
X1564930Y1384297
X1564930Y1396583
X1564930Y1408495
X1557050Y1360099
X1552690Y1384297
X1552690Y1372385
X1557050Y1372385
X1557050Y1384297
X1552690Y1396583
X1557050Y1396583
X1552690Y1408495
X1557050Y1408495
X1564930Y1348187
X1540450Y1372385
X1540450Y1384297
X1532570Y1372385
X1532570Y1384297
X1544810Y1372385
X1544810Y1384297
X1540450Y1396583
X1532570Y1396583
X1544810Y1396583
X1540450Y1408495
X1532570Y1408495
X1544810Y1408495
X1552690Y1348187
X1557050Y1348187
X1552690Y1360099
X1515970Y1372385
X1515970Y1384297
X1520330Y1384297
X1520330Y1372385
X1528210Y1384297
X1528210Y1372385
X1515970Y1396583
X1520330Y1396583
X1528210Y1396583
X1515970Y1408495
X1520330Y1408495
X1528210Y1408495
X1540450Y1348187
X1532570Y1348187
X1544810Y1348187
X1540450Y1360099
X1532570Y1360099
X1544810Y1360099
X1503730Y1384297
X1503730Y1372385
X1508090Y1372385
X1508090Y1384297
X1503730Y1396583
X1508090Y1396583
X1503730Y1408495
X1508090Y1408495
X1515970Y1348187
X1520330Y1348187
X1528210Y1348187
X1515970Y1360099
X1520330Y1360099
X1528210Y1360099
X1495850Y1372385
X1495850Y1384297
X1491490Y1396583
X1483610Y1396583
X1495850Y1396583
X1491490Y1408495
X1483610Y1408495
X1495850Y1408495
X1503730Y1348187
X1508090Y1348187
X1503730Y1360099
X1508090Y1360099
X1471370Y1396583
X1479250Y1396583
X1471370Y1408495
X1479250Y1408495
X1491490Y1348187
X1483610Y1348187
X1495850Y1348187
X1491490Y1360099
X1483610Y1360099
X1495850Y1360099
X1491490Y1372385
X1491490Y1384297
X1483610Y1372385
X1483610Y1384297
X1471370Y1348187
X1479250Y1348187
X1471370Y1360099
X1479250Y1360099
X1471370Y1384297
X1471370Y1372385
X1479250Y1372385
X1479250Y1384297
X1523819Y1254724
X1523819Y1250984
X1531299Y1254724
X1535039Y1247243
X1527559Y1247243
X1527559Y1243503
X1531299Y1250984
X1535039Y1243503
X1516338Y1247243
X1538779Y1254724
X1520078Y1247243
X1538779Y1250984
X1542519Y1247243
X1553740Y1254724
X1568700Y1250984
X1546259Y1254724
X1542519Y1243503
X1553740Y1250984
X1557480Y1243503
X1550000Y1247243
X1557480Y1247243
X1564960Y1247243
X1564960Y1243503
X1546259Y1250984
X1550000Y1243503
X1561220Y1254724
X1561220Y1250984
X1568700Y1254724
X1568700Y1232283
X1527559Y1224803
X1538779Y1232283
X1523819Y1236023
X1520078Y1239763
X1531299Y1236023
X1520078Y1228543
X1564960Y1228543
X1523819Y1232283
X1557480Y1224803
X1542519Y1224803
X1561220Y1232283
X1523819Y1258465
X1531299Y1258465
X1538779Y1258465
X1546260Y1258465
X1553740Y1258465
X1561220Y1258465
X1568701Y1258465
X1512597Y1228542
X1512596Y1247242
X1512596Y1239762
X1568700Y1239763
X1568700Y1243503
X1568700Y1247243
X1568700Y1224803
X1568700Y1228543
X1553740Y1243503
X1553740Y1239763
X1553740Y1247243
X1561220Y1243503
X1564960Y1239763
X1561220Y1239763
X1557480Y1239763
X1564960Y1254724
X1564960Y1250984
X1561220Y1247243
X1557480Y1254724
X1557480Y1250984
X1553740Y1224803
X1553740Y1228543
X1557480Y1236023
X1557480Y1232283
X1564960Y1236023
X1561220Y1228543
X1561220Y1224803
X1564960Y1232283
X1550000Y1239763
X1550000Y1254724
X1550000Y1250984
X1550000Y1236023
X1550000Y1232283
X1546259Y1247243
X1546259Y1243503
X1546259Y1239763
X1542519Y1239763
X1542519Y1250984
X1538779Y1243503
X1538779Y1239763
X1542519Y1254724
X1538779Y1247243
X1546259Y1228543
X1546259Y1224803
X1538779Y1224803
X1538779Y1228543
X1542519Y1236023
X1542519Y1232283
X1520078Y1243503
X1520078Y1254724
X1520078Y1250984
X1531299Y1243503
X1531299Y1239763
X1535039Y1239763
X1527559Y1239763
X1523819Y1243503
X1523819Y1239763
X1535039Y1254724
X1535039Y1250984
X1531299Y1247243
X1523819Y1247243
X1527559Y1254724
X1527559Y1250984
X1520078Y1224803
X1520078Y1232283
X1520078Y1236023
X1535039Y1236023
X1535039Y1232283
X1531299Y1228543
X1531299Y1224803
X1523819Y1224803
X1523819Y1228543
X1527559Y1232283
X1527559Y1236023
X1516338Y1250984
X1516338Y1243503
X1516338Y1224803
X1516338Y1236023
X1516338Y1232283
X1561220Y1236023
X1557480Y1228543
X1546259Y1236023
X1550000Y1224803
X1516338Y1228543
X1535039Y1228543
X1542519Y1228543
X1516338Y1239763
X1531299Y1232283
X1553740Y1236023
X1550000Y1228543
X1564960Y1224803
X1527559Y1228543
X1553740Y1232283
X1538779Y1236023
X1535039Y1224803
X1568700Y1236023
X1546259Y1232283
X1563090Y1133169
X1563090Y1129429
X1555610Y1136909
X1536909Y1155610
X1514468Y1136909
X1521949Y1133169
X1518208Y1136909
X1514468Y1129429
X1521949Y1125688
X1518208Y1129429
X1525689Y1125688
X1559350Y1148129
X1555610Y1159350
X1559350Y1166830
X1555610Y1178051
X1559350Y1181791
X1555610Y1151870
X1559350Y1155610
X1559350Y1174310
X1555610Y1170570
X1559350Y1215452
X1566830Y1219192
X1566830Y1215452
X1563090Y1215452
X1555610Y1215452
X1514467Y1178051
X1518207Y1178051
X1531299Y1176180
X1527559Y1176180
X1514467Y1170570
X1518207Y1170570
X1566830Y1140649
X1514468Y1155610
X1518208Y1155610
X1514468Y1148129
X1518208Y1148129
X1536909Y1144389
X1540649Y1148129
X1540649Y1178050
X1540649Y1170570
X1540649Y1174310
X1540649Y1151870
X1555610Y1185531
X1548130Y1159350
X1548130Y1166830
X1548130Y1144389
X1548130Y1148129
X1548130Y1151870
X1555610Y1144389
X1540649Y1159350
X1536909Y1148129
X1563090Y1178051
X1563090Y1185531
X1563090Y1170570
X1563090Y1159350
X1563090Y1151869
X1563090Y1144389
X1566830Y1174310
X1566830Y1181791
X1566830Y1166830
X1566830Y1155610
X1566830Y1148129
X1548130Y1181791
X1548130Y1178051
X1548130Y1174310
X1563090Y1136909
X1563090Y1193011
X1527559Y1187401
X1520078Y1213582
X1523819Y1217322
X1527559Y1209842
X1520078Y1191141
X1527559Y1194881
X1527559Y1202362
X1516338Y1221062
X1523819Y1209842
X1527559Y1217322
X1520078Y1206102
X1516338Y1206102
X1516338Y1191141
X1523819Y1202362
X1520078Y1198621
X1523819Y1194881
X1516338Y1213582
X1523819Y1187401
X1516338Y1198621
X1520078Y1221062
X1538779Y1194881
X1535039Y1202362
X1538779Y1217322
X1538779Y1209842
X1538779Y1187401
X1546259Y1206102
X1535039Y1217322
X1546259Y1191141
X1546259Y1198621
X1563090Y1140649
X1548130Y1185531
X1553740Y1217322
X1550000Y1217322
X1550000Y1213582
X1550000Y1209842
X1550000Y1206102
X1550000Y1202362
X1550000Y1198621
X1550000Y1194881
X1550000Y1191141
X1550000Y1187401
X1512597Y1191142
X1512597Y1198622
X1512597Y1206103
X1512597Y1213583
X1512597Y1221063
X1542519Y1217322
X1542519Y1221062
X1538779Y1221062
X1546259Y1221062
X1546259Y1217322
X1516338Y1183661
X1520078Y1183661
X1523819Y1183661
X1527559Y1183661
X1531299Y1183661
X1535039Y1183661
X1538779Y1183661
X1542519Y1183661
X1542519Y1187401
X1546259Y1187401
X1568700Y1221062
X1527559Y1221062
X1523819Y1221062
X1535039Y1221062
X1531299Y1221062
X1546259Y1209842
X1542519Y1209842
X1546259Y1202362
X1542519Y1202362
X1546259Y1194881
X1542519Y1194881
X1538779Y1213582
X1538779Y1191141
X1538779Y1206102
X1538779Y1198621
X1520078Y1217322
X1520078Y1209842
X1523819Y1213582
X1527559Y1213582
X1531299Y1213582
X1531299Y1209842
X1535039Y1213582
X1531299Y1217322
X1520078Y1202362
X1520078Y1194881
X1527559Y1206102
X1523819Y1206102
X1523819Y1198621
X1527559Y1198621
X1523819Y1191141
X1527559Y1191141
X1531299Y1202362
X1535039Y1206102
X1531299Y1206102
X1531299Y1194881
X1531299Y1198621
X1535039Y1198621
X1531299Y1191141
X1535039Y1191141
X1520078Y1187401
X1531299Y1187401
X1516338Y1217322
X1516338Y1209842
X1516338Y1202362
X1516338Y1194881
X1516338Y1187401
X1564960Y1221062
X1561220Y1221062
X1557480Y1221062
X1553740Y1221062
X1550000Y1221062
X1514468Y1181790
X1514468Y1174309
X1511968Y1178050
X1514468Y1166829
X1514468Y1159350
X1511968Y1170570
X1514468Y1151870
X1514468Y1144389
X1514468Y1140649
X1514468Y1133169
X1514468Y1125688
X1518207Y1181791
X1523819Y1179921
X1527559Y1179921
X1531299Y1179921
X1529429Y1174310
X1525689Y1174310
X1521948Y1178051
X1518207Y1174310
X1521948Y1174310
X1518209Y1166830
X1521948Y1170570
X1525689Y1170570
X1521948Y1166830
X1525689Y1166830
X1529429Y1166830
X1518208Y1159350
X1521949Y1159350
X1521949Y1155610
X1525689Y1155610
X1529429Y1155610
X1518208Y1151870
X1521949Y1151870
X1521949Y1148129
X1525689Y1151869
X1529429Y1151869
X1518208Y1144389
X1521949Y1144389
X1518208Y1140649
X1521949Y1140649
X1525689Y1140649
X1529429Y1140649
X1521949Y1136909
X1518208Y1133169
X1521949Y1129429
X1525689Y1129429
X1529429Y1129429
X1518208Y1125688
X1529429Y1125688
X1535039Y1176180
X1538779Y1179921
X1540649Y1181791
X1544389Y1181791
X1544389Y1178051
X1544389Y1174310
X1533169Y1178051
X1533169Y1174310
X1536909Y1174310
X1544389Y1170570
X1544389Y1166830
X1544389Y1159350
X1536909Y1170570
X1536909Y1166830
X1533169Y1159350
X1544389Y1151870
X1544389Y1155610
X1544389Y1148129
X1533169Y1155610
X1533169Y1151870
X1533169Y1148129
X1533169Y1144389
X1540649Y1144389
X1544389Y1144389
X1540649Y1136909
X1533169Y1133169
X1544389Y1136909
X1533169Y1129429
X1536909Y1129429
X1540649Y1129428
X1544389Y1129428
X1533169Y1125688
X1533169Y1140649
X1536909Y1140649
X1540649Y1140649
X1544389Y1140649
X1563090Y1174310
X1563090Y1181791
X1551870Y1181791
X1559350Y1178051
X1551870Y1174310
X1551870Y1178051
X1551870Y1185531
X1559350Y1185531
X1551870Y1189271
X1563090Y1166830
X1551870Y1170570
X1548130Y1170570
X1551870Y1159350
X1559350Y1159350
X1551870Y1166830
X1559350Y1170570
X1563090Y1148129
X1563090Y1155610
X1559350Y1151870
X1551870Y1148129
X1551870Y1144389
X1559350Y1144389
X1551870Y1151870
X1551870Y1155610
X1551870Y1140649
X1555610Y1140649
X1559350Y1140649
X1548130Y1136909
X1551870Y1136909
X1559350Y1136909
X1548130Y1133169
X1551870Y1133169
X1555610Y1133169
X1559350Y1133169
X1548130Y1129429
X1551870Y1129429
X1555610Y1129429
X1559350Y1129429
X1548130Y1125688
X1551870Y1125688
X1555610Y1125688
X1559350Y1125688
X1563090Y1125688
X1548130Y1140649
X1563090Y1219192
X1555610Y1207972
X1559350Y1207972
X1563090Y1207972
X1563090Y1211712
X1559350Y1211712
X1555610Y1211712
X1555610Y1196751
X1555610Y1193011
X1563090Y1200491
X1563090Y1196751
X1563090Y1204232
X1559350Y1204232
X1555610Y1204232
X1555610Y1200491
X1559350Y1200491
X1559350Y1196751
X1559350Y1193011
X1551870Y1193011
X1566830Y1204232
X1566830Y1193011
X1566830Y1196751
X1566830Y1200491
X1566830Y1185531
X1566830Y1178051
X1566830Y1189271
X1566830Y1170570
X1566830Y1159350
X1566830Y1144389
X1566830Y1151869
X1566830Y1136909
X1566830Y1125688
X1566830Y1129429
X1566830Y1133169
X1566830Y1211712
X1566830Y1207972
X1535039Y1187401
X1535039Y1209842
X1546259Y1213582
X1542519Y1198621
X1542519Y1206102
X1535039Y1194881
X1538779Y1202362
X1542519Y1191141
X1542519Y1213582
X1533169Y1103247
X1540649Y1114468
X1533169Y1110728
X1536909Y1110728
X1536909Y1092027
X1525689Y1080807
X1514468Y1106988
X1518208Y1088287
X1540649Y1084547
X1521949Y1095767
X1525689Y1118208
X1521949Y1092027
X1518208Y1106988
X1540649Y1103247
X1533169Y1099507
X1525689Y1103247
X1529429Y1095767
X1514468Y1088287
X1525689Y1099507
X1536909Y1077066
X1529429Y1092027
X1536909Y1095767
X1518208Y1099507
X1529429Y1073326
X1540649Y1080807
X1544389Y1114468
X1521949Y1118208
X1514468Y1114468
X1533169Y1084547
X1514468Y1121948
X1533169Y1080807
X1518208Y1121948
X1536909Y1073326
X1525689Y1084547
X1521949Y1073326
X1525689Y1110728
X1518208Y1114468
X1529429Y1077066
X1521949Y1110728
X1514468Y1099507
X1566830Y1114468
X1563090Y1114468
X1555610Y1114468
X1559350Y1114468
X1533169Y1121948
X1533169Y1118208
X1536909Y1118208
X1561220Y1075196
X1557480Y1086417
X1568700Y1075196
X1553740Y1075196
X1550000Y1082677
X1564960Y1086417
X1564960Y1082677
X1550000Y1086417
X1561220Y1078936
X1553740Y1078936
X1557480Y1082677
X1546259Y1078936
X1546259Y1075196
X1568700Y1078936
X1546259Y1093897
X1546259Y1097637
X1564960Y1101376
X1553740Y1097637
X1568700Y1093897
X1553740Y1093897
X1550000Y1105117
X1550000Y1101376
X1551870Y1110728
X1550000Y1108858
X1553740Y1108858
X1557480Y1108858
X1561220Y1108858
X1564960Y1108858
X1568700Y1108858
X1546258Y1071455
X1553739Y1071455
X1561219Y1071455
X1568699Y1071455
X1546259Y1105117
X1550000Y1075196
X1557480Y1075196
X1564960Y1075196
X1546259Y1101377
X1550000Y1097637
X1550000Y1093897
X1550000Y1090157
X1546259Y1090157
X1550000Y1078936
X1546259Y1086417
X1546259Y1082677
X1568700Y1101377
X1568700Y1090157
X1568700Y1086417
X1568700Y1082677
X1553740Y1101377
X1557480Y1093897
X1557480Y1097637
X1561220Y1101377
X1564960Y1097637
X1564960Y1093897
X1553740Y1090157
X1553740Y1086417
X1553740Y1082677
X1557480Y1090157
X1557480Y1078936
X1564960Y1078936
X1564960Y1090157
X1561220Y1082677
X1561220Y1090157
X1561220Y1086417
X1568700Y1105117
X1553740Y1105117
X1561220Y1105117
X1514468Y1118208
X1514468Y1110728
X1514468Y1103247
X1514468Y1095767
X1514468Y1092027
X1514468Y1084547
X1529429Y1103247
X1521949Y1099507
X1529429Y1099507
X1518208Y1095767
X1525689Y1095767
X1521949Y1106988
X1525689Y1106988
X1529429Y1106988
X1518208Y1103247
X1518208Y1092027
X1525689Y1092027
X1521949Y1088287
X1525689Y1088287
X1529429Y1088287
X1518208Y1084547
X1521949Y1084547
X1529429Y1084547
X1521949Y1080807
X1529429Y1080807
X1518208Y1080806
X1518208Y1077066
X1525689Y1077066
X1521948Y1077066
X1525689Y1073326
X1521949Y1121948
X1525689Y1121948
X1529429Y1121948
X1518208Y1118208
X1529429Y1118208
X1521949Y1114468
X1525689Y1114468
X1529429Y1114468
X1518208Y1110728
X1529429Y1110728
X1521949Y1103247
X1533169Y1114468
X1536909Y1114468
X1540649Y1110728
X1544389Y1110728
X1540649Y1099507
X1540649Y1095767
X1544389Y1106988
X1533169Y1106988
X1536909Y1106988
X1540649Y1106988
X1536909Y1103247
X1536909Y1099507
X1533169Y1095767
X1544389Y1099507
X1540649Y1092027
X1540649Y1077066
X1533169Y1092027
X1533169Y1088287
X1536909Y1088287
X1536909Y1084547
X1536909Y1080807
X1533169Y1077066
X1540649Y1088287
X1540649Y1073326
X1533169Y1073326
X1540649Y1121948
X1540649Y1118208
X1544389Y1118208
X1548130Y1110728
X1548130Y1121948
X1551870Y1121948
X1555610Y1121948
X1559350Y1121948
X1563090Y1121948
X1548130Y1118208
X1551870Y1118208
X1555610Y1118208
X1559350Y1118208
X1563090Y1118208
X1548130Y1114468
X1551870Y1114468
X1566830Y1118208
X1566830Y1121948
X1561220Y1097637
X1568700Y1097637
X1557480Y1105117
X1561220Y1093897
X1564960Y1105117
X1557480Y1101376
X1622933Y1118208
X1626673Y1118208
X1630413Y1118208
X1634153Y1118208
X1611712Y1114468
X1626673Y1114468
X1641633Y1114468
X1622933Y1114468
X1607972Y1118208
X1619193Y1114468
X1656594Y1114468
X1611712Y1118208
X1615452Y1114468
X1607972Y1114468
X1619193Y1118208
X1630413Y1114468
X1615452Y1118208
X1634153Y1114468
X1581791Y1114468
X1578051Y1114468
X1570571Y1114468
X1574311Y1114468
X1637893Y1114468
X1637893Y1118208
X1649114Y1114468
X1645374Y1114468
X1652854Y1114468
X1589271Y1114468
X1593012Y1114468
X1596752Y1114468
X1652854Y1118208
X1656594Y1118208
X1576181Y1078936
X1598622Y1078936
X1576181Y1075196
X1591141Y1078936
X1587401Y1086417
X1572441Y1082677
X1579921Y1086417
X1587401Y1082677
X1594882Y1086417
X1583661Y1078936
X1579921Y1082677
X1591141Y1075196
X1598622Y1075196
X1594882Y1082677
X1602362Y1086417
X1602362Y1082677
X1583661Y1075196
X1572441Y1086417
X1665944Y1075196
X1665944Y1078936
X1621062Y1075196
X1658463Y1078936
X1624802Y1086416
X1639762Y1082676
X1617321Y1086417
X1662203Y1082677
X1621062Y1078936
X1647242Y1086417
X1647242Y1082677
X1617321Y1082677
X1606101Y1075195
X1628542Y1075196
X1650983Y1078936
X1609841Y1082676
X1636022Y1078936
X1658463Y1075196
X1654723Y1082676
X1643503Y1075196
X1624802Y1082676
X1650983Y1075196
X1636022Y1075196
X1632282Y1086417
X1639762Y1086416
X1628542Y1078936
X1654723Y1086416
X1606101Y1078935
X1643503Y1078936
X1613581Y1078936
X1609841Y1086416
X1613581Y1075196
X1632282Y1082677
X1662203Y1086417
X1621062Y1097637
X1606101Y1097637
X1628542Y1097637
X1665944Y1116338
X1650983Y1097637
X1654724Y1101376
X1624803Y1105117
X1662204Y1101376
X1643503Y1093897
X1609842Y1105117
X1643503Y1097637
X1624803Y1101376
X1613581Y1097637
X1647244Y1105117
X1650983Y1093897
X1636022Y1097637
X1613581Y1093897
X1665944Y1097637
X1654724Y1105117
X1609842Y1101376
X1632283Y1101376
X1658463Y1093897
X1617322Y1101376
X1632283Y1105117
X1639763Y1105117
X1579921Y1105117
X1572441Y1105117
X1572441Y1101376
X1602362Y1105117
X1587401Y1101376
X1591141Y1093897
X1598622Y1093897
X1579921Y1101376
X1587401Y1105117
X1576181Y1093897
X1587401Y1112598
X1572441Y1108858
X1576181Y1108858
X1579921Y1108858
X1583661Y1108858
X1587401Y1108858
X1591141Y1108858
X1594882Y1108858
X1598622Y1108858
X1602362Y1108858
X1606102Y1108858
X1609842Y1108858
X1613582Y1108858
X1617322Y1108858
X1621063Y1108858
X1624803Y1108858
X1628543Y1108858
X1632283Y1108858
X1636023Y1108858
X1639763Y1108858
X1643504Y1108858
X1647244Y1108858
X1650984Y1108858
X1654724Y1108858
X1658464Y1108858
X1662204Y1108858
X1662204Y1116338
X1662204Y1120078
X1665945Y1108858
X1576180Y1071455
X1583660Y1071455
X1591140Y1071455
X1598621Y1071455
X1606101Y1071454
X1613581Y1071455
X1621062Y1071455
X1628542Y1071455
X1636022Y1071455
X1643503Y1071455
X1650983Y1071455
X1658463Y1071455
X1665944Y1071455
X1632283Y1090157
X1624803Y1090157
X1628543Y1090157
X1628543Y1086417
X1628543Y1082677
X1632283Y1078936
X1621063Y1090157
X1621063Y1086417
X1621063Y1082677
X1624803Y1078936
X1617322Y1075196
X1632283Y1075196
X1624803Y1075196
X1602362Y1097637
X1602362Y1093897
X1613582Y1101377
X1609842Y1097637
X1609842Y1093897
X1606102Y1101377
X1602362Y1078936
X1602362Y1090157
X1613582Y1082677
X1609842Y1078936
X1606102Y1090157
X1613582Y1086417
X1613582Y1090157
X1609842Y1090157
X1606102Y1086417
X1606102Y1082677
X1602362Y1075196
X1609842Y1075196
X1598622Y1101377
X1591141Y1101377
X1594882Y1097637
X1594882Y1093897
X1587401Y1093897
X1587401Y1097637
X1598622Y1090157
X1598622Y1086417
X1598622Y1082677
X1594882Y1078936
X1594882Y1090157
X1591141Y1090157
X1591141Y1086417
X1591141Y1082677
X1587401Y1078936
X1587401Y1090157
X1594882Y1075196
X1587401Y1075196
X1583661Y1101377
X1576181Y1101377
X1572441Y1097637
X1579921Y1097637
X1572441Y1093897
X1579921Y1093897
X1579921Y1078936
X1583661Y1082677
X1583661Y1086417
X1583661Y1090157
X1579921Y1090157
X1576181Y1090157
X1576181Y1086417
X1576181Y1082677
X1572441Y1078936
X1572441Y1090157
X1579921Y1075196
X1572441Y1075196
X1665944Y1120078
X1665944Y1112598
X1665945Y1105117
X1650984Y1105117
X1658464Y1105117
X1643504Y1105117
X1636023Y1105117
X1613582Y1105117
X1606102Y1105117
X1598622Y1105117
X1591141Y1105117
X1583661Y1105117
X1576181Y1105117
X1665944Y1101377
X1665944Y1090157
X1665945Y1086417
X1665944Y1082677
X1650984Y1101377
X1662204Y1097637
X1662204Y1093897
X1654724Y1093897
X1658464Y1101377
X1628543Y1105117
X1621063Y1105117
X1654724Y1097637
X1639763Y1078936
X1662204Y1075196
X1621063Y1101377
X1624803Y1097637
X1570571Y1121948
X1570571Y1118208
X1578051Y1121948
X1574311Y1121948
X1574311Y1118208
X1578051Y1118208
X1585531Y1114468
X1581791Y1118208
X1585531Y1121948
X1593011Y1121948
X1589271Y1121948
X1593011Y1118208
X1589271Y1118208
X1585531Y1118208
X1581791Y1121948
X1600492Y1121948
X1596752Y1118208
X1607972Y1121948
X1611712Y1121948
X1600492Y1114468
X1600492Y1118208
X1596752Y1121948
X1615452Y1121948
X1619193Y1121948
X1622933Y1121948
X1626673Y1121948
X1641633Y1121948
X1630413Y1121948
X1634153Y1121948
X1637893Y1121948
X1641633Y1118208
X1645374Y1121948
X1649114Y1121948
X1649114Y1118208
X1645374Y1118208
X1639763Y1097637
X1639763Y1093897
X1647244Y1078936
X1647244Y1090157
X1650984Y1090157
X1639763Y1090157
X1624803Y1093897
X1632283Y1097637
X1643504Y1086417
X1628543Y1101377
X1617322Y1078936
X1617322Y1090157
X1650984Y1086417
X1650984Y1082677
X1643504Y1101377
X1662203Y1090157
X1662204Y1078936
X1658464Y1082677
X1658464Y1086417
X1658464Y1090157
X1654724Y1090157
X1654724Y1078936
X1647244Y1093897
X1647244Y1097637
X1654724Y1075196
X1636023Y1101377
X1617322Y1097637
X1617322Y1093897
X1632283Y1093897
X1643504Y1090157
X1636023Y1086417
X1636023Y1082677
X1643504Y1082677
X1647244Y1075196
X1639763Y1075196
X1636023Y1090157
X1598622Y1097637
X1583661Y1097637
X1594881Y1101376
X1583661Y1093897
X1576181Y1097637
X1591141Y1097637
X1594881Y1105117
X1602362Y1101376
X1636022Y1093897
X1647244Y1101376
X1662204Y1105117
X1628542Y1093897
X1617322Y1105117
X1658463Y1097637
X1665944Y1093897
X1606101Y1093897
X1621062Y1093897
X1639763Y1101376
X1652854Y1211712
X1641634Y1215452
X1656594Y1200491
X1652854Y1207972
X1649114Y1200491
X1645374Y1178051
X1649114Y1196751
X1649114Y1204232
X1649114Y1207972
X1664075Y1140649
X1664075Y1155610
X1664075Y1148129
X1667815Y1155610
X1667815Y1170570
X1664075Y1170570
X1574311Y1211712
X1652854Y1200491
X1656594Y1204232
X1622933Y1211711
X1619192Y1211711
X1656594Y1207972
X1656594Y1215452
X1645374Y1211712
X1656594Y1211712
X1609842Y1217322
X1652854Y1215452
X1578051Y1211712
X1570571Y1215452
X1613582Y1217322
X1634153Y1215452
X1585531Y1211712
X1607972Y1211712
X1615452Y1215452
X1607972Y1215452
X1611712Y1215452
X1626673Y1215452
X1574311Y1215452
X1619192Y1215451
X1585531Y1215452
X1570571Y1211712
X1589271Y1215452
X1578051Y1215452
X1581791Y1215452
X1660334Y1140649
X1656594Y1144389
X1656594Y1148129
X1652854Y1144389
X1656594Y1178051
X1660334Y1181791
X1665945Y1198621
X1665945Y1213582
X1665945Y1206102
X1656594Y1196751
X1656594Y1136909
X1660334Y1148129
X1656594Y1140649
X1656594Y1133169
X1622933Y1215452
X1637893Y1215452
X1630413Y1215452
X1593012Y1215452
X1593012Y1211712
X1596752Y1211712
X1600492Y1215452
X1600492Y1211712
X1649114Y1215452
X1645374Y1215452
X1645374Y1193011
X1645374Y1189271
X1645374Y1185531
X1645374Y1144389
X1645374Y1140649
X1645374Y1136909
X1574311Y1174310
X1570571Y1159350
X1578051Y1159350
X1570571Y1170570
X1574311Y1166830
X1578051Y1170570
X1574311Y1155610
X1581791Y1174310
X1589271Y1174310
X1593011Y1159350
X1585531Y1159350
X1581791Y1166830
X1589271Y1166830
X1585531Y1170570
X1593011Y1170570
X1589271Y1155610
X1581791Y1155610
X1596752Y1174310
X1607972Y1174310
X1600492Y1159350
X1611712Y1159350
X1596752Y1166830
X1600492Y1170570
X1611712Y1170570
X1607972Y1166830
X1607972Y1155610
X1596752Y1155610
X1626673Y1170570
X1622933Y1166830
X1619193Y1159350
X1626673Y1159350
X1619193Y1170570
X1615452Y1166830
X1615452Y1155610
X1622933Y1155610
X1615452Y1174310
X1622933Y1174310
X1630413Y1155610
X1637893Y1155610
X1630413Y1174310
X1637893Y1174310
X1630413Y1166830
X1660334Y1189271
X1570571Y1178051
X1574311Y1178051
X1578051Y1178051
X1578051Y1185531
X1570571Y1185531
X1574311Y1185531
X1570571Y1151870
X1574311Y1151870
X1578051Y1151870
X1570571Y1144389
X1574311Y1144389
X1578051Y1144389
X1585531Y1178051
X1589271Y1178051
X1593011Y1178051
X1581791Y1178051
X1593011Y1185531
X1581791Y1185531
X1585531Y1185531
X1589271Y1185531
X1581791Y1151870
X1585531Y1151870
X1589271Y1151870
X1593012Y1151870
X1589271Y1144389
X1593011Y1144389
X1581791Y1144389
X1585531Y1144389
X1607972Y1178051
X1611712Y1178051
X1607972Y1185531
X1611712Y1185531
X1596752Y1178051
X1600492Y1178051
X1596752Y1185531
X1600492Y1185531
X1596752Y1151870
X1600492Y1151870
X1607972Y1144389
X1611712Y1144389
X1607972Y1151869
X1611712Y1151869
X1596752Y1144389
X1600492Y1144389
X1615452Y1185531
X1626673Y1144389
X1619193Y1144389
X1615452Y1144389
X1622933Y1144389
X1622933Y1151869
X1626673Y1151869
X1619193Y1151869
X1615452Y1151869
X1626673Y1178051
X1619193Y1178051
X1615452Y1178051
X1622933Y1178051
X1622933Y1185531
X1626673Y1185531
X1619193Y1185531
X1637893Y1144389
X1630413Y1144389
X1634153Y1144389
X1634153Y1151869
X1637893Y1151869
X1630413Y1151869
X1637893Y1178051
X1637893Y1185531
X1634153Y1178051
X1630413Y1178051
X1634153Y1185531
X1630413Y1185531
X1634153Y1159350
X1641633Y1159350
X1637893Y1159350
X1637893Y1166830
X1641633Y1166830
X1634153Y1170570
X1641633Y1170570
X1637893Y1170570
X1641633Y1181791
X1645374Y1200491
X1652854Y1181791
X1645374Y1129429
X1578051Y1129429
X1570571Y1129429
X1574311Y1129429
X1574311Y1200491
X1578051Y1200491
X1570571Y1200491
X1593011Y1200491
X1581791Y1200491
X1585531Y1200491
X1589271Y1200491
X1593011Y1129429
X1581791Y1129429
X1585531Y1129429
X1589271Y1129429
X1607972Y1200491
X1611712Y1200491
X1596752Y1200491
X1600492Y1200491
X1596752Y1129429
X1600492Y1129429
X1607972Y1129429
X1611712Y1129429
X1615452Y1129429
X1619193Y1129429
X1622933Y1129429
X1626673Y1129429
X1626673Y1200491
X1615452Y1200491
X1619193Y1200491
X1622933Y1200491
X1634153Y1129429
X1637893Y1129429
X1630413Y1129429
X1634153Y1200491
X1637893Y1200491
X1630413Y1200491
X1656594Y1174310
X1656594Y1159350
X1656594Y1166830
X1656594Y1170570
X1656594Y1155610
X1570571Y1136909
X1574311Y1136909
X1578051Y1136909
X1578051Y1193011
X1574311Y1193011
X1570571Y1193011
X1581791Y1193011
X1593011Y1193011
X1589271Y1193011
X1585531Y1193011
X1581791Y1136909
X1585531Y1136909
X1589271Y1136909
X1593011Y1136909
X1596752Y1193011
X1600492Y1193011
X1611712Y1193011
X1607972Y1193011
X1607972Y1136909
X1611712Y1136909
X1596752Y1136909
X1600492Y1136909
X1619193Y1136909
X1615452Y1136909
X1622933Y1136909
X1626673Y1136909
X1619193Y1193011
X1615452Y1193011
X1626673Y1193011
X1622933Y1193011
X1634153Y1136909
X1637893Y1136909
X1630413Y1136909
X1630413Y1193011
X1637893Y1193011
X1634153Y1193011
X1649114Y1174310
X1649114Y1166830
X1649114Y1170570
X1649114Y1159350
X1649114Y1155610
X1656594Y1189271
X1662204Y1138779
X1662204Y1123818
X1662204Y1127558
X1662204Y1131299
X1662204Y1135039
X1647244Y1221062
X1643504Y1221062
X1639763Y1221062
X1636023Y1221062
X1602362Y1221062
X1594882Y1221062
X1662204Y1221062
X1650984Y1221062
X1658464Y1221062
X1665945Y1209842
X1665945Y1217322
X1665945Y1221062
X1665945Y1202362
X1654724Y1221062
X1583661Y1221062
X1579921Y1221062
X1576181Y1221062
X1572441Y1221062
X1665945Y1135039
X1665945Y1127558
X1624803Y1221062
X1632283Y1221062
X1609842Y1221062
X1598622Y1221062
X1628543Y1221062
X1613582Y1221062
X1621063Y1221062
X1587401Y1221062
X1591141Y1221062
X1570571Y1204232
X1570571Y1196751
X1574311Y1196751
X1578051Y1196751
X1578051Y1174310
X1570571Y1174310
X1570571Y1189271
X1574311Y1189271
X1578051Y1189271
X1570571Y1181791
X1574311Y1181791
X1578051Y1181791
X1574311Y1170570
X1570571Y1166830
X1574311Y1159350
X1578051Y1166830
X1578051Y1155610
X1570571Y1155610
X1578051Y1148129
X1570571Y1148129
X1574311Y1148129
X1570571Y1133169
X1574311Y1133169
X1578051Y1133169
X1578051Y1125688
X1574311Y1125688
X1570571Y1125688
X1578051Y1140649
X1574311Y1140649
X1570571Y1140649
X1570571Y1207972
X1574311Y1207972
X1578051Y1207972
X1578051Y1204232
X1574311Y1204232
X1581791Y1211712
X1581791Y1207972
X1589271Y1211712
X1589271Y1204232
X1585531Y1204232
X1581791Y1204232
X1581791Y1196751
X1585531Y1196751
X1589271Y1196751
X1593011Y1196751
X1593011Y1204232
X1593011Y1174310
X1585531Y1174310
X1581791Y1189271
X1585531Y1189271
X1589271Y1189271
X1593011Y1189271
X1581791Y1181791
X1585531Y1181791
X1589271Y1181791
X1593011Y1181791
X1581791Y1170570
X1589271Y1159350
X1581791Y1159350
X1585531Y1166830
X1593012Y1166830
X1589271Y1170570
X1585531Y1155610
X1593011Y1155610
X1581791Y1148129
X1585531Y1148129
X1589271Y1148129
X1593011Y1148129
X1585531Y1133169
X1589271Y1133169
X1593011Y1133169
X1593011Y1125688
X1581791Y1125688
X1585531Y1125688
X1589271Y1125688
X1593011Y1140649
X1589271Y1140649
X1585531Y1140649
X1581791Y1140649
X1581791Y1133169
X1585531Y1207972
X1589271Y1207972
X1593011Y1207972
X1591141Y1217322
X1593011Y1219192
X1611712Y1140649
X1607972Y1140649
X1596752Y1125688
X1600492Y1125688
X1600492Y1140649
X1596752Y1140649
X1596752Y1133169
X1600590Y1132677
X1611712Y1133169
X1607972Y1133464
X1600492Y1207972
X1596752Y1219192
X1611712Y1211712
X1611712Y1207972
X1607972Y1207972
X1596752Y1207972
X1600492Y1204232
X1596752Y1204232
X1596752Y1196751
X1600492Y1196751
X1611712Y1196751
X1607972Y1196751
X1607972Y1204232
X1611712Y1204232
X1611712Y1174310
X1600492Y1174310
X1596752Y1189271
X1600492Y1189271
X1596752Y1181791
X1611712Y1189271
X1607972Y1189271
X1607972Y1181791
X1611712Y1181791
X1600492Y1181791
X1607972Y1159350
X1600492Y1166830
X1607972Y1170570
X1611712Y1166830
X1596752Y1159350
X1596752Y1170570
X1611712Y1155610
X1600492Y1155610
X1611712Y1148129
X1607972Y1148129
X1596752Y1148129
X1600492Y1148129
X1611712Y1125688
X1607972Y1125688
X1619193Y1174310
X1626673Y1174310
X1626673Y1189271
X1622933Y1189271
X1619193Y1189271
X1615452Y1189271
X1626673Y1181791
X1622933Y1181791
X1619193Y1181791
X1615452Y1181791
X1622933Y1159350
X1619193Y1166830
X1615452Y1159350
X1626673Y1166830
X1622933Y1170570
X1615452Y1170570
X1626673Y1155610
X1619193Y1155610
X1626673Y1148129
X1622933Y1148129
X1619193Y1148129
X1615452Y1148129
X1626673Y1125688
X1622933Y1125688
X1619193Y1125688
X1615452Y1125688
X1626673Y1140649
X1622933Y1140649
X1619193Y1140649
X1615452Y1140649
X1626673Y1133169
X1622933Y1133169
X1619193Y1133169
X1615452Y1133169
X1615452Y1207972
X1615452Y1211712
X1626673Y1207972
X1626673Y1211712
X1622933Y1207972
X1619193Y1207972
X1626673Y1196751
X1622933Y1196751
X1619193Y1196751
X1615452Y1196751
X1622933Y1204232
X1626673Y1204232
X1615452Y1204232
X1619193Y1204232
X1630413Y1170570
X1630413Y1159350
X1634153Y1166830
X1641633Y1155610
X1634153Y1155610
X1641633Y1151869
X1641633Y1148129
X1641633Y1144389
X1637893Y1148129
X1634153Y1148129
X1630413Y1148129
X1630413Y1140649
X1641633Y1140649
X1637893Y1125688
X1634153Y1125688
X1630413Y1125688
X1641633Y1129429
X1641633Y1125688
X1637893Y1140649
X1634153Y1140649
X1641633Y1133169
X1637893Y1133169
X1634153Y1133169
X1630413Y1133169
X1641633Y1136909
X1641633Y1207972
X1630413Y1211712
X1637893Y1211712
X1637893Y1207972
X1634153Y1211712
X1630413Y1207972
X1634153Y1207972
X1641633Y1211712
X1641633Y1193011
X1637893Y1196751
X1634153Y1196751
X1630413Y1196751
X1641633Y1200491
X1637893Y1204232
X1634153Y1204232
X1630413Y1204232
X1641633Y1204232
X1641653Y1196732
X1641633Y1174310
X1630413Y1189271
X1641633Y1189271
X1637893Y1181791
X1634153Y1181791
X1630413Y1181791
X1641633Y1185531
X1634153Y1174310
X1641633Y1178051
X1637893Y1189271
X1634153Y1189271
X1652854Y1140649
X1649114Y1136909
X1649114Y1129429
X1660334Y1196751
X1645374Y1196751
X1649114Y1193011
X1652854Y1193011
X1652854Y1196751
X1660334Y1193011
X1660334Y1200491
X1660334Y1204232
X1652854Y1204232
X1656594Y1193011
X1645374Y1204232
X1649114Y1185531
X1652854Y1189271
X1649114Y1189271
X1649114Y1178051
X1645374Y1174310
X1645374Y1181791
X1660334Y1185531
X1660334Y1178051
X1660334Y1174310
X1656594Y1185531
X1649114Y1181791
X1652854Y1174310
X1652854Y1178051
X1656594Y1181791
X1652854Y1185531
X1652854Y1166830
X1652854Y1170570
X1645374Y1170570
X1660334Y1159350
X1645374Y1159350
X1660334Y1170570
X1660334Y1166830
X1652854Y1159350
X1645374Y1166830
X1649114Y1151870
X1660334Y1144389
X1660334Y1155610
X1660334Y1151869
X1656594Y1151869
X1652854Y1151869
X1649114Y1148129
X1652854Y1155610
X1649114Y1144389
X1652854Y1148129
X1645374Y1148129
X1645374Y1151869
X1645374Y1155610
X1645374Y1125688
X1649114Y1125688
X1652854Y1136909
X1649114Y1140649
X1649114Y1133169
X1660334Y1211712
X1660334Y1215452
X1660334Y1207972
X1645374Y1207972
X1649114Y1211712
X1664074Y1204232
X1665945Y1194881
X1667815Y1189271
X1664074Y1181791
X1667815Y1181791
X1667815Y1174310
X1664074Y1174310
X1664074Y1189271
X1664074Y1166830
X1667815Y1166830
X1667815Y1159350
X1664074Y1159350
X1667815Y1144389
X1664074Y1144389
X1664074Y1151869
X1667815Y1151869
X1606102Y1221062
X1617322Y1221062
X1665944Y1131299
X1665944Y1123818
X1662204Y1224803
X1665945Y1236023
X1665945Y1232283
X1665945Y1250984
X1662204Y1228543
X1662204Y1243503
X1665945Y1254724
X1662204Y1247243
X1621063Y1250984
X1602362Y1243503
X1613582Y1254724
X1658464Y1250984
X1643504Y1254724
X1628543Y1254724
X1602362Y1247243
X1658464Y1254724
X1639763Y1247243
X1617322Y1247243
X1650984Y1254724
X1647244Y1243503
X1628543Y1250984
X1609842Y1243503
X1617322Y1243503
X1606102Y1254724
X1654724Y1247243
X1613582Y1250984
X1621063Y1254724
X1624803Y1243503
X1647244Y1247243
X1606102Y1250984
X1650984Y1250984
X1643504Y1250984
X1632283Y1247243
X1636023Y1250984
X1624803Y1247243
X1639763Y1243503
X1654724Y1243503
X1636023Y1254724
X1632283Y1243503
X1609842Y1247243
X1591141Y1250984
X1583661Y1250984
X1594882Y1247243
X1579921Y1243503
X1572441Y1243503
X1576181Y1250984
X1598622Y1250984
X1594882Y1243503
X1598622Y1254724
X1587401Y1243503
X1587401Y1247243
X1591141Y1254724
X1576181Y1254724
X1579921Y1247243
X1583661Y1254724
X1572441Y1247243
X1591141Y1236023
X1576181Y1232283
X1587401Y1224803
X1587401Y1228543
X1598622Y1232283
X1579921Y1224803
X1572441Y1224803
X1602362Y1228543
X1613582Y1232283
X1639763Y1228543
X1650984Y1232283
X1647244Y1224803
X1650984Y1236023
X1636023Y1232283
X1624803Y1228543
X1643504Y1236023
X1632283Y1224803
X1658464Y1236023
X1654724Y1224803
X1643504Y1232283
X1583661Y1258465
X1576181Y1258465
X1591142Y1258465
X1598623Y1258465
X1606102Y1258465
X1613582Y1258465
X1621063Y1258465
X1628543Y1258465
X1636023Y1258465
X1643504Y1258465
X1650984Y1258465
X1658464Y1258465
X1665945Y1258465
X1665945Y1228543
X1665945Y1224803
X1650984Y1243503
X1650984Y1239763
X1650984Y1247243
X1662204Y1239763
X1658464Y1243503
X1658464Y1239763
X1654724Y1239763
X1662204Y1254724
X1662204Y1250984
X1658464Y1247243
X1654724Y1254724
X1654724Y1250984
X1650984Y1224803
X1650984Y1228543
X1662204Y1236023
X1662204Y1232283
X1658464Y1224803
X1654724Y1236023
X1658464Y1228543
X1654724Y1232283
X1647244Y1239763
X1643504Y1243503
X1636023Y1243503
X1639763Y1239763
X1643504Y1239763
X1636023Y1239763
X1643504Y1247243
X1647244Y1250984
X1647244Y1254724
X1639763Y1254724
X1639763Y1250984
X1636023Y1247243
X1643504Y1224803
X1643504Y1228543
X1647244Y1236023
X1647244Y1232283
X1639763Y1236023
X1639763Y1232283
X1636023Y1224803
X1636023Y1228543
X1617322Y1254724
X1617322Y1250984
X1617322Y1239763
X1628543Y1239763
X1632283Y1250984
X1632283Y1239763
X1628543Y1243503
X1628543Y1247243
X1624803Y1254724
X1624803Y1250984
X1624803Y1239763
X1621063Y1247243
X1621063Y1243503
X1621063Y1239763
X1632283Y1254724
X1617322Y1236023
X1617322Y1232283
X1624803Y1236023
X1632283Y1236023
X1632283Y1232283
X1624803Y1232283
X1628543Y1224803
X1628543Y1228543
X1621063Y1224803
X1621063Y1228543
X1602362Y1254724
X1602362Y1250984
X1602362Y1239763
X1613582Y1247243
X1613582Y1243503
X1613582Y1239763
X1609842Y1239763
X1606102Y1239763
X1606102Y1243503
X1606102Y1247243
X1609842Y1250984
X1609842Y1254724
X1602362Y1236023
X1602362Y1232283
X1606102Y1224803
X1606102Y1228543
X1613582Y1224803
X1613582Y1228543
X1609842Y1236023
X1609842Y1232283
X1587401Y1239763
X1591141Y1239763
X1594882Y1239763
X1594882Y1254724
X1594882Y1250984
X1591141Y1243503
X1591141Y1247243
X1587401Y1254724
X1587401Y1250984
X1598622Y1247243
X1598622Y1243503
X1598622Y1239763
X1587401Y1236023
X1587401Y1232283
X1591141Y1224803
X1591141Y1228543
X1594882Y1236023
X1594882Y1232283
X1598622Y1224803
X1598622Y1228543
X1576181Y1239763
X1572441Y1239763
X1583661Y1239763
X1579921Y1239763
X1579921Y1250984
X1579921Y1254724
X1583661Y1247243
X1583661Y1243503
X1576181Y1243503
X1576181Y1247243
X1572441Y1254724
X1572441Y1250984
X1572441Y1236023
X1572441Y1232283
X1576181Y1228543
X1576181Y1224803
X1579921Y1236023
X1579921Y1232283
X1583661Y1228543
X1583661Y1224803
X1665945Y1239763
X1665945Y1243503
X1665945Y1247243
X1636023Y1236023
X1609842Y1224803
X1621063Y1232283
X1658464Y1232283
X1639763Y1224803
X1647244Y1228543
X1654724Y1228543
X1602362Y1224803
X1606102Y1232283
X1609842Y1228543
X1613582Y1236023
X1621063Y1236023
X1606102Y1236023
X1628543Y1232283
X1617322Y1224803
X1628543Y1236023
X1624803Y1224803
X1617322Y1228543
X1632283Y1228543
X1576181Y1236023
X1594882Y1228543
X1583661Y1232283
X1579921Y1228543
X1583661Y1236023
X1591141Y1232283
X1598622Y1236023
X1572441Y1228543
X1594882Y1224803
X1581530Y1360099
X1589410Y1360099
X1589410Y1372385
X1589410Y1384297
X1581530Y1372385
X1581530Y1384297
X1589410Y1396583
X1581530Y1396583
X1589410Y1408495
X1581530Y1408495
X1577170Y1348187
X1569290Y1348187
X1577170Y1360099
X1569290Y1360099
X1569290Y1384297
X1569290Y1372385
X1577170Y1384297
X1577170Y1372385
X1569290Y1396583
X1577170Y1396583
X1569290Y1408495
X1577170Y1408495
X1581530Y1348187
X1589410Y1348187
X1665998Y1348187
X1665998Y1360099
X1665998Y1372385
X1665998Y1384297
X1665998Y1396583
X1665998Y1408495
X1641518Y1408495
X1629278Y1408495
X1658118Y1348187
X1653758Y1348187
X1645878Y1348187
X1658118Y1360099
X1653758Y1360099
X1645878Y1360099
X1658118Y1372385
X1658118Y1384297
X1653758Y1384297
X1653758Y1372385
X1645878Y1372385
X1645878Y1384297
X1658118Y1396583
X1653758Y1396583
X1645878Y1396583
X1658118Y1408495
X1653758Y1408495
X1645878Y1408495
X1621398Y1384297
X1621398Y1372385
X1617038Y1372385
X1617038Y1384297
X1621398Y1396583
X1621398Y1408495
X1633638Y1348187
X1641518Y1348187
X1629278Y1348187
X1633638Y1360099
X1641518Y1360099
X1629278Y1360099
X1633638Y1372385
X1633638Y1384297
X1641518Y1372385
X1641518Y1384297
X1629278Y1372385
X1629278Y1384297
X1633638Y1396583
X1641518Y1396583
X1629278Y1396583
X1633638Y1408495
X1609158Y1348187
X1609158Y1360099
X1609158Y1372385
X1609158Y1384297
X1621398Y1348187
X1617038Y1348187
X1621398Y1360099
X1617038Y1360099
X1739438Y1384297
X1727198Y1384297
X1727198Y1372385
X1731558Y1396583
X1739438Y1396583
X1727198Y1396583
X1731558Y1408495
X1739438Y1408495
X1727198Y1408495
X1719318Y1384297
X1719318Y1372385
X1714958Y1372385
X1714958Y1384297
X1719318Y1396583
X1714958Y1396583
X1719318Y1408495
X1714958Y1408495
X1731558Y1348187
X1739438Y1348187
X1727198Y1348187
X1731558Y1360099
X1739438Y1360099
X1727198Y1360099
X1731558Y1372385
X1731558Y1384297
X1739438Y1372385
X1694838Y1360099
X1707078Y1372385
X1707078Y1384297
X1702718Y1384297
X1702718Y1372385
X1694838Y1372385
X1694838Y1384297
X1707078Y1396583
X1702718Y1396583
X1694838Y1396583
X1707078Y1408495
X1702718Y1408495
X1694838Y1408495
X1719318Y1348187
X1714958Y1348187
X1719318Y1360099
X1714958Y1360099
X1682598Y1348187
X1690478Y1348187
X1678238Y1348187
X1682598Y1360099
X1690478Y1360099
X1678238Y1360099
X1682598Y1372385
X1682598Y1384297
X1690478Y1372385
X1690478Y1384297
X1678238Y1384297
X1678238Y1372385
X1682598Y1396583
X1690478Y1396583
X1678238Y1396583
X1682598Y1408495
X1690478Y1408495
X1678238Y1408495
X1707078Y1348187
X1702718Y1348187
X1694838Y1348187
X1707078Y1360099
X1702718Y1360099
X1670358Y1348187
X1670358Y1360099
X1670358Y1384297
X1670358Y1372385
X1670358Y1396583
X1670358Y1408495
X1688385Y1236023
X1669685Y1224803
X1688385Y1232283
X1677165Y1224803
X1684645Y1228543
X1684645Y1224803
X1695866Y1228543
X1692126Y1228543
X1680905Y1232283
X1680905Y1236023
X1680905Y1250984
X1695866Y1247243
X1669685Y1243503
X1673425Y1232283
X1669685Y1247243
X1669685Y1228543
X1680905Y1254724
X1692126Y1239763
X1688385Y1250984
X1677165Y1228543
X1688385Y1254724
X1695866Y1239763
X1673425Y1236023
X1677165Y1247243
X1673425Y1254724
X1684645Y1247243
X1692126Y1247243
X1677165Y1243503
X1684645Y1243503
X1673425Y1250984
X1682775Y1222932
X1673425Y1258465
X1680905Y1258465
X1688385Y1258465
X1699607Y1228543
X1699607Y1239762
X1699607Y1247243
X1680905Y1239763
X1677165Y1239763
X1673425Y1239763
X1669685Y1239763
X1680905Y1243503
X1680905Y1247243
X1677165Y1254724
X1677165Y1250984
X1673425Y1243503
X1673425Y1247243
X1669685Y1254724
X1669685Y1250984
X1677165Y1236023
X1677165Y1232283
X1680905Y1228543
X1680905Y1224803
X1669685Y1236023
X1669685Y1232283
X1673425Y1228543
X1673425Y1224803
X1695866Y1224803
X1692126Y1254724
X1688385Y1239763
X1684645Y1239763
X1695866Y1243503
X1692126Y1243503
X1688385Y1243503
X1688385Y1247243
X1692126Y1250984
X1695866Y1250984
X1684645Y1254724
X1684645Y1250984
X1695866Y1236023
X1692126Y1236023
X1692126Y1232283
X1695866Y1232283
X1684645Y1232283
X1684645Y1236023
X1688385Y1228543
X1688385Y1224803
X1692126Y1224803
X1682775Y1155610
X1693996Y1174310
X1693996Y1181791
X1686515Y1148129
X1682775Y1140649
X1693996Y1159350
X1697736Y1181791
X1682775Y1170570
X1697736Y1136909
X1697736Y1159350
X1697736Y1189271
X1682775Y1185531
X1686515Y1155610
X1686515Y1178051
X1697736Y1144389
X1693996Y1189271
X1682775Y1193011
X1682775Y1178051
X1693996Y1144389
X1686515Y1170570
X1697736Y1151870
X1686515Y1193011
X1686515Y1140649
X1686515Y1185531
X1693996Y1151870
X1682775Y1148129
X1693996Y1136909
X1697736Y1174310
X1679035Y1174310
X1675295Y1151869
X1679035Y1144389
X1675295Y1181791
X1675295Y1144389
X1675295Y1174310
X1679035Y1189271
X1679035Y1151869
X1675295Y1189271
X1679035Y1181791
X1673425Y1217322
X1669685Y1198621
X1677165Y1202362
X1669685Y1206102
X1673425Y1209842
X1695866Y1198621
X1669685Y1213582
X1688385Y1217322
X1673425Y1202362
X1677165Y1217322
X1695866Y1206102
X1688385Y1209842
X1692126Y1221062
X1677165Y1209842
X1692126Y1206102
X1695866Y1213582
X1684645Y1209842
X1695866Y1221062
X1684645Y1217322
X1688385Y1202362
X1692126Y1198621
X1692126Y1213582
X1684645Y1202362
X1675295Y1159350
X1675295Y1166830
X1679035Y1166830
X1688385Y1135039
X1688385Y1127558
X1692126Y1131299
X1692126Y1123818
X1684645Y1127558
X1695866Y1131299
X1684645Y1135039
X1695866Y1123818
X1673425Y1135039
X1677165Y1127559
X1669685Y1123818
X1673425Y1127559
X1669685Y1131299
X1677165Y1135039
X1699607Y1198621
X1699607Y1206102
X1699607Y1213582
X1699607Y1221062
X1699607Y1123819
X1699607Y1131300
X1673425Y1198621
X1677165Y1198621
X1680905Y1198621
X1680905Y1202362
X1669685Y1202362
X1673425Y1206102
X1677165Y1206102
X1680905Y1206102
X1684645Y1198621
X1688385Y1198621
X1684645Y1206102
X1688385Y1206102
X1692126Y1202362
X1695866Y1202362
X1669685Y1209842
X1680905Y1209842
X1680905Y1213582
X1677165Y1213582
X1673425Y1213582
X1669685Y1217322
X1669685Y1221062
X1673425Y1221062
X1677165Y1221062
X1680905Y1217322
X1680905Y1221062
X1684645Y1213582
X1688385Y1213582
X1692126Y1209842
X1695866Y1209842
X1684645Y1221062
X1688385Y1221062
X1692126Y1217322
X1695866Y1217322
X1669685Y1135039
X1695866Y1135039
X1692126Y1135039
X1680905Y1135039
X1684644Y1131299
X1688385Y1131299
X1692126Y1127558
X1695866Y1127558
X1688385Y1123818
X1684645Y1123818
X1677165Y1131299
X1680905Y1131299
X1680905Y1127558
X1673425Y1131299
X1669685Y1127558
X1677165Y1123818
X1680905Y1123818
X1673425Y1123818
X1671555Y1193011
X1675295Y1193011
X1669685Y1194881
X1671555Y1189271
X1675295Y1178051
X1675295Y1185531
X1671555Y1174310
X1671555Y1178051
X1671555Y1181791
X1671555Y1185531
X1671555Y1166830
X1671555Y1170570
X1675295Y1170570
X1671555Y1159350
X1671555Y1144389
X1671555Y1148129
X1671555Y1151869
X1671555Y1155610
X1675295Y1148129
X1675295Y1155610
X1671555Y1136909
X1671555Y1140649
X1675295Y1140649
X1679035Y1193011
X1690256Y1193011
X1690256Y1181791
X1690256Y1185531
X1690256Y1189271
X1686515Y1189271
X1686515Y1181791
X1682775Y1189271
X1679035Y1185531
X1682775Y1181791
X1679035Y1178051
X1682775Y1174310
X1690256Y1174310
X1686515Y1174310
X1690256Y1178051
X1690256Y1166830
X1690256Y1170570
X1686515Y1166830
X1679035Y1159350
X1682775Y1159350
X1690256Y1159350
X1686515Y1159350
X1679035Y1170570
X1682775Y1166830
X1690256Y1148129
X1690256Y1151869
X1686515Y1151869
X1690256Y1155610
X1686515Y1144389
X1679035Y1155610
X1682775Y1151869
X1679035Y1148129
X1682775Y1144389
X1690256Y1144389
X1679035Y1140649
X1682775Y1136909
X1690256Y1136909
X1686515Y1136909
X1690256Y1140649
X1680905Y1194881
X1697676Y1193011
X1693996Y1193011
X1693996Y1185531
X1697736Y1185531
X1693996Y1178051
X1697736Y1178051
X1697736Y1170570
X1697736Y1166830
X1693996Y1166830
X1693996Y1170570
X1693996Y1155610
X1697736Y1155610
X1693996Y1148129
X1697736Y1148129
X1693996Y1140649
X1697736Y1140649
X1700236Y1136909
X1688385Y1112598
X1677164Y1082677
X1695866Y1108858
X1669684Y1082676
X1695866Y1116338
X1695866Y1082676
X1677164Y1086417
X1684645Y1112598
X1673424Y1078936
X1688385Y1120078
X1688384Y1075196
X1688384Y1078936
X1680904Y1078936
X1680904Y1075196
X1684644Y1086417
X1684645Y1120078
X1669684Y1086416
X1684644Y1082677
X1673424Y1075196
X1692126Y1082676
X1692126Y1108858
X1692126Y1116338
X1669685Y1116338
X1695866Y1101377
X1688385Y1093897
X1680904Y1093897
X1684645Y1105117
X1692126Y1090157
X1673425Y1120078
X1688385Y1097637
X1677165Y1101376
X1680904Y1097637
X1673424Y1093897
X1673425Y1071455
X1680905Y1071455
X1688385Y1071455
X1699607Y1082677
X1699607Y1090158
X1699607Y1101378
X1699607Y1108859
X1699607Y1116339
X1695866Y1120078
X1692126Y1120078
X1695866Y1112598
X1692126Y1112598
X1688385Y1116338
X1684645Y1116338
X1688385Y1108858
X1684645Y1108858
X1695866Y1105117
X1692126Y1105117
X1680905Y1120078
X1680905Y1112598
X1677165Y1116338
X1680905Y1116338
X1680904Y1108858
X1677164Y1108857
X1669685Y1120078
X1669685Y1112598
X1673425Y1116338
X1673425Y1108858
X1669685Y1108858
X1688386Y1105117
X1680905Y1105117
X1673425Y1105117
X1692126Y1097637
X1695866Y1097637
X1695866Y1093897
X1692126Y1093897
X1688385Y1101377
X1684645Y1097637
X1684645Y1093897
X1695866Y1078936
X1688385Y1090157
X1684644Y1090157
X1688386Y1086417
X1692126Y1086417
X1695866Y1086417
X1688385Y1082677
X1684646Y1078936
X1692126Y1078936
X1692126Y1075196
X1684646Y1075196
X1673425Y1101377
X1680905Y1101377
X1677165Y1097637
X1669685Y1097637
X1677165Y1093897
X1669685Y1093897
X1680904Y1090157
X1677164Y1090157
X1673424Y1090157
X1669684Y1090157
X1680905Y1086417
X1673425Y1086417
X1673424Y1082677
X1680904Y1082677
X1669686Y1078936
X1677166Y1078936
X1677166Y1075196
X1669685Y1075196
X1669685Y1101376
X1673424Y1097637
X1677165Y1105117
X1684645Y1101377
X1669685Y1105117
X1695866Y1090157
X1677165Y1112598
X1677165Y1120078
X1673425Y1112598
X1692126Y1101377
X1793483Y0444629
X1796283Y0444629
X1793483Y0437543
X1793483Y0433999
X1793483Y0441086
X1796283Y0437543
X1796283Y0433999
X1796283Y0441086
X1813087Y2087512
X1852032Y2052576
X1859032Y2052576
X1812366Y2054109
X1822066Y2054109
X1812366Y2063809
X1825427Y2104853
X1833727Y2104853
X1833649Y2057507
X1829349Y2072324
X1837649Y2072324
X1832995Y2065122
X1841295Y2065122
X1835862Y2121040
X1851762Y2121040
X1860338Y2071384
X1840875Y2083215
X1830872Y2083503
X1854559Y2077931
X1864547Y2185020
X1833506Y2185252
X1806706Y2180760
X1815006Y2180760
X1809078Y2165771
X1817378Y2165771
X1847678Y2185118
X1855978Y2185118
X1846496Y2170548
X1854796Y2170548
X1867072Y2174962
X1860234Y2157701
X1896403Y2185019
X1874932Y2180585
X1882111Y2179074
X1876697Y2183170
X1893087Y2168011
X1886699Y2183170
X1959428Y2151583
X1936377Y2163810
X1946077Y2163810
X1959428Y2161283
X1884535Y2155415
X1892835Y2155415
X1894572Y2178531
X1902872Y2178531
X1913710Y2151829
X1922010Y2151829
X1923438Y2182647
X1931738Y2182647
X1909250Y2158451
X1917550Y2158451
X1921855Y2172152
X1930155Y2172152
X1882972Y2174962
X1936212Y2173508
X1881852Y2196600
X1924735Y2178131
X1935195Y2155918
X1951095Y2155918
X1941040Y2070124
X1936295Y2074343
X1876497Y2070684
X1898342Y2062143
X1905944Y2055424
X1870505Y2064156
X1878805Y2064156
X1874505Y2078973
X1882805Y2078973
X1886128Y2075919
X1893118Y2054585
X1890039Y2066092
X1905939Y2066092
X1901295Y2072745
X1917195Y2072745
X1969128Y2151583
X1969128Y2161283
M00
X0056248Y1796941
X0046248Y1796941
X0046248Y1806941
X0056248Y1806941
X0046248Y1750941
X0046248Y1760941
X0056248Y1750941
X0056248Y1760941
X0046348Y1737941
X0046348Y1727941
X0056348Y1737941
X0056348Y1727941
X0046348Y1783941
X0046348Y1773941
X0056348Y1783941
X0056348Y1773941
X0308348Y1806941
X0318348Y1806941
X0318348Y1796941
X0308348Y1796941
X0308448Y1773941
X0318448Y1773941
X0318448Y1783941
X0308448Y1783941
X0308448Y1727941
X0318448Y1727941
X0318448Y1737941
X0308448Y1737941
X0343112Y1761624
X0333112Y1761624
X0333112Y1751624
X0343112Y1751624
X0343212Y1807624
X0333212Y1807624
X0333212Y1797624
X0343212Y1797624
X0318448Y1760941
X0318448Y1750941
X0308448Y1760941
X0308448Y1750941
X0333212Y1774624
X0333212Y1784624
X0343212Y1774624
X0343212Y1784624
X0333286Y1728583
X0333286Y1738583
X0343286Y1728583
X0343286Y1738583
X0629475Y1808845
X0619475Y1808845
X0619475Y1798845
X0629475Y1798845
X0629861Y1761765
X0619861Y1761765
X0619861Y1751765
X0629861Y1751765
X0630083Y1728286
X0620083Y1728286
X0620083Y1738286
X0630083Y1738286
X0629711Y1775438
X0619711Y1775438
X0619711Y1785438
X0629711Y1785438
X0595312Y1751624
X0605312Y1751624
X0605312Y1761624
X0595312Y1761624
X0595312Y1797624
X0605312Y1797624
X0605312Y1807624
X0595312Y1807624
X0605312Y1784624
X0605312Y1774624
X0595312Y1784624
X0595312Y1774624
X0605386Y1738583
X0605386Y1728583
X0595386Y1738583
X0595386Y1728583
X0881911Y1751765
X0891911Y1751765
X0891911Y1761765
X0881911Y1761765
X0917166Y1810435
X0907166Y1810435
X0907166Y1800435
X0917166Y1800435
X0917279Y1728990
X0907279Y1728990
X0907279Y1738990
X0917279Y1738990
X0881761Y1785438
X0891761Y1785438
X0891761Y1775438
X0881761Y1775438
X0917073Y1776014
X0907073Y1776014
X0907073Y1786014
X0917073Y1786014
X0882183Y1738286
X0892183Y1738286
X0892183Y1728286
X0882183Y1728286
X0881525Y1798845
X0891525Y1798845
X0891525Y1808845
X0881525Y1808845
X0917163Y1762566
X0907163Y1762566
X0907163Y1752566
X0917163Y1752566
X1169216Y1800435
X1179216Y1800435
X1179216Y1810435
X1169216Y1810435
X1169123Y1786014
X1179123Y1786014
X1179123Y1776014
X1169123Y1776014
X1169263Y1752566
X1179263Y1752566
X1179263Y1762566
X1169263Y1762566
X1169329Y1738990
X1179329Y1738990
X1179329Y1728990
X1169329Y1728990
M00
X0015972Y0003000
X0003704Y0005374
X0026956Y0004469
X0018000Y0090000
X0011011Y0079720
X0012786Y0087903
X0007271Y0070981
X0055921Y0095236
X0055871Y0099961
X0035207Y0106561
X0066856Y0107649
X0066856Y0104249
X0015143Y0115581
X0010131Y0115473
X0010292Y0094236
X0051550Y0090615
X0014264Y0094236
X0045988Y0090512
X0064829Y0092874
X0035048Y0103411
X0035442Y0097667
X0022439Y0102495
X0008000Y0102500
X0018298Y0102141
X0026588Y0097667
X0008786Y0088425
X0032350Y0063562
X0032350Y0059562
X0028442Y0055340
X0032350Y0067562
X0064785Y0077393
X0064785Y0074793
X0064785Y0085193
X0064785Y0082593
X0064785Y0079993
X0028388Y0118342
X0028388Y0121742
X0035688Y0114655
X0035688Y0111255
X0012652Y0116894
X0016728Y0107910
X0009364Y0107501
X0012601Y0092110
X0014751Y0062381
X0020408Y0055296
X0020408Y0051296
X0003017Y0104773
X0003017Y0084773
X0003017Y0064773
X0003017Y0044773
X0003017Y0024773
X0022439Y0106495
X0025988Y0116497
X0030788Y0116497
X0033288Y0116497
X0033288Y0109410
X0035638Y0053597
X0024316Y0059527
X0024316Y0063527
X0024316Y0067527
X0028317Y0044773
X0028317Y0024773
X0064098Y0116496
X0064098Y0109410
X0064098Y0102323
X0055964Y0103037
X0056098Y0116496
X0056098Y0109410
X0055638Y0053597
X0049236Y0121658
X0037988Y0116496
X0037988Y0102323
X0046240Y0116496
X0045988Y0102323
X0046240Y0109410
X0037988Y0109410
X0046450Y0085584
X0048364Y0092473
X0046450Y0080384
X0046450Y0075184
X0046450Y0077784
X0046450Y0082984
X0022335Y0166721
X0021909Y0153263
X0017313Y0166937
X0012247Y0166341
X0016909Y0153263
X0032507Y0180517
X0016709Y0175943
X0026565Y0177448
X0015948Y0141267
X0011999Y0141415
X0019855Y0133000
X0011442Y0132719
X0014996Y0133034
X0065189Y0215713
X0054733Y0210478
X0054733Y0207978
X0054733Y0215478
X0054733Y0212978
X0065189Y0208213
X0065189Y0213213
X0065189Y0210713
X0019572Y0216970
X0016859Y0216385
X0013059Y0218085
X0010259Y0218085
X0019572Y0221970
X0019572Y0219470
X0048476Y0180812
X0010966Y0159073
X0010966Y0162073
X0019855Y0141362
X0009082Y0135789
X0027421Y0206806
X0029585Y0201748
X0028148Y0210509
X0025648Y0210509
X0032585Y0202048
X0029921Y0206806
X0032585Y0199248
X0029585Y0199248
X0033067Y0195176
X0025567Y0195176
X0028067Y0195176
X0030567Y0195176
X0022935Y0159073
X0022935Y0162073
X0063878Y0162368
X0066478Y0162368
X0035688Y0128828
X0028388Y0132515
X0035688Y0125428
X0028388Y0135915
X0016568Y0206838
X0019068Y0206838
X0010380Y0203393
X0012880Y0203393
X0015139Y0201683
X0010520Y0195176
X0013020Y0195176
X0018320Y0195176
X0015520Y0195176
X0015139Y0198883
X0012709Y0175777
X0010966Y0152873
X0010966Y0155873
X0013615Y0153263
X0015184Y0144728
X0019184Y0144728
X0009057Y0138939
X0003017Y0204773
X0003017Y0184773
X0003017Y0164773
X0003017Y0144773
X0003017Y0124773
X0034520Y0213539
X0020709Y0175777
X0026201Y0151651
X0029201Y0151651
X0023184Y0144728
X0025988Y0137757
X0030788Y0137757
X0025988Y0130670
X0030788Y0130670
X0033288Y0130670
X0025988Y0123584
X0033288Y0123583
X0030788Y0123584
X0064098Y0130670
X0064098Y0123583
X0056098Y0130670
X0056098Y0123583
X0045984Y0163264
X0037988Y0137756
X0052437Y0137756
X0046932Y0137756
X0037988Y0123583
X0037988Y0130670
X0046931Y0130670
X0064098Y0137756
X0025549Y0256394
X0015586Y0249108
X0018206Y0244571
X0015586Y0269108
X0018206Y0264571
X0025549Y0276394
X0014807Y0282181
X0037117Y0279991
X0029116Y0281129
X0008335Y0280663
X0022599Y0228646
X0066956Y0270026
X0066956Y0267526
X0008970Y0254871
X0058062Y0264180
X0060562Y0264180
X0057987Y0258880
X0031595Y0227824
X0036185Y0230117
X0027340Y0230556
X0013715Y0259381
X0015499Y0288542
X0033902Y0244297
X0031682Y0266874
X0031682Y0246874
X0021556Y0232971
X0026629Y0295619
X0026325Y0262078
X0023844Y0239299
X0019638Y0226320
X0034845Y0291756
X0007036Y0272371
X0032201Y0238714
X0007036Y0268371
X0019075Y0278429
X0009745Y0245784
X0018564Y0238589
X0003017Y0304773
X0003017Y0284773
X0003017Y0264773
X0003017Y0244773
X0003017Y0224773
X0037284Y0285272
X0023479Y0295619
X0021386Y0273198
X0028740Y0267292
X0021449Y0253198
X0028740Y0247292
X0027966Y0238689
X0021530Y0236121
X0036201Y0238714
X0060779Y0293796
X0068793Y0288190
X0066293Y0288190
X0068793Y0285690
X0066293Y0285690
X0058279Y0293796
X0068841Y0248891
X0054733Y0226226
X0054733Y0223726
X0054733Y0228726
X0054733Y0231226
X0068896Y0226141
X0065189Y0226461
X0065189Y0223661
X0065189Y0231461
X0065189Y0228961
X0003221Y0324773
X0017964Y0409298
X0017964Y0389298
X0017964Y0369298
X0017964Y0349298
X0010971Y0333342
X0041643Y0464919
X0057857Y0446071
X0065737Y0445603
X0063154Y0462371
X0049643Y0464419
X0058224Y0465004
X0067670Y0464818
X0048596Y0451419
X0044563Y0482165
X0062224Y0473045
X0045256Y0495993
X0035650Y0495982
X0049643Y0472905
X0066403Y0492987
X0062700Y0493714
X0066403Y0495487
X0062700Y0491214
X0035650Y0491982
X0041643Y0473419
X0043804Y0500202
X0043948Y0492108
X0040009Y0481467
X0048643Y0442919
X0055124Y0475825
X0056824Y0482425
X0056239Y0485138
X0053739Y0485138
X0055124Y0478625
X0051239Y0485138
X0048390Y0485128
X0045643Y0472905
X0056667Y0462339
X0054167Y0462339
X0054167Y0459839
X0056667Y0459839
X0056667Y0457339
X0054167Y0457339
X0044742Y0517401
X0042242Y0517401
X0039742Y0517401
X0044801Y0504825
X0042301Y0504825
X0039801Y0504825
X0066371Y0484634
X0066371Y0482134
X0053643Y0472905
X0035650Y0483982
X0035650Y0478982
X0017964Y0469298
X0017964Y0449298
X0017964Y0429298
X0068497Y0450201
X0068619Y0447269
X0017964Y0509298
X0017964Y0489298
X0035650Y0499982
X0035650Y0487982
X0068202Y0522129
X0060233Y0521804
X0059252Y0516979
X0064252Y0516979
X0061752Y0516979
X0059550Y0504699
X0062050Y0504699
X0064550Y0504699
X0059670Y0500086
X0068236Y0519458
X0059522Y0448874
X0058224Y0473045
X0057759Y0437508
X0054936Y0449352
X0048596Y0458466
X0042690Y0451466
X0066224Y0473045
X0061759Y0437508
X0065759Y0437508
X0040362Y0610548
X0036306Y0622285
X0036494Y0616905
X0067684Y0605637
X0025819Y0527726
X0063684Y0605443
X0063684Y0597130
X0059684Y0605443
X0063859Y0590801
X0053972Y0610562
X0053972Y0607762
X0051172Y0610562
X0048372Y0610562
X0045572Y0610562
X0045572Y0607762
X0048372Y0607762
X0051172Y0607762
X0048200Y0591215
X0045400Y0591215
X0051000Y0591215
X0048200Y0581222
X0045400Y0581222
X0051000Y0581222
X0046643Y0563194
X0043843Y0563194
X0043843Y0571194
X0046643Y0571194
X0068188Y0548358
X0061630Y0541895
X0064130Y0544895
X0064130Y0541895
X0056572Y0542231
X0061330Y0544895
X0068202Y0540377
X0068202Y0545377
X0068202Y0542877
X0043843Y0555194
X0052869Y0540458
X0046643Y0555194
X0056572Y0539731
X0068202Y0537877
X0052869Y0537958
X0034732Y0534909
X0025819Y0544726
X0034359Y0541135
X0034448Y0552726
X0034425Y0546553
X0030177Y0534211
X0027686Y0621311
X0067684Y0597232
X0064408Y0582747
X0025819Y0548726
X0061854Y0620653
X0061854Y0617853
X0030123Y0611071
X0038358Y0531948
X0046408Y0531882
X0045293Y0525369
X0043908Y0531882
X0041408Y0531882
X0046993Y0529169
X0045293Y0522569
X0017964Y0609298
X0017964Y0589298
X0017964Y0569298
X0017964Y0549298
X0017964Y0529298
X0034254Y0611091
X0032452Y0591215
X0029652Y0591215
X0035252Y0591215
X0035252Y0581222
X0029652Y0581222
X0032452Y0581222
X0025819Y0540726
X0025819Y0552726
X0025819Y0536726
X0025819Y0531726
X0036843Y0571194
X0039643Y0571194
X0036843Y0563194
X0039643Y0563194
X0049839Y0546830
X0036843Y0555194
X0039643Y0555194
X0062789Y0608311
X0064408Y0572975
X0067622Y0572842
X0068202Y0529629
X0068202Y0524629
X0068202Y0527129
X0061695Y0527449
X0056540Y0528878
X0056540Y0531378
X0060233Y0524304
X0064495Y0527449
X0036575Y0627713
X0047179Y0633736
X0049192Y0628078
X0058181Y0627908
X0042172Y0633716
X0036692Y0633724
X0054192Y0633473
X0064692Y0642184
X0027686Y0625311
X0037365Y0699082
X0040165Y0699082
X0034565Y0699082
X0035293Y0662952
X0037847Y0662910
X0035250Y0671508
X0037804Y0671508
X0036910Y0682108
X0039549Y0682108
X0027686Y0629311
X0066530Y0625013
X0028818Y0682139
X0017964Y0709298
X0017964Y0689298
X0017964Y0669298
X0017964Y0649298
X0017964Y0629298
X0030414Y0671508
X0027854Y0671553
X0025818Y0682139
X0027625Y0663094
X0030369Y0663048
X0036692Y0641817
X0029451Y0633560
X0042192Y0641817
X0055307Y0688473
X0053129Y0627948
X0055318Y0629362
X0066510Y0628242
X0058949Y0821018
X0017964Y0789298
X0017964Y0769298
X0017964Y0749298
X0017964Y0729298
X0017964Y0809298
X0069049Y0847718
X0053549Y0843118
X0068649Y0827218
X0068598Y0859415
X0047264Y0919649
X0065549Y0850718
X0048429Y0916430
X0052077Y0905295
X0063930Y0874694
X0063969Y0869475
X0059962Y0910251
X0064632Y0901500
X0068100Y0910122
X0056049Y0827218
X0068778Y0873821
X0046049Y0837718
X0052349Y0837718
X0049249Y0837718
X0047949Y0822718
X0051449Y0822718
X0064649Y0826818
X0060849Y0826818
X0060249Y0840418
X0064849Y0840418
X0049265Y0886660
X0026596Y0874520
X0026844Y0920354
X0017964Y0909298
X0017964Y0889298
X0017964Y0869298
X0017964Y0849298
X0017964Y0829298
X0052922Y0900295
X0063303Y0912835
X0067461Y0912983
X0064175Y0897500
X0067316Y0865869
X0066342Y0880067
X0053197Y1017759
X0053197Y1014205
X0048704Y1017982
X0038197Y1017759
X0044197Y1017759
X0041197Y1014205
X0047197Y1014205
X0035197Y1014205
X0026197Y1017759
X0032197Y1017759
X0029197Y1014205
X0020197Y1017759
X0020197Y1014205
X0014197Y1017759
X0014197Y1014205
X0038823Y1009273
X0044999Y1009510
X0050541Y1009589
X0042470Y1006738
X0048683Y1006510
X0026155Y1009985
X0032093Y1009748
X0024456Y1006401
X0030479Y1006509
X0036529Y1006321
X0020216Y1009748
X0014357Y1009906
X0017033Y1006819
X0047916Y0947622
X0057178Y0981386
X0024132Y0958151
X0025371Y0980696
X0003035Y1018036
X0003035Y0998036
X0003035Y0978036
X0017964Y0949298
X0009554Y0961954
X0017964Y0929298
X0047314Y1072228
X0062109Y1091656
X0062109Y1079656
X0041172Y1079064
X0062109Y1084656
X0061588Y1074481
X0039659Y1114800
X0042259Y1114800
X0044859Y1114800
X0047559Y1114800
X0032574Y1121333
X0029874Y1121333
X0027274Y1121333
X0024674Y1121333
X0024674Y1111633
X0027274Y1111633
X0029874Y1111633
X0032574Y1111633
X0047559Y1105100
X0044859Y1105100
X0042259Y1105100
X0039659Y1105100
X0021321Y1101335
X0026521Y1101335
X0029121Y1101335
X0023921Y1101335
X0023921Y1098769
X0029121Y1098769
X0026521Y1098769
X0021321Y1098769
X0055699Y1072761
X0062109Y1087656
X0046166Y1093757
X0020806Y1080178
X0020806Y1082678
X0028606Y1080178
X0023406Y1080178
X0026006Y1080178
X0026006Y1082678
X0023406Y1082678
X0028606Y1082678
X0043889Y1065101
X0038689Y1065101
X0041289Y1065101
X0041289Y1062601
X0038689Y1062601
X0043889Y1062601
X0028996Y1063029
X0023796Y1063029
X0026396Y1063029
X0026396Y1065529
X0023796Y1065529
X0028996Y1065529
X0033425Y1075663
X0035925Y1075663
X0036089Y1065101
X0036089Y1062601
X0021196Y1063029
X0021196Y1065529
X0006108Y1065318
X0006108Y1070611
X0006161Y1075991
X0006053Y1081305
X0006055Y1086546
X0006059Y1091964
X0003035Y1118036
X0003035Y1098036
X0003035Y1078036
X0003035Y1058036
X0003035Y1038036
X0016652Y1111633
X0008852Y1111633
X0011452Y1111633
X0014152Y1111633
X0008952Y1121333
X0016752Y1121333
X0011552Y1121333
X0014252Y1121333
X0038216Y1093757
X0044365Y1086404
X0038200Y1089721
X0050366Y1082388
X0050366Y1086981
X0064381Y1114800
X0059081Y1114800
X0056481Y1114800
X0061681Y1114800
X0064281Y1105100
X0061581Y1105100
X0056381Y1105100
X0058981Y1105100
X0055004Y1086937
X0055049Y1082343
X0068245Y1212054
X0023709Y1138705
X0021209Y1138705
X0051047Y1133688
X0048547Y1133688
X0021974Y1130333
X0024674Y1130333
X0048585Y1123867
X0051023Y1201416
X0031631Y1198651
X0055188Y1205179
X0053479Y1216256
X0055596Y1210466
X0048842Y1211109
X0063094Y1207604
X0060269Y1198820
X0016806Y1138705
X0014306Y1138705
X0057897Y1133688
X0055397Y1133688
X0003035Y1198036
X0003035Y1178036
X0003035Y1158036
X0003035Y1138036
X0016752Y1130333
X0014252Y1130333
X0030934Y1207111
X0030934Y1209911
X0030934Y1212711
X0027934Y1207111
X0027934Y1209911
X0027934Y1212711
X0034314Y1215403
X0030934Y1215511
X0027934Y1215511
X0030410Y1220997
X0030410Y1218497
X0030934Y1204311
X0027934Y1204311
X0051197Y1218206
X0049638Y1203884
X0049500Y1199066
X0044960Y1190619
X0065940Y1209382
X0058250Y1220896
X0057218Y1123867
X0058443Y1272257
X0048198Y1251555
X0043198Y1251555
X0045698Y1251555
X0048198Y1254055
X0045698Y1254055
X0043198Y1254055
X0030410Y1239197
X0030410Y1241697
X0003035Y1318036
X0003035Y1298036
X0003035Y1278036
X0003035Y1258036
X0003035Y1238036
X0030410Y1225397
X0030410Y1227897
X0030410Y1232297
X0030410Y1234797
X0039452Y1250932
X0058250Y1223396
X0058250Y1234696
X0058250Y1237196
X0058250Y1230296
X0058250Y1227796
X0047621Y1343672
X0003035Y1418036
X0003035Y1398036
X0003035Y1378036
X0003035Y1358036
X0003035Y1338036
X0029880Y1441702
X0012599Y1438143
X0019859Y1520657
X0033189Y1501373
X0039095Y1501361
X0060227Y1514751
X0048089Y1501387
X0054843Y1501625
X0019745Y1508846
X0010089Y1494254
X0015889Y1494254
X0039225Y1464845
X0035825Y1464845
X0006489Y1501334
X0016304Y1468196
X0023603Y1449735
X0029860Y1438552
X0012327Y1519202
X0022284Y1464612
X0020079Y1429347
X0057185Y1480808
X0057144Y1491047
X0040996Y1467703
X0033536Y1467485
X0008042Y1522199
X0048079Y1521641
X0032079Y1517641
X0032079Y1521641
X0040195Y1511279
X0048195Y1511279
X0044195Y1511279
X0032195Y1511279
X0025674Y1486291
X0021544Y1489648
X0019365Y1494298
X0021544Y1479662
X0013606Y1476707
X0006690Y1496782
X0003035Y1498036
X0003035Y1478036
X0003035Y1458036
X0003035Y1438036
X0060303Y1534436
X0060277Y1528395
X0018879Y1534334
X0064747Y1555890
X0040951Y1555932
X0047074Y1555923
X0026231Y1554167
X0010367Y1553080
X0065478Y1541980
X0055862Y1541791
X0019735Y1530499
X0007983Y1525635
X0007983Y1529035
X0060747Y1555890
X0006951Y1538547
X0022381Y1554152
X0055264Y1583484
X0058064Y1583484
X0060864Y1583484
X0060554Y1615152
X0056114Y1556061
X0052048Y1556062
X0035850Y1556096
X0011995Y1535134
X0007922Y1532494
X0018409Y1554202
X0014375Y1553121
X0048079Y1529641
X0039237Y1532096
X0048079Y1525641
X0031237Y1532096
X0032079Y1525641
X0035237Y1532096
X0006567Y1554215
X0003035Y1578036
X0003035Y1558036
X0003035Y1538036
X0068743Y1583498
X0060554Y1612002
X0012000Y1644980
X0003017Y1639466
X0032000Y1644980
X0052000Y1644980
X0066291Y1633801
X0083689Y1624736
X0078291Y1625743
X0071910Y1625009
X0070291Y1633801
X0078291Y1633801
X0082291Y1633801
X0072000Y1644980
X0092000Y1644980
X0112000Y1644980
X0132000Y1644980
X0152000Y1644980
X0086291Y1633801
X0074291Y1633801
X0074909Y1593009
X0069816Y1592527
X0093496Y1547768
X0082433Y1580590
X0076005Y1580680
X0107669Y1589522
X0116330Y1587960
X0107669Y1574167
X0116330Y1572606
X0116330Y1578498
X0107669Y1578898
X0116330Y1567875
X0107669Y1568275
X0107669Y1558813
X0116330Y1563144
X0107669Y1563544
X0107669Y1614338
X0116330Y1618669
X0116330Y1613938
X0107669Y1604876
X0116330Y1603315
X0116330Y1598584
X0107669Y1598984
X0116330Y1609207
X0107669Y1609607
X0116330Y1593853
X0107669Y1594253
X0116330Y1583229
X0107669Y1583629
X0124992Y1568275
X0133653Y1572606
X0133653Y1578498
X0124992Y1578898
X0124992Y1574167
X0133653Y1567875
X0133653Y1563144
X0124992Y1563544
X0124992Y1558813
X0133653Y1618669
X0133653Y1613938
X0124992Y1614338
X0133653Y1603315
X0133653Y1598584
X0133653Y1609207
X0124992Y1598984
X0124992Y1604876
X0124992Y1609607
X0133653Y1583229
X0124992Y1583629
X0133653Y1587960
X0133653Y1593853
X0124992Y1594253
X0124992Y1589522
X0142315Y1568275
X0142315Y1578898
X0142315Y1574167
X0142315Y1563544
X0142315Y1558813
X0142315Y1614338
X0142315Y1598984
X0142315Y1604876
X0142315Y1609607
X0142315Y1583629
X0142315Y1594253
X0142315Y1589522
X0159637Y1574167
X0159637Y1568275
X0150976Y1572606
X0150976Y1578498
X0150976Y1567875
X0159637Y1578898
X0150976Y1563144
X0159637Y1563544
X0159637Y1558813
X0159637Y1614338
X0150976Y1618669
X0150976Y1613938
X0159637Y1598984
X0159637Y1604876
X0159637Y1609607
X0150976Y1603315
X0150976Y1598584
X0150976Y1609207
X0159637Y1594253
X0159637Y1589522
X0159637Y1583629
X0150976Y1587960
X0150976Y1593853
X0150976Y1583229
X0168299Y1563144
X0168299Y1618669
X0168299Y1613938
X0168299Y1603315
X0168299Y1598584
X0168299Y1609207
X0168299Y1587960
X0168299Y1593853
X0168299Y1583229
X0168299Y1567875
X0168299Y1572606
X0168299Y1578498
X0087000Y1597855
X0116330Y1460782
X0107669Y1461182
X0116330Y1465513
X0107669Y1465913
X0107669Y1456451
X0116330Y1516307
X0107669Y1507245
X0107669Y1511976
X0116330Y1511576
X0107669Y1502514
X0116330Y1500952
X0116330Y1506845
X0107669Y1491890
X0116330Y1496221
X0107669Y1496621
X0107669Y1487159
X0116330Y1485598
X0116330Y1491490
X0107669Y1471805
X0116330Y1470244
X0116330Y1476136
X0107669Y1476536
X0116330Y1480867
X0107669Y1481267
X0133653Y1480867
X0133653Y1470244
X0133653Y1476136
X0124992Y1481267
X0124992Y1476536
X0124992Y1471805
X0133653Y1460782
X0133653Y1465513
X0124992Y1461182
X0124992Y1456451
X0124992Y1465913
X0133653Y1516307
X0124992Y1502514
X0124992Y1507245
X0124992Y1511976
X0133653Y1511576
X0133653Y1500952
X0133653Y1506845
X0133653Y1485598
X0133653Y1491490
X0124992Y1496621
X0124992Y1491890
X0124992Y1487159
X0133653Y1496221
X0142315Y1465913
X0142315Y1461182
X0142315Y1456451
X0142315Y1511976
X0142315Y1502514
X0142315Y1507245
X0142315Y1496621
X0142315Y1491890
X0142315Y1487159
X0142315Y1481267
X0142315Y1476536
X0142315Y1471805
X0159637Y1491890
X0159637Y1481267
X0159637Y1476536
X0159637Y1471805
X0150976Y1480867
X0150976Y1470244
X0150976Y1476136
X0159637Y1456451
X0159637Y1465913
X0150976Y1460782
X0150976Y1465513
X0159637Y1461182
X0150976Y1516307
X0150976Y1506845
X0159637Y1511976
X0159637Y1502514
X0159637Y1507245
X0150976Y1511576
X0150976Y1500952
X0159637Y1487159
X0150976Y1496221
X0150976Y1485598
X0150976Y1491490
X0159637Y1496621
X0168299Y1516307
X0168299Y1511576
X0168299Y1500952
X0168299Y1506845
X0168299Y1496221
X0168299Y1485598
X0168299Y1491490
X0168299Y1480867
X0168299Y1470244
X0168299Y1476136
X0168299Y1460782
X0168299Y1465513
X0152952Y1408495
X0103992Y1396583
X0100592Y1360099
X0149552Y1396583
X0128472Y1396583
X0137312Y1372385
X0112832Y1372385
X0152952Y1396583
X0149552Y1408495
X0103992Y1408495
X0091752Y1384297
X0116232Y1384297
X0116232Y1372385
X0128472Y1348187
X0125072Y1396583
X0088352Y1384297
X0161792Y1372385
X0149552Y1348187
X0103992Y1348187
X0137312Y1384297
X0152952Y1360099
X0079512Y1348187
X0165192Y1384297
X0088352Y1372385
X0125072Y1360099
X0100592Y1348187
X0103992Y1360099
X0112832Y1384297
X0100592Y1408495
X0076112Y1348187
X0165192Y1372385
X0140712Y1384297
X0079512Y1360099
X0091752Y1372385
X0128472Y1360099
X0140712Y1372385
X0076112Y1360099
X0152952Y1348187
X0128472Y1408495
X0125072Y1408495
X0161792Y1384297
X0125072Y1348187
X0149552Y1360099
X0100592Y1396583
X0140712Y1360099
X0137312Y1360099
X0103992Y1384297
X0088352Y1408495
X0091752Y1408495
X0088352Y1360099
X0091752Y1360099
X0079512Y1384297
X0161792Y1396583
X0076112Y1384297
X0165192Y1396583
X0161792Y1348187
X0112832Y1348187
X0165192Y1348187
X0137312Y1348187
X0137312Y1396583
X0140712Y1396583
X0152952Y1372385
X0112832Y1396583
X0091752Y1348187
X0103992Y1372385
X0088352Y1396583
X0088352Y1348187
X0116232Y1396583
X0116232Y1348187
X0076112Y1372385
X0128472Y1372385
X0140712Y1348187
X0149552Y1372385
X0100592Y1372385
X0091752Y1396583
X0125072Y1372385
X0079512Y1372385
X0116232Y1360099
X0116232Y1408495
X0112832Y1408495
X0128472Y1384297
X0125072Y1384297
X0112832Y1360099
X0100592Y1384297
X0165970Y1399079
X0153730Y1399079
X0161014Y1399079
X0165970Y1405999
X0165970Y1410991
X0153730Y1410991
X0153730Y1405999
X0161014Y1405999
X0161014Y1410991
X0165970Y1350683
X0165970Y1345691
X0153730Y1350683
X0153730Y1345691
X0161014Y1350683
X0161014Y1345691
X0165970Y1357603
X0165970Y1362595
X0153730Y1357603
X0153730Y1362595
X0161014Y1357603
X0161014Y1362595
X0165970Y1369889
X0165970Y1381801
X0165970Y1374881
X0153730Y1374881
X0153730Y1381801
X0153730Y1369889
X0161014Y1374881
X0161014Y1369889
X0161014Y1381801
X0165970Y1386793
X0165970Y1394087
X0153730Y1386793
X0153730Y1394087
X0161014Y1386793
X0161014Y1394087
X0117010Y1350683
X0117010Y1345691
X0112054Y1350683
X0112054Y1345691
X0104770Y1345691
X0104770Y1350683
X0117010Y1357603
X0117010Y1362595
X0112054Y1357603
X0112054Y1362595
X0104770Y1357603
X0104770Y1362595
X0129250Y1345691
X0129250Y1350683
X0124294Y1345691
X0124294Y1350683
X0129250Y1362595
X0129250Y1357603
X0124294Y1357603
X0124294Y1362595
X0148774Y1345691
X0148774Y1350683
X0136534Y1345691
X0136534Y1350683
X0141490Y1350683
X0141490Y1345691
X0148774Y1362595
X0148774Y1357603
X0136534Y1357603
X0136534Y1362595
X0141490Y1362595
X0141490Y1357603
X0075334Y1350683
X0075334Y1345691
X0080290Y1350683
X0080290Y1345691
X0075334Y1362595
X0075334Y1357603
X0080290Y1362595
X0080290Y1357603
X0075334Y1369889
X0075334Y1374881
X0075334Y1381801
X0080290Y1374881
X0080290Y1369889
X0080290Y1381801
X0075334Y1386793
X0080290Y1386793
X0092530Y1350683
X0092530Y1345691
X0099814Y1345691
X0099814Y1350683
X0087574Y1350683
X0087574Y1345691
X0092530Y1357603
X0092530Y1362595
X0099814Y1357603
X0099814Y1362595
X0087574Y1357603
X0087574Y1362595
X0129250Y1410991
X0129250Y1405999
X0124294Y1410991
X0124294Y1405999
X0148774Y1374881
X0148774Y1381801
X0148774Y1369889
X0136534Y1374881
X0136534Y1381801
X0136534Y1369889
X0141490Y1381801
X0141490Y1374881
X0141490Y1369889
X0148774Y1386793
X0148774Y1399079
X0148774Y1394087
X0136534Y1386793
X0136534Y1394087
X0136534Y1399079
X0141490Y1399079
X0141490Y1394087
X0141490Y1386793
X0148774Y1410991
X0148774Y1405999
X0136534Y1405999
X0136534Y1410991
X0141490Y1410991
X0141490Y1405999
X0112054Y1381801
X0112054Y1374881
X0112054Y1369889
X0104770Y1369889
X0104770Y1374881
X0104770Y1381801
X0117010Y1386793
X0117010Y1399079
X0117010Y1394087
X0112054Y1386793
X0112054Y1394087
X0112054Y1399079
X0104770Y1386793
X0104770Y1394087
X0104770Y1399079
X0117010Y1405999
X0117010Y1410991
X0112054Y1405999
X0112054Y1410991
X0104770Y1405999
X0104770Y1410991
X0129250Y1381801
X0129250Y1369889
X0129250Y1374881
X0124294Y1381801
X0124294Y1369889
X0124294Y1374881
X0129250Y1386793
X0129250Y1399079
X0129250Y1394087
X0124294Y1386793
X0124294Y1399079
X0124294Y1394087
X0092530Y1381801
X0092530Y1369795
X0092530Y1374881
X0099814Y1369889
X0099814Y1374881
X0099814Y1381801
X0087574Y1381801
X0087574Y1369795
X0087574Y1374881
X0092530Y1386793
X0092530Y1399079
X0092530Y1393993
X0099814Y1386793
X0099814Y1394087
X0099814Y1399079
X0087574Y1386793
X0087574Y1393993
X0087574Y1399079
X0092530Y1405999
X0092530Y1410991
X0099814Y1405999
X0099814Y1410991
X0087574Y1405999
X0087574Y1410991
X0117010Y1381801
X0117010Y1374881
X0117010Y1369889
X0149552Y1384297
X0137312Y1408495
X0161792Y1408495
X0161792Y1360099
X0165192Y1408495
X0140712Y1408495
X0165192Y1360099
X0152952Y1384297
X0129250Y1227650
X0126433Y1230407
X0136432Y1224472
X0135448Y1234921
X0135448Y1229402
X0071020Y1224323
X0071006Y1228684
X0112795Y1223749
X0107803Y1218169
X0124765Y1180691
X0131000Y1180266
X0130380Y1130291
X0124880Y1130291
X0124925Y1152491
X0124925Y1127291
X0124925Y1139891
X0124925Y1177691
X0124925Y1165091
X0124880Y1155491
X0130380Y1155491
X0124474Y1142997
X0130434Y1144964
X0130434Y1170164
X0124474Y1168197
X0103861Y1182703
X0108971Y1159964
X0103124Y1159964
X0108971Y1172564
X0103124Y1172564
X0108971Y1147364
X0103124Y1147364
X0108971Y1134764
X0103124Y1134764
X0135757Y1221407
X0112048Y1214372
X0118533Y1207737
X0165649Y1151870
X0165649Y1159350
X0070947Y1205835
X0103124Y1165091
X0112433Y1152491
X0108933Y1152491
X0103124Y1152491
X0112433Y1139891
X0103124Y1127291
X0112433Y1127291
X0108933Y1127291
X0106586Y1204932
X0109415Y1202103
X0112433Y1177691
X0108933Y1177691
X0103184Y1177691
X0112433Y1165091
X0108933Y1165091
X0133870Y1155491
X0133870Y1142891
X0133870Y1130291
X0126937Y1209607
X0121211Y1215195
X0133870Y1168091
X0134457Y1180654
X0070947Y1201565
X0160807Y1043955
X0088287Y1026537
X0130380Y1117691
X0124880Y1117691
X0124880Y1105091
X0130380Y1105091
X0136526Y1024954
X0142026Y1024954
X0124925Y1102091
X0124925Y1114691
X0110409Y1024094
X0108971Y1122164
X0103124Y1122164
X0108971Y1109564
X0103124Y1109564
X0120617Y1029427
X0107970Y1030672
X0104970Y1030672
X0101970Y1030672
X0110970Y1030672
X0114770Y1029427
X0133579Y1097469
X0088479Y1023731
X0160627Y1053561
X0160547Y1049283
X0146595Y1053457
X0102761Y1096233
X0090450Y1033542
X0150952Y1040115
X0144640Y1039439
X0153693Y1051037
X0159228Y1065613
X0105971Y1025745
X0077734Y1095676
X0163191Y1065313
X0166188Y1066551
X0094586Y1023900
X0070302Y1067656
X0070059Y1075656
X0160733Y1056594
X0069373Y1063389
X0069263Y1053152
X0070059Y1079656
X0070059Y1071656
X0097247Y1030568
X0100594Y1035088
X0108933Y1114691
X0103124Y1114691
X0112433Y1114691
X0103124Y1102091
X0112433Y1102091
X0108933Y1102091
X0133870Y1117691
X0133870Y1105091
X0148534Y1046476
X0145516Y1024954
X0155513Y1065148
X0164028Y1041468
X0097609Y1018469
X0076332Y0953421
X0155836Y0997860
X0136571Y1009354
X0136571Y1021954
X0142026Y1012354
X0136526Y1012354
X0101025Y1009655
X0103825Y1009655
X0120617Y1016827
X0114770Y1016827
X0095836Y0988813
X0127836Y0988813
X0100200Y0988800
X0143836Y0988813
X0107836Y0988813
X0123836Y0988813
X0115836Y0988813
X0103836Y0988813
X0159836Y0988813
X0119836Y0988813
X0151836Y0988813
X0111836Y0988813
X0131836Y0988813
X0088007Y1013678
X0091765Y1018307
X0087632Y1007522
X0094398Y1006648
X0139836Y0988813
X0078167Y0949261
X0135836Y0988813
X0147836Y0988813
X0080593Y0946082
X0085706Y0998507
X0103972Y0977609
X0103836Y0980330
X0100058Y0977651
X0099836Y0980330
X0084679Y1018368
X0076991Y0946134
X0095836Y0997860
X0099836Y0997860
X0091128Y1006487
X0111275Y1011762
X0115836Y0997860
X0107836Y0997860
X0114770Y1009354
X0111275Y1008262
X0111836Y0997860
X0103836Y0997860
X0124079Y1021954
X0120579Y1021954
X0120579Y1009354
X0123836Y0997860
X0127836Y0997860
X0131836Y0997860
X0119836Y0997860
X0124079Y1009354
X0145516Y1012354
X0135836Y0997860
X0143836Y0997860
X0147836Y0997860
X0139836Y0997860
X0159836Y0997860
X0151836Y0997860
X0074700Y0842890
X0110887Y0884000
X0123387Y0892000
X0074349Y0824718
X0072149Y0827318
X0136862Y0857244
X0133424Y0857303
X0129666Y0857514
X0122432Y0857540
X0125698Y0857515
X0122437Y0860775
X0091387Y0905295
X0103770Y0868206
X0103692Y0900295
X0090000Y0871389
X0122887Y0888000
X0102320Y0891043
X0102947Y0877196
X0102355Y0874267
X0083079Y0888515
X0074028Y0889065
X0076203Y0897910
X0071528Y0913190
X0076528Y0878533
X0080339Y0897943
X0072035Y0898346
X0084367Y0878286
X0086367Y0848086
X0072549Y0838818
X0071928Y0873683
X0087853Y0899220
X0091581Y0874859
X0091581Y0877859
X0088875Y0840940
X0107641Y0865224
X0113601Y0881266
X0127067Y0891495
X0122887Y0884000
X0120250Y0758841
X0119099Y0755052
X0074349Y0821918
X0086289Y0822088
X0109591Y0796905
X0118467Y0796785
X0113505Y0796856
X0114397Y0727974
X0118122Y0747565
X0095539Y0664443
X0149469Y0634190
X0152658Y0645389
X0111993Y0710102
X0147925Y0623600
X0078735Y0683426
X0082562Y0680037
X0084845Y0659857
X0079043Y0667391
X0073914Y0660107
X0082648Y0670679
X0084314Y0686107
X0095917Y0658374
X0092897Y0658359
X0095973Y0655660
X0074414Y0681907
X0082714Y0674707
X0072314Y0683407
X0072314Y0680207
X0078129Y0656900
X0081740Y0639050
X0069670Y0638805
X0081740Y0633450
X0069670Y0636005
X0069670Y0633205
X0081740Y0636250
X0087714Y0684607
X0085614Y0674707
X0092134Y0668293
X0089432Y0668293
X0093456Y0649838
X0112474Y0716315
X0152386Y0634946
X0077734Y0596782
X0084159Y0578986
X0072515Y0596089
X0078733Y0578405
X0083684Y0596729
X0086788Y0581659
X0072337Y0573303
X0074983Y0573689
X0075340Y0576484
X0074923Y0570478
X0072128Y0570686
X0070688Y0548358
X0073188Y0548358
X0075688Y0548358
X0147925Y0619600
X0147925Y0603600
X0078133Y0561097
X0078133Y0563697
X0078133Y0566597
X0078133Y0558497
X0078133Y0555897
X0078133Y0553297
X0087684Y0605443
X0079684Y0605443
X0142024Y0552466
X0069670Y0613913
X0069670Y0616713
X0069670Y0619513
X0081740Y0614158
X0081740Y0616958
X0081740Y0619758
X0138290Y0527694
X0148692Y0534806
X0148692Y0538206
X0138290Y0531094
X0148692Y0524033
X0074795Y0532749
X0071995Y0532749
X0083684Y0605443
X0075684Y0605443
X0075822Y0590190
X0071228Y0590145
X0071730Y0579475
X0071184Y0585507
X0075777Y0585507
X0147893Y0607588
X0147925Y0615600
X0147896Y0596095
X0145609Y0594668
X0147094Y0592354
X0147155Y0589556
X0147893Y0599588
X0145670Y0597580
X0140703Y0536382
X0140786Y0526916
X0146196Y0534028
X0146196Y0538984
X0146196Y0524811
X0135794Y0531872
X0140786Y0531872
X0135794Y0526916
X0157090Y0562003
X0157375Y0555234
X0151188Y0524811
X0151188Y0534028
X0151188Y0538984
X0145376Y0458711
X0148940Y0455921
X0073961Y0498151
X0078033Y0493633
X0078033Y0496133
X0078033Y0498633
X0073961Y0495151
X0071461Y0495151
X0071461Y0498151
X0078033Y0491133
X0073630Y0464652
X0073630Y0462152
X0073630Y0459652
X0071130Y0464652
X0071130Y0459652
X0071130Y0462152
X0147520Y0463600
X0150703Y0453682
X0138290Y0472787
X0148692Y0494073
X0148692Y0479899
X0138290Y0513521
X0138290Y0444033
X0138290Y0486960
X0138290Y0516921
X0138290Y0440633
X0148692Y0520633
X0148692Y0436921
X0148692Y0490673
X0138290Y0483560
X0138290Y0429860
X0138290Y0426460
X0148692Y0422747
X0148692Y0433521
X0148692Y0476499
X0138290Y0469387
X0151188Y0475721
X0151188Y0480677
X0140786Y0473565
X0135794Y0473565
X0140786Y0482782
X0135794Y0482782
X0146196Y0475721
X0146196Y0480677
X0078033Y0483586
X0078033Y0476086
X0078033Y0481086
X0078033Y0478586
X0069816Y0478446
X0069816Y0475946
X0074326Y0480705
X0071826Y0480705
X0090257Y0445506
X0135794Y0425682
X0140786Y0425682
X0151188Y0437699
X0151188Y0432743
X0151188Y0423525
X0140786Y0468609
X0135794Y0468609
X0136604Y0450750
X0135794Y0444811
X0140786Y0444811
X0135794Y0439855
X0140786Y0439855
X0146196Y0437699
X0146196Y0432743
X0135794Y0430638
X0140786Y0430638
X0146196Y0423525
X0070736Y0519458
X0073236Y0519458
X0075736Y0519458
X0146196Y0519855
X0140786Y0517699
X0135794Y0517699
X0140786Y0512743
X0135794Y0512743
X0146196Y0494851
X0140786Y0487738
X0135794Y0487738
X0146196Y0489895
X0151188Y0519855
X0151188Y0494851
X0151188Y0489895
X0148176Y0458711
X0100066Y0381976
X0126131Y0359511
X0125753Y0365856
X0100120Y0377898
X0098255Y0374510
X0148061Y0382600
X0148692Y0408574
X0140690Y0398113
X0138290Y0415687
X0148692Y0419347
X0140690Y0401513
X0148692Y0391001
X0148692Y0405174
X0138290Y0412287
X0148692Y0394401
X0095943Y0377953
X0138194Y0402291
X0146196Y0409352
X0146196Y0404396
X0146196Y0395179
X0143186Y0397335
X0138194Y0397335
X0143186Y0402291
X0146196Y0390223
X0125125Y0362403
X0151188Y0418569
X0151188Y0409352
X0151188Y0404396
X0151188Y0395179
X0151188Y0390223
X0146196Y0418569
X0135794Y0411509
X0135794Y0416465
X0140786Y0411509
X0140786Y0416465
X0148061Y0378600
X0080525Y0265896
X0120568Y0244571
X0127911Y0256394
X0077073Y0281716
X0083014Y0281982
X0085541Y0266114
X0117948Y0249108
X0075438Y0265701
X0164496Y0309405
X0124961Y0228646
X0133957Y0227824
X0080766Y0256303
X0103841Y0228631
X0160349Y0258880
X0138664Y0241699
X0129702Y0230556
X0138547Y0230117
X0072256Y0270026
X0069756Y0270026
X0069756Y0267526
X0072256Y0267526
X0162924Y0264180
X0160424Y0264180
X0109329Y0248371
X0134563Y0238714
X0134044Y0246874
X0123918Y0232971
X0128687Y0242078
X0122000Y0226320
X0094087Y0268195
X0091287Y0268195
X0088787Y0268195
X0088787Y0270695
X0091287Y0270695
X0094087Y0270695
X0100247Y0265897
X0097747Y0265897
X0093590Y0248765
X0088590Y0248765
X0091090Y0248765
X0088649Y0236189
X0091149Y0236189
X0093649Y0236189
X0088098Y0228221
X0088098Y0231021
X0086398Y0224421
X0069139Y0236611
X0083819Y0290755
X0079819Y0290755
X0075819Y0290755
X0071593Y0288190
X0071593Y0285690
X0084766Y0256535
X0076766Y0256535
X0073841Y0248891
X0071341Y0248891
X0073158Y0231786
X0071639Y0236611
X0074139Y0236611
X0076851Y0224712
X0071696Y0226141
X0073158Y0229286
X0091890Y0288345
X0091890Y0290845
X0091890Y0293645
X0094390Y0288345
X0094390Y0290845
X0094390Y0293645
X0089900Y0281307
X0085796Y0279208
X0109329Y0252371
X0138563Y0238714
X0123811Y0253198
X0120926Y0238589
X0123892Y0236121
X0130328Y0238689
X0131102Y0247292
X0166528Y0312392
X0160641Y0293796
X0163141Y0293796
X0157095Y0223726
X0157095Y0226226
X0167551Y0223661
X0157095Y0231226
X0157095Y0228726
X0167551Y0226461
X0167551Y0228961
X0167551Y0231461
X0168655Y0285690
X0168655Y0288190
X0107798Y0124283
X0112864Y0124879
X0117886Y0124663
X0094811Y0152373
X0080041Y0148277
X0082661Y0143740
X0122867Y0125107
X0119230Y0138838
X0095711Y0143518
X0107653Y0186778
X0103456Y0157370
X0125381Y0148717
X0092337Y0144172
X0131481Y0143762
X0107540Y0192665
X0107540Y0196665
X0091224Y0141247
X0083756Y0168697
X0080522Y0215632
X0080522Y0213132
X0076819Y0211359
X0076819Y0213859
X0071761Y0211695
X0072061Y0208695
X0069261Y0208695
X0069261Y0211695
X0072783Y0184221
X0075400Y0184012
X0078581Y0181009
X0075786Y0181366
X0072575Y0181426
X0098653Y0183834
X0098173Y0190185
X0081083Y0172190
X0098763Y0178560
X0098826Y0172665
X0080502Y0177616
X0167551Y0215713
X0167551Y0210713
X0167551Y0213213
X0167551Y0208213
X0157095Y0212978
X0157095Y0215478
X0157095Y0207978
X0157095Y0210478
X0092898Y0192490
X0168840Y0162368
X0166240Y0162368
X0134947Y0202048
X0131947Y0201748
X0129783Y0206806
X0132283Y0206806
X0130510Y0210509
X0128010Y0210509
X0135429Y0195176
X0134947Y0199248
X0132929Y0195176
X0130429Y0195176
X0127929Y0195176
X0131947Y0199248
X0071422Y0147540
X0099032Y0212455
X0098943Y0200864
X0098966Y0207037
X0107572Y0208864
X0097961Y0152562
X0103213Y0219379
X0121934Y0221970
X0121934Y0219470
X0121934Y0216970
X0119221Y0216385
X0115421Y0218085
X0112621Y0218085
X0107572Y0204864
X0099639Y0186629
X0084844Y0191941
X0107540Y0168665
X0107540Y0176665
X0106205Y0161306
X0124340Y0142862
X0075194Y0141247
X0073578Y0167993
X0073578Y0170493
X0073578Y0162793
X0073578Y0165393
X0138050Y0125428
X0138050Y0128828
X0130750Y0135915
X0130750Y0132515
X0076005Y0128796
X0076005Y0125396
X0086407Y0135909
X0091983Y0221708
X0096333Y0221642
X0086983Y0221708
X0089483Y0221708
X0091853Y0206767
X0086853Y0206767
X0089353Y0206767
X0076851Y0222212
X0083552Y0206760
X0074939Y0188727
X0081572Y0184619
X0075072Y0191941
X0071422Y0151540
X0083911Y0136687
X0083911Y0131731
X0083911Y0122513
X0078501Y0124618
X0078501Y0129574
X0073509Y0124618
X0073509Y0129574
X0117607Y0133298
X0110152Y0130898
X0087604Y0185165
X0092242Y0185121
X0096010Y0192421
X0092287Y0180527
X0087604Y0180572
X0085904Y0152367
X0088903Y0136687
X0087002Y0146461
X0088903Y0131731
X0088903Y0122513
X0121430Y0206838
X0118930Y0206838
X0120682Y0195176
X0129134Y0150847
X0124340Y0146012
X0126246Y0141228
X0133150Y0137757
X0128350Y0137757
X0128350Y0130670
X0133150Y0130670
X0128350Y0123584
X0133150Y0123584
X0107572Y0221864
X0107572Y0216864
X0107572Y0212864
X0107572Y0200864
X0112742Y0203393
X0115242Y0203393
X0117501Y0201683
X0117882Y0195176
X0112882Y0195176
X0115382Y0195176
X0117501Y0198883
X0107540Y0180665
X0107540Y0172665
X0111754Y0134579
X0136882Y0213539
X0140350Y0137756
X0149822Y0137756
X0140350Y0123583
X0140350Y0130670
X0135650Y0130670
X0135650Y0123583
X0149827Y0130670
X0148774Y0124576
X0166460Y0137756
X0155051Y0137756
X0166460Y0130670
X0166460Y0123583
X0158460Y0123583
X0158460Y0130670
X0086407Y0132509
X0113307Y0110784
X0118307Y0110784
X0133200Y0095111
X0148350Y0095236
X0077804Y0095879
X0158233Y0099961
X0158283Y0095236
X0137569Y0106561
X0153912Y0090615
X0148600Y0090650
X0167147Y0079993
X0167147Y0082593
X0167147Y0085193
X0167147Y0074793
X0167147Y0077393
X0119333Y0116594
X0119333Y0119594
X0128950Y0097667
X0137804Y0097667
X0137410Y0103411
X0167191Y0092874
X0124606Y0102495
X0107364Y0119594
X0107364Y0116594
X0076660Y0103783
X0073110Y0098551
X0138050Y0114655
X0130750Y0118342
X0130750Y0121742
X0138050Y0111255
X0076005Y0111223
X0086407Y0121735
X0073745Y0044773
X0073745Y0024773
X0080660Y0103783
X0083911Y0117557
X0078501Y0115401
X0073509Y0115401
X0078501Y0110445
X0073509Y0110445
X0073110Y0101701
X0069381Y0094017
X0073381Y0094017
X0115582Y0102249
X0110013Y0110784
X0111582Y0102249
X0107364Y0110394
X0107364Y0113394
X0119582Y0102249
X0088903Y0117557
X0088080Y0103603
X0122599Y0109172
X0125599Y0109172
X0124606Y0106495
X0133150Y0116497
X0128350Y0116497
X0130679Y0044773
X0130679Y0024773
X0135650Y0116497
X0140350Y0102323
X0140350Y0109410
X0140350Y0116496
X0148350Y0102323
X0148602Y0116496
X0148602Y0109410
X0135650Y0109410
X0148812Y0085584
X0148812Y0077784
X0148812Y0075184
X0148812Y0082984
X0148812Y0080384
X0138000Y0053597
X0166460Y0102323
X0166460Y0109410
X0166460Y0116496
X0158460Y0109410
X0158326Y0103037
X0158460Y0116496
X0151366Y0092849
X0158000Y0053597
X0086407Y0118335
X0076005Y0114623
X0074432Y0005374
X0113334Y0003000
X0093334Y0003000
X0129318Y0004469
X0176794Y0005374
X0195697Y0003000
X0231681Y0004469
X0215697Y0003000
X0215669Y0110784
X0220669Y0110784
X0235562Y0095111
X0250712Y0095236
X0186026Y0097475
X0193007Y0100625
X0201669Y0103621
X0169218Y0104249
X0197380Y0112083
X0169218Y0107649
X0239931Y0106561
X0260645Y0095236
X0260595Y0099961
X0205976Y0085731
X0209530Y0086046
X0191568Y0072615
X0256274Y0090615
X0250962Y0090650
X0191568Y0076587
X0208645Y0060369
X0210482Y0094279
X0205848Y0060513
X0206533Y0094351
X0214389Y0086012
X0185957Y0106186
X0179022Y0103783
X0175472Y0098551
X0199486Y0080581
X0199473Y0068581
X0203248Y0055513
X0240166Y0097667
X0239772Y0103411
X0226968Y0102495
X0209726Y0119594
X0209726Y0116594
X0214389Y0094374
X0203616Y0088801
X0221695Y0116594
X0221695Y0119594
X0231312Y0097667
X0240412Y0111255
X0233112Y0118342
X0240412Y0114655
X0233112Y0121742
X0178367Y0114623
X0178367Y0111223
X0175871Y0115401
X0180863Y0110445
X0180863Y0115401
X0175871Y0110445
X0175472Y0101701
X0171743Y0094017
X0175743Y0094017
X0179743Y0094017
X0176107Y0044773
X0176107Y0024773
X0194189Y0103621
X0183022Y0103783
X0191265Y0117557
X0186273Y0117557
X0183752Y0094017
X0188820Y0076140
X0188820Y0084140
X0188820Y0080140
X0212375Y0110784
X0213944Y0102249
X0209726Y0110394
X0209726Y0113394
X0202195Y0117261
X0203591Y0091951
X0208463Y0096472
X0206398Y0055513
X0211262Y0060922
X0227961Y0109172
X0217944Y0102249
X0230712Y0116497
X0226968Y0106495
X0224961Y0109172
X0221944Y0102249
X0253728Y0092849
X0251174Y0075184
X0251174Y0082984
X0251174Y0080384
X0251174Y0077784
X0260363Y0053597
X0238012Y0109410
X0235512Y0116497
X0238012Y0116497
X0242712Y0102323
X0242712Y0109410
X0242712Y0116496
X0240363Y0053597
X0233042Y0044773
X0233042Y0024773
X0260822Y0109410
X0260822Y0116496
X0250964Y0116496
X0250712Y0102323
X0250964Y0109410
X0260688Y0103037
X0251174Y0085584
X0268822Y0102323
X0268822Y0109410
X0268822Y0116496
X0188769Y0121735
X0188769Y0118335
X0215226Y0124879
X0210160Y0124283
X0197173Y0152373
X0182403Y0148277
X0185023Y0143740
X0220248Y0124663
X0225229Y0125107
X0221592Y0138838
X0198073Y0143518
X0210015Y0186778
X0205818Y0157370
X0227743Y0148717
X0201328Y0207037
X0233843Y0143762
X0209902Y0192665
X0209902Y0196665
X0201305Y0200864
X0201394Y0212455
X0193586Y0141247
X0209934Y0208864
X0183445Y0172190
X0182864Y0177616
X0200535Y0190185
X0195260Y0192490
X0201188Y0172665
X0186118Y0168697
X0182884Y0215632
X0174423Y0208695
X0171623Y0208695
X0174123Y0211695
X0179181Y0213859
X0179181Y0211359
X0182884Y0213132
X0171623Y0211695
X0177762Y0184012
X0175145Y0184221
X0174937Y0181426
X0180943Y0181009
X0178148Y0181366
X0201125Y0178560
X0201015Y0183834
X0259457Y0212978
X0259457Y0215478
X0259457Y0207978
X0259457Y0210478
X0268602Y0162368
X0175940Y0170493
X0175940Y0167993
X0175940Y0165393
X0175940Y0162793
X0200323Y0152562
X0205575Y0219379
X0214983Y0218085
X0217783Y0218085
X0221583Y0216385
X0224296Y0221970
X0224296Y0219470
X0224296Y0216970
X0209934Y0204864
X0202001Y0186629
X0187206Y0191941
X0209902Y0168665
X0209902Y0176665
X0208567Y0161306
X0226702Y0142862
X0177556Y0141247
X0233112Y0135915
X0240412Y0128828
X0234309Y0201748
X0232145Y0206806
X0234645Y0206806
X0232872Y0210509
X0237309Y0202048
X0230372Y0210509
X0237791Y0195176
X0234309Y0199248
X0237309Y0199248
X0235291Y0195176
X0232791Y0195176
X0230291Y0195176
X0173784Y0147540
X0240412Y0125428
X0233112Y0132515
X0188769Y0132509
X0178367Y0125396
X0189345Y0221708
X0191845Y0221708
X0198695Y0221642
X0194345Y0221708
X0194215Y0206767
X0191715Y0206767
X0189215Y0206767
X0179213Y0222212
X0177301Y0188727
X0177434Y0191941
X0173784Y0151540
X0175871Y0124618
X0175871Y0129574
X0180863Y0124618
X0180863Y0129574
X0189966Y0180572
X0188266Y0152367
X0191265Y0136687
X0186273Y0136687
X0189364Y0146461
X0191265Y0131731
X0191265Y0122513
X0186273Y0122513
X0186273Y0131731
X0185914Y0206760
X0183934Y0184619
X0194604Y0185121
X0189966Y0185165
X0198372Y0192421
X0194649Y0180527
X0209934Y0221864
X0209934Y0216864
X0209934Y0212864
X0215104Y0203393
X0209934Y0200864
X0215244Y0195176
X0209902Y0180665
X0209902Y0172665
X0214116Y0134579
X0211969Y0133298
X0217604Y0203393
X0221292Y0206838
X0219863Y0201683
X0223792Y0206838
X0223044Y0195176
X0217744Y0195176
X0219863Y0198883
X0220244Y0195176
X0231496Y0150847
X0226702Y0146012
X0230712Y0137757
X0228608Y0141228
X0219969Y0133298
X0230712Y0130670
X0230712Y0123584
X0239244Y0213539
X0242712Y0137756
X0235512Y0137757
X0235512Y0123584
X0242712Y0123583
X0242712Y0130670
X0235512Y0130670
X0238012Y0130670
X0238012Y0123583
X0252184Y0137756
X0257413Y0137756
X0252189Y0130670
X0260822Y0123583
X0260822Y0130670
X0251136Y0124576
X0268822Y0137756
X0268822Y0123583
X0268822Y0130670
X0188769Y0135909
X0178367Y0128796
X0222930Y0244571
X0233417Y0253198
X0182887Y0265896
X0220310Y0249108
X0177800Y0265701
X0179435Y0281716
X0187903Y0266114
X0185376Y0281982
X0257993Y0307994
X0227323Y0228646
X0183128Y0256303
X0206203Y0228631
X0236319Y0227824
X0230842Y0313888
X0170215Y0311671
X0238626Y0244297
X0262711Y0258880
X0240909Y0230117
X0232064Y0230556
X0169318Y0270026
X0172118Y0270026
X0172118Y0267526
X0169318Y0267526
X0174618Y0270026
X0174618Y0267526
X0265286Y0264180
X0262786Y0264180
X0211691Y0248371
X0226280Y0232971
X0236406Y0246874
X0231049Y0242078
X0224362Y0226320
X0236925Y0238714
X0191149Y0268195
X0191149Y0270695
X0193649Y0270695
X0196449Y0270695
X0193649Y0268195
X0196449Y0268195
X0195952Y0248765
X0193452Y0248765
X0190952Y0248765
X0196011Y0236189
X0193511Y0236189
X0191011Y0236189
X0188760Y0224421
X0190460Y0231021
X0190460Y0228221
X0202609Y0265897
X0200109Y0265897
X0179128Y0256535
X0171203Y0248891
X0173703Y0248891
X0176203Y0248891
X0171501Y0236611
X0175520Y0231786
X0176501Y0236611
X0174001Y0236611
X0174058Y0226141
X0171258Y0226141
X0179213Y0224712
X0175520Y0229286
X0178181Y0290755
X0182181Y0290755
X0171155Y0288190
X0171155Y0285690
X0173955Y0288190
X0173955Y0285690
X0186181Y0290755
X0194252Y0288345
X0194252Y0290845
X0194252Y0293645
X0196752Y0288345
X0196752Y0290845
X0196752Y0293645
X0192262Y0281307
X0188158Y0279208
X0187128Y0256535
X0211691Y0252371
X0223288Y0238589
X0226254Y0236121
X0233464Y0247292
X0240925Y0238714
X0232690Y0238689
X0228760Y0316122
X0226173Y0253198
X0257226Y0312081
X0263003Y0293796
X0259457Y0223726
X0259457Y0226226
X0259457Y0231226
X0259457Y0228726
X0265503Y0293796
X0204675Y0382109
X0233258Y0359186
X0236264Y0342494
X0234986Y0336161
X0228267Y0396718
X0256475Y0422088
X0212980Y0408568
X0205680Y0398082
X0205680Y0412255
X0212980Y0390995
X0205680Y0401482
X0212980Y0394395
X0205680Y0415655
X0212980Y0405168
X0212980Y0419341
X0177369Y0417500
X0177369Y0410413
X0177369Y0403327
X0177369Y0396240
X0177369Y0389154
X0195295Y0414823
X0185402Y0412571
X0190518Y0396240
X0186448Y0404911
X0185169Y0396240
X0185169Y0389154
X0191988Y0389154
X0210580Y0396240
X0208080Y0396240
X0203280Y0410413
X0203280Y0403327
X0203280Y0396240
X0215380Y0410413
X0210580Y0410413
X0208080Y0410413
X0210580Y0403326
X0215380Y0403326
X0208080Y0403327
X0215380Y0396240
X0203280Y0389154
X0210580Y0389153
X0215380Y0389153
X0203280Y0417500
X0210580Y0417499
X0215380Y0417499
X0208080Y0417500
X0236349Y0339428
X0228267Y0412718
X0228267Y0404718
X0228267Y0400718
X0228267Y0408718
X0228267Y0392718
X0265011Y0403307
X0265011Y0410394
X0262526Y0451108
X0254512Y0438323
X0265011Y0446595
X0263301Y0444232
X0254678Y0445873
X0220349Y0465622
X0250336Y0456386
X0256705Y0477824
X0264005Y0481510
X0256705Y0491997
X0256705Y0521958
X0264005Y0511471
X0256705Y0474424
X0256705Y0518558
X0264005Y0470737
X0264005Y0467337
X0256705Y0488597
X0264005Y0484910
X0264005Y0514871
X0212980Y0486954
X0212980Y0472781
X0205680Y0520602
X0212980Y0469381
X0212980Y0436915
X0212980Y0513515
X0205680Y0476468
X0212980Y0483554
X0205680Y0444002
X0205680Y0426428
X0212980Y0516915
X0205680Y0479868
X0205680Y0490641
X0265011Y0453881
X0212980Y0422741
X0212980Y0433515
X0261965Y0458455
X0205680Y0429828
X0205680Y0494041
X0205680Y0440602
X0249125Y0465874
X0252695Y0442956
X0266405Y0472579
X0266405Y0486752
X0266405Y0479665
X0254305Y0472579
X0259105Y0472579
X0261605Y0472579
X0259105Y0486752
X0254305Y0479666
X0261605Y0479666
X0259105Y0479666
X0254305Y0486752
X0261605Y0486752
X0203280Y0474626
X0215380Y0474626
X0210580Y0474626
X0208080Y0474626
X0215380Y0481712
X0208080Y0481712
X0210580Y0481712
X0203280Y0481713
X0194222Y0472772
X0185169Y0474626
X0185430Y0480828
X0195069Y0479104
X0177369Y0474626
X0177369Y0481713
X0177369Y0467539
X0177369Y0445847
X0177369Y0438760
X0177369Y0431673
X0177369Y0424587
X0194278Y0436447
X0194673Y0429832
X0186589Y0426299
X0194603Y0422864
X0195480Y0467539
X0185169Y0467539
X0196313Y0447953
X0186900Y0445847
X0203280Y0467539
X0210580Y0467539
X0215380Y0467539
X0208080Y0445847
X0203280Y0445847
X0203280Y0438760
X0203280Y0431673
X0210580Y0431673
X0215380Y0431673
X0215380Y0438760
X0210580Y0438760
X0208080Y0438760
X0208080Y0431673
X0203280Y0424586
X0215380Y0424586
X0210580Y0424586
X0208080Y0424586
X0261605Y0465492
X0254678Y0449873
X0253758Y0435029
X0254692Y0431029
X0255000Y0427017
X0265945Y0430098
X0265945Y0432598
X0265945Y0435098
X0265945Y0437598
X0265945Y0440098
X0266229Y0462264
X0266405Y0465492
X0266405Y0458406
X0266405Y0451319
X0177369Y0518760
X0177369Y0511673
X0177369Y0495886
X0177369Y0488799
X0185169Y0511673
X0185169Y0518760
X0194080Y0510565
X0190829Y0516841
X0195480Y0495886
X0187380Y0498834
X0194956Y0487711
X0203280Y0495886
X0208080Y0495886
X0210580Y0488799
X0208080Y0488799
X0203280Y0488799
X0215380Y0488799
X0203280Y0518760
X0203280Y0511673
X0215380Y0511673
X0210580Y0511673
X0208080Y0518760
X0210580Y0518760
X0215380Y0518760
X0261605Y0509626
X0254305Y0516713
X0259105Y0516713
X0261605Y0516713
X0259105Y0493839
X0254305Y0493839
X0266405Y0509626
X0266405Y0516713
X0266405Y0493839
X0221375Y0455024
X0225500Y0530000
X0208540Y0621591
X0243278Y0618288
X0204674Y0561420
X0204674Y0558917
X0174923Y0541863
X0247278Y0618288
X0174923Y0545263
X0200495Y0577937
X0191125Y0610400
X0224040Y0558800
X0224104Y0562800
X0173115Y0553407
X0175615Y0553407
X0173115Y0550907
X0175615Y0550907
X0177099Y0569426
X0174776Y0568475
X0175033Y0570962
X0172686Y0569928
X0171339Y0572070
X0177385Y0566929
X0247536Y0602689
X0245362Y0542712
X0224200Y0549800
X0224000Y0547075
X0256705Y0582771
X0264005Y0564910
X0256705Y0596944
X0264005Y0604030
X0264005Y0579084
X0256705Y0568597
X0264005Y0607430
X0264005Y0575684
X0264005Y0529044
X0264005Y0525644
X0256705Y0536131
X0256705Y0586171
X0256705Y0614517
X0256705Y0571997
X0264005Y0593257
X0256705Y0600344
X0256705Y0532731
X0256705Y0611117
X0264005Y0561510
X0264005Y0589857
X0205680Y0524002
X0212980Y0531088
X0205680Y0538175
X0212980Y0527688
X0205680Y0534775
X0204674Y0551683
X0222289Y0590895
X0208000Y0604567
X0185328Y0545528
X0209094Y0616317
X0221693Y0594982
X0194063Y0577716
X0209158Y0610072
X0203741Y0612592
X0203500Y0606929
X0208500Y0595500
X0203460Y0618400
X0223500Y0568000
X0245362Y0546712
X0177114Y0595108
X0176650Y0602197
X0177369Y0547106
X0177369Y0540020
X0177369Y0532933
X0177369Y0525847
X0191125Y0614400
X0191125Y0606400
X0191125Y0594400
X0191125Y0598400
X0191125Y0602400
X0185640Y0574102
X0187408Y0572334
X0186867Y0560675
X0185099Y0562443
X0185776Y0550123
X0185654Y0552872
X0185169Y0525847
X0203280Y0595118
X0203280Y0602205
X0203740Y0572914
X0203740Y0575414
X0203740Y0570414
X0203740Y0565414
X0203740Y0567914
X0212460Y0560500
X0203280Y0554193
X0203280Y0547106
X0203280Y0540020
X0203280Y0532933
X0203280Y0525847
X0215380Y0532933
X0215380Y0525846
X0210580Y0525846
X0208080Y0525846
X0208080Y0540020
X0208080Y0532933
X0210580Y0532933
X0222646Y0607542
X0224500Y0555000
X0223925Y0543925
X0241967Y0616063
X0247333Y0599506
X0254305Y0523800
X0261605Y0523800
X0259105Y0523800
X0254305Y0616359
X0259105Y0616359
X0261605Y0609272
X0259105Y0609272
X0254305Y0609272
X0261605Y0602185
X0261605Y0595099
X0259105Y0595099
X0254305Y0595099
X0254305Y0602186
X0259105Y0602186
X0254305Y0588013
X0254305Y0580926
X0259105Y0580926
X0261605Y0580926
X0259105Y0573839
X0261605Y0573839
X0254305Y0573839
X0259105Y0588013
X0261605Y0588012
X0259105Y0566752
X0261605Y0566752
X0261605Y0559665
X0254305Y0566752
X0254305Y0537973
X0254305Y0530886
X0259105Y0537973
X0259105Y0530886
X0261605Y0530886
X0266405Y0616358
X0266405Y0609272
X0266405Y0595099
X0266405Y0602185
X0266405Y0573839
X0266405Y0588012
X0266405Y0580926
X0266405Y0559665
X0266405Y0566752
X0266405Y0537973
X0266405Y0530886
X0266405Y0523799
X0220333Y0617930
X0225000Y0540500
X0246102Y0656321
X0250102Y0656321
X0203046Y0693716
X0201115Y0695581
X0205941Y0668934
X0244267Y0696911
X0254634Y0698241
X0248690Y0678519
X0245000Y0678462
X0242102Y0656321
X0240194Y0643113
X0248090Y0691114
X0220255Y0629749
X0193723Y0656942
X0209429Y0625300
X0241850Y0678462
X0246583Y0665140
X0241084Y0638243
X0240249Y0628328
X0243078Y0636486
X0258867Y0680499
X0248984Y0638125
X0252688Y0636364
X0246311Y0819000
X0235790Y0754332
X0237591Y0815266
X0256303Y0812254
X0254058Y0819851
X0248506Y0812042
X0241204Y0814841
X0250700Y0819900
X0238400Y0836900
X0252100Y0836800
X0252305Y0831018
X0255289Y0824340
X0248556Y0824003
X0247600Y0848500
X0251802Y0824128
X0169389Y1155610
X0198512Y1408495
X0177432Y1360099
X0186272Y1372385
X0174032Y1408495
X0201912Y1360099
X0198512Y1360099
X0189672Y1372385
X0198512Y1396583
X0189672Y1384297
X0174032Y1396583
X0198512Y1348187
X0174032Y1360099
X0177432Y1408495
X0174032Y1348187
X0177432Y1396583
X0201912Y1348187
X0201912Y1396583
X0186272Y1384297
X0201912Y1408495
X0177432Y1348187
X0257263Y1384297
X0241623Y1360099
X0253863Y1384297
X0266103Y1408495
X0245023Y1360099
X0266103Y1360099
X0257263Y1348187
X0186272Y1348187
X0201912Y1372385
X0189672Y1396583
X0245023Y1384297
X0177432Y1372385
X0198512Y1372385
X0241623Y1384297
X0257263Y1360099
X0174032Y1372385
X0253863Y1360099
X0186272Y1396583
X0189672Y1348187
X0257263Y1372385
X0266103Y1384297
X0245801Y1362595
X0245801Y1357603
X0240845Y1362595
X0240845Y1357603
X0245801Y1369889
X0245801Y1374881
X0245801Y1381801
X0240845Y1369889
X0240845Y1374881
X0240845Y1381801
X0245801Y1386793
X0240845Y1386793
X0253085Y1345691
X0253085Y1350683
X0258041Y1345691
X0258041Y1350683
X0253085Y1357603
X0258041Y1357603
X0265325Y1350683
X0265325Y1345691
X0265325Y1357603
X0245801Y1350683
X0245801Y1345691
X0240845Y1350683
X0240845Y1345691
X0253085Y1386793
X0258041Y1393993
X0258041Y1399079
X0258041Y1386793
X0253085Y1410991
X0253085Y1405999
X0258041Y1410991
X0258041Y1405999
X0265325Y1362595
X0265325Y1381801
X0265325Y1374881
X0265325Y1369889
X0265325Y1386793
X0265325Y1399079
X0265325Y1394087
X0265325Y1410991
X0265325Y1405999
X0178210Y1410991
X0178210Y1405999
X0173254Y1410991
X0173254Y1405999
X0197734Y1399079
X0190450Y1399079
X0185494Y1399079
X0197734Y1410991
X0197734Y1405999
X0190450Y1405999
X0190450Y1410991
X0185494Y1405999
X0185494Y1410991
X0202690Y1399079
X0202690Y1410991
X0202690Y1405999
X0253085Y1362595
X0258041Y1362595
X0253085Y1374881
X0253085Y1369795
X0253085Y1381801
X0258041Y1374881
X0258041Y1369795
X0258041Y1381801
X0253085Y1399079
X0253085Y1393993
X0190450Y1381801
X0190450Y1374881
X0190450Y1369889
X0197734Y1374881
X0197734Y1381801
X0197734Y1369889
X0185494Y1369889
X0185494Y1381801
X0185494Y1374881
X0197734Y1386793
X0197734Y1394087
X0190450Y1386793
X0190450Y1393993
X0185494Y1386793
X0185494Y1393993
X0202690Y1350683
X0202690Y1345597
X0202690Y1357603
X0202690Y1362595
X0202690Y1374881
X0202690Y1381801
X0202690Y1369889
X0202690Y1386793
X0202690Y1394087
X0178210Y1399079
X0173254Y1399079
X0178210Y1362595
X0178210Y1357603
X0173254Y1357603
X0173254Y1362595
X0178210Y1381801
X0178210Y1369889
X0178210Y1374881
X0173254Y1381801
X0173254Y1369889
X0173254Y1374881
X0178210Y1386793
X0178210Y1394087
X0173254Y1386793
X0173254Y1394087
X0197734Y1350683
X0197734Y1345691
X0190450Y1350683
X0190450Y1345597
X0185494Y1350683
X0185494Y1345597
X0190450Y1357603
X0190450Y1362595
X0197734Y1357603
X0197734Y1362595
X0185494Y1357603
X0185494Y1362595
X0178210Y1350683
X0178210Y1345691
X0173254Y1350683
X0173254Y1345691
X0266103Y1348187
X0245023Y1348187
X0253863Y1372385
X0266103Y1396583
X0241623Y1348187
X0253863Y1348187
X0253863Y1408495
X0257263Y1408495
X0174032Y1384297
X0266103Y1372385
X0186272Y1408495
X0201912Y1384297
X0241623Y1372385
X0189672Y1408495
X0186272Y1360099
X0198512Y1384297
X0177432Y1384297
X0189672Y1360099
X0245023Y1372385
X0257263Y1396583
X0253863Y1396583
X0237633Y1511909
X0213969Y1450853
X0213969Y1447453
X0227249Y1461853
X0227249Y1458453
X0227249Y1450853
X0227249Y1447453
X0213969Y1458453
X0213969Y1461853
X0216125Y1440028
X0219525Y1440028
X0233166Y1491454
X0233180Y1486442
X0245500Y1517033
X0234976Y1481676
X0243535Y1511473
X0217614Y1489671
X0222843Y1498442
X0226971Y1514578
X0218021Y1494724
X0223322Y1518578
X0217906Y1427052
X0230758Y1505046
X0233313Y1476699
X0226135Y1502442
X0225765Y1471985
X0217906Y1430452
X0221899Y1488800
X0217985Y1483055
X0224780Y1478149
X0240808Y1519942
X0222253Y1438483
X0213296Y1438215
X0217799Y1433684
X0217945Y1423924
X0232675Y1466801
X0224176Y1492816
X0218171Y1474460
X0229260Y1469587
X0216342Y1515642
X0243268Y1501903
X0240466Y1503857
X0176960Y1511977
X0176960Y1502515
X0176960Y1507246
X0176960Y1496622
X0176960Y1487160
X0176960Y1491891
X0176960Y1481268
X0176960Y1471806
X0176960Y1476537
X0176960Y1461183
X0176960Y1456452
X0176960Y1465914
X0185622Y1470244
X0185622Y1476137
X0185622Y1480868
X0185622Y1460782
X0185622Y1465513
X0185622Y1485599
X0211473Y1457675
X0211473Y1462631
X0211473Y1451631
X0211473Y1446675
X0226957Y1510442
X0222908Y1502028
X0223235Y1506770
X0224753Y1451631
X0229745Y1462631
X0229745Y1451631
X0224753Y1457675
X0229745Y1457675
X0224753Y1462631
X0216465Y1457675
X0216465Y1462631
X0216465Y1451631
X0224753Y1446675
X0229745Y1446675
X0216465Y1446675
X0245937Y1524237
X0233753Y1539752
X0219981Y1530797
X0227882Y1540816
X0226971Y1522578
X0244912Y1539389
X0222119Y1539941
X0250790Y1539759
X0255909Y1542043
X0237580Y1528604
X0235687Y1522578
X0239949Y1541327
X0250876Y1532782
X0232622Y1531104
X0227552Y1530675
X0244600Y1531700
X0217519Y1537172
X0248042Y1532900
X0237700Y1531600
X0176960Y1558813
X0176960Y1563544
X0176960Y1614338
X0176960Y1604876
X0176960Y1598984
X0176960Y1609607
X0176960Y1589522
X0176960Y1594253
X0176960Y1583629
X0176960Y1568275
X0172000Y1644980
X0192000Y1644980
X0272000Y1644980
X0292000Y1644980
X0312000Y1644980
X0332000Y1644980
X0352000Y1644980
X0280897Y1594253
X0289558Y1583229
X0280897Y1583629
X0280897Y1589522
X0289558Y1587960
X0289558Y1572606
X0289558Y1578498
X0280897Y1578898
X0289558Y1567875
X0280897Y1568275
X0280897Y1574167
X0280897Y1558813
X0289558Y1563144
X0280897Y1563544
X0289558Y1618669
X0289558Y1613938
X0280897Y1614338
X0280897Y1604876
X0289558Y1603315
X0289558Y1598584
X0280897Y1598984
X0289558Y1609207
X0280897Y1609607
X0289558Y1593853
X0306881Y1587960
X0306881Y1593853
X0298220Y1594253
X0298220Y1589522
X0306881Y1583229
X0298220Y1583629
X0306881Y1572606
X0306881Y1578498
X0298220Y1578898
X0298220Y1574167
X0306881Y1567875
X0298220Y1568275
X0306881Y1563144
X0298220Y1563544
X0298220Y1558813
X0306881Y1618669
X0306881Y1613938
X0298220Y1614338
X0306881Y1609207
X0298220Y1598984
X0298220Y1604876
X0298220Y1609607
X0306881Y1603315
X0306881Y1598584
X0315543Y1568275
X0324204Y1572606
X0324204Y1578498
X0324204Y1567875
X0315543Y1578898
X0315543Y1574167
X0324204Y1563144
X0315543Y1563544
X0315543Y1558813
X0324204Y1618669
X0324204Y1613938
X0315543Y1614338
X0324204Y1603315
X0324204Y1598584
X0324204Y1609207
X0315543Y1598984
X0315543Y1604876
X0315543Y1609607
X0324204Y1587960
X0324204Y1593853
X0324204Y1583229
X0315543Y1594253
X0315543Y1589522
X0315543Y1583629
X0341527Y1587960
X0341527Y1593853
X0341527Y1583229
X0332865Y1594253
X0332865Y1589522
X0332865Y1583629
X0332865Y1574167
X0332865Y1568275
X0341527Y1572606
X0341527Y1578498
X0341527Y1567875
X0332865Y1578898
X0341527Y1563144
X0332865Y1563544
X0332865Y1558813
X0332865Y1614338
X0341527Y1618669
X0341527Y1613938
X0332865Y1604876
X0332865Y1609607
X0341527Y1603315
X0341527Y1598584
X0341527Y1609207
X0332865Y1598984
X0350188Y1614338
X0350188Y1598984
X0350188Y1609607
X0350188Y1604876
X0350188Y1589522
X0350188Y1594253
X0350188Y1583629
X0350188Y1574167
X0350188Y1578898
X0350188Y1568275
X0350188Y1558813
X0350188Y1563544
X0358850Y1516307
X0358850Y1506845
X0358850Y1511576
X0289558Y1496221
X0280897Y1496621
X0280897Y1487159
X0289558Y1485598
X0289558Y1491490
X0280897Y1491890
X0280897Y1481267
X0280897Y1471805
X0289558Y1470244
X0289558Y1476136
X0280897Y1476536
X0289558Y1480867
X0280897Y1456451
X0289558Y1460782
X0280897Y1461182
X0289558Y1465513
X0280897Y1465913
X0289558Y1516307
X0280897Y1511976
X0289558Y1511576
X0280897Y1502514
X0289558Y1500952
X0289558Y1506845
X0280897Y1507245
X0306881Y1496221
X0306881Y1485598
X0306881Y1491490
X0298220Y1496621
X0298220Y1491890
X0298220Y1487159
X0306881Y1476136
X0298220Y1481267
X0298220Y1476536
X0298220Y1471805
X0306881Y1480867
X0306881Y1470244
X0306881Y1460782
X0306881Y1465513
X0298220Y1461182
X0298220Y1456451
X0298220Y1465913
X0306881Y1516307
X0298220Y1511976
X0306881Y1511576
X0306881Y1500952
X0306881Y1506845
X0298220Y1502514
X0298220Y1507245
X0324204Y1470244
X0324204Y1476136
X0315543Y1481267
X0315543Y1476536
X0315543Y1471805
X0324204Y1480867
X0324204Y1460782
X0324204Y1465513
X0315543Y1461182
X0315543Y1456451
X0315543Y1465913
X0324204Y1516307
X0324204Y1506845
X0315543Y1511976
X0315543Y1502514
X0315543Y1507245
X0324204Y1511576
X0324204Y1500952
X0324204Y1496221
X0324204Y1485598
X0324204Y1491490
X0315543Y1496621
X0315543Y1491890
X0315543Y1487159
X0332865Y1496621
X0332865Y1491890
X0332865Y1487159
X0341527Y1496221
X0341527Y1485598
X0341527Y1491490
X0332865Y1481267
X0332865Y1476536
X0332865Y1471805
X0341527Y1480867
X0341527Y1470244
X0341527Y1476136
X0341527Y1465513
X0332865Y1461182
X0332865Y1456451
X0332865Y1465913
X0341527Y1460782
X0341527Y1516307
X0332865Y1502514
X0332865Y1507245
X0341527Y1511576
X0341527Y1500952
X0341527Y1506845
X0332865Y1511976
X0350188Y1511977
X0350188Y1502515
X0350188Y1507246
X0350188Y1496622
X0350188Y1487160
X0350188Y1491891
X0278343Y1384297
X0281743Y1384297
X0290583Y1360099
X0293983Y1360099
X0290583Y1408495
X0293983Y1408495
X0302823Y1384297
X0306223Y1384297
X0367423Y1408495
X0364023Y1408495
X0315063Y1408495
X0318463Y1360099
X0351783Y1384297
X0339543Y1408495
X0339543Y1360099
X0315063Y1360099
X0355183Y1384297
X0330703Y1384297
X0318463Y1408495
X0327303Y1384297
X0342943Y1360099
X0269503Y1360099
X0364023Y1360099
X0269503Y1408495
X0342943Y1408495
X0367423Y1360099
X0318463Y1372385
X0281743Y1396583
X0367423Y1372385
X0355183Y1396583
X0290583Y1372385
X0330703Y1348187
X0306223Y1396583
X0351783Y1360099
X0339543Y1384297
X0342943Y1384297
X0355183Y1408495
X0364023Y1384297
X0351783Y1408495
X0367423Y1384297
X0355183Y1360099
X0302823Y1360099
X0306223Y1360099
X0278343Y1408495
X0290583Y1348187
X0367423Y1396583
X0293983Y1384297
X0281743Y1408495
X0290583Y1396583
X0278343Y1360099
X0318463Y1396583
X0342943Y1396583
X0290583Y1384297
X0281743Y1360099
X0318463Y1348187
X0367423Y1348187
X0327303Y1372385
X0364023Y1396583
X0281743Y1372385
X0269503Y1384297
X0364023Y1348187
X0339543Y1396583
X0342943Y1348187
X0293983Y1348187
X0343721Y1350683
X0343721Y1345691
X0331481Y1350683
X0331481Y1345691
X0338765Y1357603
X0343721Y1357603
X0331481Y1357603
X0282521Y1350683
X0294761Y1345691
X0294761Y1350683
X0289805Y1345691
X0289805Y1350683
X0282521Y1357603
X0294761Y1357603
X0289805Y1357603
X0307001Y1345691
X0307001Y1350683
X0302045Y1350683
X0302045Y1345691
X0307001Y1357603
X0302045Y1357603
X0326525Y1350683
X0326525Y1345691
X0314285Y1350683
X0314285Y1345691
X0319241Y1345691
X0319241Y1350683
X0326525Y1357603
X0314285Y1357603
X0319241Y1357603
X0338765Y1345691
X0338765Y1350683
X0270281Y1350683
X0270281Y1345691
X0277565Y1345691
X0277565Y1350683
X0270281Y1357603
X0277565Y1357603
X0282521Y1345691
X0368201Y1399079
X0368201Y1394087
X0368201Y1386793
X0363245Y1386793
X0363245Y1394087
X0363245Y1399079
X0368201Y1405999
X0368201Y1410991
X0363245Y1410991
X0363245Y1405999
X0355961Y1345597
X0351005Y1350683
X0351005Y1345597
X0355961Y1350683
X0355961Y1357603
X0351005Y1357603
X0368201Y1350683
X0368201Y1345691
X0363245Y1350683
X0363245Y1345691
X0368201Y1357603
X0363245Y1357603
X0338765Y1405999
X0338765Y1410991
X0343721Y1405999
X0343721Y1410991
X0331481Y1405999
X0331481Y1410991
X0355961Y1362595
X0351005Y1362595
X0355961Y1369889
X0355961Y1374881
X0355961Y1381801
X0351005Y1369889
X0351005Y1381801
X0351005Y1374881
X0355961Y1393993
X0355961Y1399079
X0355961Y1386793
X0351005Y1386793
X0351005Y1393993
X0351005Y1399079
X0355961Y1410991
X0355961Y1405999
X0351005Y1405999
X0351005Y1410991
X0368201Y1362595
X0363245Y1362595
X0368201Y1369889
X0368201Y1381801
X0368201Y1374881
X0363245Y1374881
X0363245Y1381801
X0363245Y1369889
X0326525Y1386793
X0326525Y1394087
X0326525Y1399079
X0314285Y1394087
X0314285Y1399079
X0314285Y1386793
X0319241Y1394087
X0319241Y1399079
X0319241Y1386793
X0326525Y1405999
X0326525Y1410991
X0314285Y1405999
X0314285Y1410991
X0319241Y1405999
X0319241Y1410991
X0338765Y1362595
X0343721Y1362595
X0331481Y1362595
X0338765Y1374881
X0338765Y1369889
X0338765Y1381801
X0343721Y1374881
X0343721Y1369889
X0343721Y1381801
X0331481Y1369889
X0331481Y1381801
X0331481Y1374881
X0338765Y1399079
X0338765Y1394087
X0338765Y1386793
X0343721Y1399079
X0343721Y1394087
X0343721Y1386793
X0331481Y1386793
X0331481Y1394087
X0331481Y1399079
X0307001Y1381801
X0307001Y1369889
X0307001Y1374881
X0302045Y1369889
X0302045Y1381801
X0302045Y1374881
X0307001Y1394087
X0307001Y1399079
X0307001Y1386793
X0302045Y1399079
X0302045Y1394087
X0302045Y1386793
X0307001Y1410991
X0307001Y1405999
X0302045Y1410991
X0302045Y1405999
X0326525Y1362595
X0314285Y1362595
X0319241Y1362595
X0326525Y1374881
X0326525Y1369889
X0326525Y1381801
X0314285Y1369889
X0314285Y1381801
X0314285Y1374881
X0319241Y1369889
X0319241Y1381801
X0319241Y1374881
X0277565Y1410991
X0277565Y1405999
X0282521Y1362595
X0294761Y1362595
X0289805Y1362595
X0282521Y1369889
X0282521Y1374881
X0282521Y1381801
X0294761Y1381801
X0294761Y1369889
X0294761Y1374881
X0289805Y1381801
X0289805Y1369889
X0289805Y1374881
X0282521Y1394087
X0282521Y1399079
X0282521Y1386793
X0294761Y1386793
X0294761Y1399079
X0294761Y1394087
X0289805Y1386793
X0289805Y1399079
X0289805Y1394087
X0282521Y1410991
X0282521Y1405999
X0294761Y1410991
X0294761Y1405999
X0289805Y1410991
X0289805Y1405999
X0307001Y1362595
X0302045Y1362595
X0270281Y1362595
X0277565Y1362595
X0270281Y1381801
X0270281Y1374881
X0270281Y1369889
X0277565Y1369889
X0277565Y1374881
X0277565Y1381801
X0270281Y1386793
X0270281Y1394087
X0270281Y1399079
X0277565Y1399079
X0277565Y1394087
X0277565Y1386793
X0270281Y1410991
X0270281Y1405999
X0302823Y1372385
X0355183Y1372385
X0293983Y1396583
X0330703Y1372385
X0327303Y1360099
X0327303Y1408495
X0330703Y1408495
X0339543Y1348187
X0306223Y1408495
X0315063Y1348187
X0315063Y1384297
X0351783Y1372385
X0302823Y1408495
X0278343Y1372385
X0315063Y1396583
X0327303Y1396583
X0318463Y1384297
X0306223Y1372385
X0342943Y1372385
X0330703Y1360099
X0269503Y1396583
X0278343Y1348187
X0351783Y1396583
X0269503Y1348187
X0306223Y1348187
X0364023Y1372385
X0355183Y1348187
X0302823Y1348187
X0281743Y1348187
X0351783Y1348187
X0278343Y1396583
X0330703Y1396583
X0339543Y1372385
X0269503Y1372385
X0293983Y1372385
X0302823Y1396583
X0327303Y1348187
X0315063Y1372385
X0358062Y1226016
X0360273Y1228226
X0355215Y1223170
X0362332Y1230265
X0367816Y1315542
X0367816Y1310586
X0335502Y1188222
X0360523Y1192282
X0339776Y1187962
X0341266Y1171956
X0336755Y1143489
X0366402Y1200969
X0335190Y1173065
X0342009Y1176100
X0357950Y1167768
X0352931Y1167768
X0366222Y1180235
X0348125Y1180175
X0366429Y1185238
X0348432Y1187215
X0361792Y1187310
X0357083Y1185205
X0340500Y1147500
X0352545Y1142666
X0354420Y1157544
X0360877Y1157404
X0353748Y1134729
X0357748Y1134729
X0346387Y1199256
X0339540Y1196894
X0357796Y1188058
X0343121Y1188412
X0349748Y1134729
X0362402Y1201039
X0350402Y1201043
X0354398Y1201043
X0351940Y1219895
X0358368Y1201043
X0361621Y1134729
X0349276Y1217228
X0339251Y1138130
X0330800Y1174500
X0357057Y1179542
X0366133Y1170767
X0366521Y1208993
X0368657Y1150087
X0346366Y1134729
X0365748Y1134325
X0357297Y1192709
X0337629Y1186071
X0349700Y1148000
X0336901Y1196407
X0360659Y1209789
X0352536Y1160168
X0357947Y1159455
X0351563Y1132410
X0355929Y1132042
X0362735Y1211864
X0365029Y1214158
X0368917Y1195419
X0368661Y1182649
X0366133Y1162817
X0368657Y1146937
X0278739Y0936439
X0366761Y0934550
X0279261Y0926339
X0368964Y0937738
X0341077Y1018056
X0368067Y0925136
X0333985Y1017945
X0368626Y0931346
X0363893Y0946863
X0281980Y0953926
X0270100Y0946500
X0358085Y0923327
X0337564Y1018294
X0367944Y0946082
X0368273Y0928100
X0275400Y0899400
X0275400Y0864400
X0275123Y0847874
X0274697Y0830951
X0269700Y0853100
X0278400Y0890839
X0358207Y0836462
X0269700Y0884600
X0269900Y0914200
X0358024Y0912085
X0357962Y0898800
X0358086Y0884616
X0358096Y0867459
X0365850Y0773950
X0362042Y0814772
X0365691Y0815127
X0274096Y0820725
X0368491Y0815092
X0365887Y0710329
X0363015Y0710365
X0321119Y0622912
X0335399Y0544718
X0337078Y0551381
X0327456Y0550065
X0320785Y0553287
X0318660Y0539315
X0331395Y0571991
X0331395Y0596938
X0331395Y0532725
X0320993Y0589825
X0331395Y0582765
X0320993Y0579052
X0320993Y0529013
X0331395Y0614511
X0320993Y0561479
X0320993Y0593225
X0331395Y0600338
X0331395Y0536125
X0331395Y0586165
X0320993Y0525613
X0320993Y0603999
X0331395Y0568591
X0331395Y0611111
X0320993Y0607399
X0320993Y0564879
X0320993Y0575652
X0274332Y0616358
X0274233Y0574338
X0274205Y0559665
X0274586Y0565574
X0275302Y0535677
X0275463Y0529136
X0292316Y0609272
X0292316Y0616358
X0284580Y0608117
X0292316Y0602185
X0292316Y0595099
X0284516Y0573839
X0292316Y0580925
X0292316Y0588012
X0292316Y0573839
X0284366Y0579978
X0292316Y0566752
X0292316Y0559665
X0284516Y0566752
X0284516Y0559665
X0280976Y0537973
X0283456Y0525483
X0283377Y0532756
X0292316Y0530886
X0292316Y0537973
X0292316Y0523799
X0328899Y0522730
X0328899Y0615289
X0318497Y0608177
X0323489Y0608177
X0328899Y0610333
X0328899Y0601116
X0318497Y0603221
X0323489Y0603221
X0323489Y0594003
X0328899Y0596160
X0318497Y0594003
X0328899Y0586943
X0318497Y0589047
X0323489Y0589047
X0328899Y0581987
X0323489Y0579830
X0318497Y0574874
X0323489Y0574874
X0318497Y0579830
X0323489Y0560701
X0323489Y0565657
X0328899Y0567813
X0318497Y0560701
X0318497Y0565657
X0328899Y0572769
X0324291Y0556775
X0318497Y0529791
X0323489Y0524835
X0323489Y0529791
X0328899Y0531947
X0328899Y0536903
X0318497Y0524835
X0333891Y0615289
X0333891Y0610333
X0333891Y0601116
X0333891Y0596160
X0333891Y0581987
X0333891Y0586943
X0333891Y0567813
X0333891Y0572769
X0338358Y0554861
X0333891Y0536903
X0333891Y0531947
X0333891Y0522730
X0353367Y0459330
X0367564Y0461034
X0353663Y0449045
X0367564Y0456034
X0353320Y0454214
X0345050Y0454334
X0274866Y0446606
X0274949Y0442606
X0363686Y0476168
X0363686Y0478668
X0366420Y0477486
X0366420Y0479986
X0353670Y0473571
X0357742Y0477053
X0360242Y0477053
X0353670Y0476071
X0353670Y0478571
X0353670Y0481071
X0295807Y0454177
X0293307Y0454177
X0295807Y0451677
X0293307Y0451677
X0358754Y0462060
X0361754Y0462060
X0295011Y0463618
X0295011Y0460218
X0276344Y0467367
X0367919Y0442118
X0367919Y0439318
X0358042Y0435518
X0357655Y0426689
X0358042Y0432718
X0357655Y0424089
X0295253Y0435669
X0295253Y0430469
X0295253Y0433069
X0292453Y0433069
X0292453Y0430469
X0292453Y0435669
X0292453Y0440869
X0292453Y0438269
X0295253Y0438269
X0295253Y0440869
X0275873Y0463479
X0359241Y0447001
X0356241Y0447001
X0358754Y0450091
X0361754Y0450091
X0278529Y0440489
X0280220Y0448493
X0282230Y0458572
X0278784Y0435158
X0278827Y0444841
X0331395Y0474418
X0331395Y0477818
X0331395Y0488591
X0320993Y0511439
X0331395Y0521952
X0320993Y0484879
X0331395Y0518552
X0320993Y0470706
X0331395Y0491991
X0320993Y0467306
X0320993Y0481479
X0320993Y0514839
X0274347Y0475262
X0274347Y0482666
X0333891Y0473640
X0333891Y0478596
X0328899Y0473640
X0323489Y0485657
X0318497Y0485657
X0318497Y0480701
X0328899Y0478596
X0323489Y0480701
X0292316Y0472579
X0284516Y0472579
X0292316Y0486752
X0292316Y0479665
X0284516Y0486752
X0284516Y0479665
X0274205Y0466027
X0284173Y0439963
X0284132Y0437072
X0284316Y0433570
X0284295Y0430760
X0292316Y0465492
X0282247Y0470136
X0284516Y0465492
X0284482Y0460250
X0292316Y0458406
X0284379Y0452018
X0284437Y0454744
X0284417Y0443180
X0302457Y0445787
X0298507Y0445908
X0318497Y0471484
X0323489Y0466528
X0318497Y0466528
X0323489Y0471484
X0321549Y0448115
X0321549Y0445315
X0347450Y0447486
X0358042Y0439718
X0358042Y0442518
X0345050Y0458334
X0366443Y0472189
X0367564Y0452740
X0367919Y0446318
X0367919Y0449118
X0364954Y0450091
X0274898Y0514608
X0274820Y0522134
X0274205Y0509626
X0274163Y0495088
X0274347Y0489435
X0284516Y0509626
X0284516Y0516713
X0292316Y0509626
X0292316Y0516713
X0284516Y0493839
X0292316Y0493839
X0318497Y0515617
X0323489Y0510661
X0318497Y0510661
X0328899Y0517774
X0323489Y0515617
X0328899Y0492769
X0328899Y0487813
X0333891Y0487813
X0333891Y0517774
X0333891Y0492769
X0353670Y0496118
X0356778Y0491870
X0359278Y0491870
X0353670Y0493618
X0353670Y0491118
X0353670Y0488618
X0361887Y0496258
X0361887Y0493758
X0365332Y0487570
X0365332Y0490070
X0358491Y0377173
X0315944Y0332584
X0318508Y0324322
X0315310Y0356712
X0318500Y0356519
X0312316Y0356747
X0308952Y0356875
X0274425Y0381500
X0277575Y0395084
X0366526Y0377173
X0365559Y0354300
X0353894Y0406060
X0354486Y0385123
X0366486Y0385123
X0347058Y0399918
X0349311Y0385644
X0359486Y0385123
X0357655Y0411089
X0357655Y0418889
X0357655Y0421489
X0357655Y0416289
X0357655Y0413689
X0358248Y0403300
X0357655Y0408489
X0357655Y0405889
X0347591Y0391533
X0349120Y0336100
X0350163Y0412106
X0354155Y0416289
X0354155Y0418889
X0354155Y0421489
X0339072Y0422088
X0339072Y0419488
X0339072Y0416888
X0368587Y0401066
X0362486Y0385123
X0350486Y0377173
X0351136Y0372334
X0317333Y0353470
X0301943Y0328867
X0312263Y0324518
X0297719Y0339559
X0295699Y0382047
X0298000Y0391496
X0292358Y0393858
X0321416Y0348015
X0292520Y0384410
X0299000Y0386500
X0299000Y0377912
X0316067Y0347937
X0294000Y0398583
X0298000Y0409000
X0299088Y0397912
X0296000Y0403500
X0291396Y0350223
X0274425Y0390500
X0292500Y0403307
X0292500Y0410394
X0284075Y0381500
X0320483Y0353506
X0315904Y0336324
X0306673Y0418838
X0309258Y0401924
X0309258Y0405924
X0309258Y0409924
X0301393Y0400039
X0301308Y0395346
X0309258Y0385912
X0309258Y0393924
X0309258Y0389912
X0301158Y0380307
X0301943Y0332017
X0306812Y0342319
X0302966Y0324139
X0361234Y0402867
X0357218Y0396866
X0357173Y0392183
X0354486Y0377173
X0348737Y0375386
X0348968Y0333138
X0361811Y0396866
X0364551Y0409032
X0368587Y0409016
X0361767Y0392228
X0364933Y0374232
X0368057Y0354184
X0285249Y0265896
X0332635Y0256394
X0287738Y0281982
X0281797Y0281716
X0325292Y0244571
X0290265Y0266114
X0322672Y0249108
X0280162Y0265701
X0359376Y0290592
X0329685Y0228646
X0334426Y0230556
X0351132Y0322202
X0348806Y0315427
X0348351Y0319372
X0285490Y0256303
X0308565Y0228631
X0338681Y0227824
X0340988Y0244297
X0365073Y0258880
X0314855Y0311740
X0327032Y0303962
X0343271Y0230117
X0365148Y0264180
X0367648Y0264180
X0314053Y0248371
X0271680Y0270026
X0274480Y0270026
X0274480Y0267526
X0271680Y0267526
X0276980Y0270026
X0276980Y0267526
X0328642Y0232971
X0338768Y0246874
X0286940Y0315039
X0333411Y0242078
X0326724Y0226320
X0339287Y0238714
X0315079Y0314890
X0296011Y0268195
X0293511Y0268195
X0293511Y0270695
X0296011Y0270695
X0295814Y0248765
X0293314Y0248765
X0295873Y0236189
X0293373Y0236189
X0291122Y0224421
X0292822Y0231021
X0292822Y0228221
X0298811Y0268195
X0298811Y0270695
X0304971Y0265897
X0302471Y0265897
X0298314Y0248765
X0298373Y0236189
X0276317Y0285690
X0271017Y0285690
X0273517Y0288190
X0271017Y0288190
X0273517Y0285690
X0276317Y0288190
X0278565Y0248891
X0273565Y0248891
X0276065Y0248891
X0273863Y0236611
X0277882Y0231786
X0278863Y0236611
X0276363Y0236611
X0269913Y0231461
X0273620Y0226141
X0277882Y0229286
X0269913Y0223661
X0276420Y0226141
X0269913Y0226461
X0269913Y0228961
X0288543Y0290755
X0280543Y0290755
X0284543Y0290755
X0296614Y0288345
X0296614Y0290845
X0296614Y0293645
X0294624Y0281307
X0290520Y0279208
X0289490Y0256535
X0281490Y0256535
X0281575Y0224712
X0310013Y0316731
X0299114Y0293645
X0299114Y0288345
X0299114Y0290845
X0319857Y0321649
X0323882Y0303839
X0314053Y0252371
X0328535Y0253198
X0328616Y0236121
X0325650Y0238589
X0348375Y0322284
X0356423Y0301288
X0343287Y0238714
X0335826Y0247292
X0335052Y0238689
X0367865Y0293796
X0365365Y0293796
X0361819Y0226226
X0361819Y0223726
X0361819Y0228726
X0361819Y0231226
X0303487Y0178560
X0300814Y0192859
X0317588Y0124879
X0284765Y0148277
X0312522Y0124283
X0322610Y0124663
X0299535Y0152373
X0287385Y0143740
X0327591Y0125107
X0323954Y0138838
X0300435Y0143518
X0312377Y0186778
X0308180Y0157370
X0330105Y0148717
X0336205Y0143762
X0303690Y0207037
X0303756Y0212455
X0303667Y0200864
X0312264Y0192665
X0312264Y0196665
X0295948Y0141247
X0312296Y0208864
X0303550Y0172665
X0302897Y0190185
X0285226Y0177616
X0303377Y0183834
X0361819Y0210478
X0361819Y0215478
X0361819Y0212978
X0361819Y0207978
X0297622Y0192490
X0288480Y0168697
X0285246Y0215632
X0269913Y0215713
X0281543Y0213859
X0281543Y0211359
X0285246Y0213132
X0269913Y0213213
X0269913Y0208213
X0276485Y0211695
X0273985Y0211695
X0276785Y0208695
X0273985Y0208695
X0269913Y0210713
X0277507Y0184221
X0280124Y0184012
X0283305Y0181009
X0280510Y0181366
X0277299Y0181426
X0285807Y0172190
X0278302Y0170493
X0278302Y0167993
X0278302Y0165393
X0278302Y0162793
X0271202Y0162368
X0302685Y0152562
X0307937Y0219379
X0326658Y0221970
X0326658Y0219470
X0326658Y0216970
X0323945Y0216385
X0320145Y0218085
X0317345Y0218085
X0312296Y0204864
X0304363Y0186629
X0289568Y0191941
X0312264Y0168665
X0312264Y0176665
X0310929Y0161306
X0329064Y0142862
X0279918Y0141247
X0342774Y0128828
X0339671Y0202048
X0332734Y0210509
X0335234Y0210509
X0337007Y0206806
X0334507Y0206806
X0336671Y0201748
X0339671Y0199248
X0340153Y0195176
X0337653Y0195176
X0336671Y0199248
X0332653Y0195176
X0335153Y0195176
X0276146Y0147540
X0342774Y0125428
X0335474Y0132515
X0335474Y0135915
X0291131Y0132509
X0280729Y0128796
X0291707Y0221708
X0294207Y0221708
X0296707Y0221708
X0296577Y0206767
X0294077Y0206767
X0291577Y0206767
X0301057Y0221642
X0279663Y0188727
X0279796Y0191941
X0276146Y0151540
X0278233Y0124618
X0278233Y0129574
X0292328Y0180572
X0290628Y0152367
X0288635Y0136687
X0293627Y0136687
X0291726Y0146461
X0293627Y0131731
X0293627Y0122513
X0283225Y0124618
X0283225Y0129574
X0288635Y0122513
X0288635Y0131731
X0281575Y0222212
X0288276Y0206760
X0286296Y0184619
X0292328Y0185165
X0312296Y0216864
X0312296Y0221864
X0312296Y0200864
X0312296Y0212864
X0296966Y0185121
X0299759Y0190285
X0312264Y0180665
X0312264Y0172665
X0297011Y0180527
X0326154Y0206838
X0317466Y0203393
X0322225Y0201683
X0319966Y0203393
X0323654Y0206838
X0317606Y0195176
X0320106Y0195176
X0325406Y0195176
X0322606Y0195176
X0322225Y0198883
X0316478Y0134579
X0329064Y0146012
X0322331Y0133298
X0314854Y0130898
X0341606Y0213539
X0333858Y0150847
X0345074Y0137756
X0330970Y0141228
X0337874Y0137757
X0333074Y0137757
X0340374Y0130670
X0333074Y0130670
X0333074Y0123584
X0337874Y0123584
X0340374Y0123583
X0345074Y0123583
X0345074Y0130670
X0337874Y0130670
X0354546Y0137756
X0359525Y0137756
X0354551Y0130670
X0353498Y0124576
X0363184Y0123583
X0363184Y0130670
X0280729Y0125396
X0291131Y0135909
X0323031Y0110784
X0289631Y0028281
X0318031Y0110784
X0284666Y0034068
X0290113Y0023188
X0322113Y0026187
X0337924Y0095111
X0353074Y0095236
X0288388Y0097475
X0295369Y0100625
X0304031Y0103621
X0271580Y0104249
X0271580Y0107649
X0362957Y0099961
X0342293Y0106561
X0363007Y0095236
X0299742Y0112083
X0311892Y0086046
X0308338Y0085731
X0293930Y0072615
X0353324Y0090650
X0358636Y0090615
X0293930Y0076587
X0316751Y0086012
X0307916Y0060529
X0308895Y0094351
X0312844Y0094279
X0310817Y0060393
X0289797Y0036735
X0269509Y0079993
X0269509Y0082593
X0269509Y0085193
X0269509Y0074793
X0269509Y0077393
X0342528Y0097667
X0269553Y0092874
X0342134Y0103411
X0329330Y0102495
X0312088Y0119594
X0312088Y0116594
X0316751Y0094374
X0305978Y0088801
X0312256Y0037543
X0330905Y0027806
X0324057Y0116594
X0324057Y0119594
X0333674Y0097667
X0288319Y0106186
X0281384Y0103783
X0277834Y0098551
X0301848Y0080581
X0301835Y0068581
X0305610Y0055513
X0335474Y0121742
X0342774Y0114655
X0342774Y0111255
X0335474Y0118342
X0280729Y0114623
X0291131Y0118335
X0277834Y0101701
X0278105Y0094017
X0274105Y0094017
X0278469Y0044773
X0278469Y0024773
X0278233Y0110445
X0278233Y0115401
X0293627Y0117557
X0296551Y0103621
X0285384Y0103783
X0283225Y0110445
X0283225Y0115401
X0288635Y0117557
X0286114Y0094017
X0282105Y0094017
X0291182Y0076140
X0291182Y0080140
X0291182Y0084140
X0286129Y0036971
X0304557Y0117261
X0312088Y0113394
X0305953Y0091951
X0310882Y0096613
X0308760Y0055513
X0309106Y0037543
X0314737Y0110784
X0316306Y0102249
X0327323Y0109172
X0320306Y0102249
X0324306Y0102249
X0313624Y0060922
X0330323Y0109172
X0333074Y0116497
X0340374Y0109410
X0345074Y0102323
X0345074Y0109410
X0340374Y0116497
X0337874Y0116497
X0345074Y0116496
X0329330Y0106495
X0342725Y0053597
X0335404Y0044773
X0330905Y0031806
X0330905Y0023806
X0335404Y0024773
X0353326Y0116496
X0353326Y0109410
X0353074Y0102323
X0353536Y0085584
X0356090Y0092849
X0353536Y0075184
X0353536Y0077784
X0353536Y0080384
X0353536Y0082984
X0363184Y0109410
X0363184Y0116496
X0363050Y0103037
X0362725Y0053597
X0291131Y0121735
X0280729Y0111223
X0321840Y0014408
X0322847Y0019806
X0330905Y0019806
X0330905Y0015806
X0279156Y0005374
X0294959Y0011097
X0298059Y0003000
X0318059Y0003000
X0330905Y0011806
X0334043Y0004469
X0381518Y0005374
X0388059Y0003000
X0408059Y0003000
X0448059Y0003000
X0428059Y0003000
X0468059Y0003000
X0468032Y0110784
X0390750Y0097475
X0397731Y0100625
X0406393Y0103621
X0373942Y0107649
X0373942Y0104249
X0402104Y0112083
X0413904Y0032569
X0414145Y0027486
X0404686Y0045448
X0400714Y0045448
X0410789Y0022627
X0422378Y0026534
X0387948Y0027288
X0422450Y0030483
X0388612Y0031168
X0371871Y0074793
X0371871Y0077393
X0371871Y0079993
X0371871Y0082593
X0371871Y0085193
X0371915Y0092874
X0462089Y0119594
X0462089Y0116594
X0422473Y0022627
X0416900Y0033400
X0390681Y0106186
X0383746Y0103783
X0380196Y0098551
X0396680Y0037543
X0408680Y0037530
X0383612Y0033768
X0383091Y0114623
X0393493Y0121735
X0371184Y0102323
X0371184Y0109410
X0371184Y0116496
X0376467Y0094017
X0387746Y0103783
X0380595Y0110445
X0385587Y0110445
X0380595Y0115401
X0385587Y0115401
X0390997Y0117557
X0380196Y0101701
X0380467Y0094017
X0388476Y0094017
X0384467Y0094017
X0393544Y0080140
X0393544Y0084140
X0393544Y0076140
X0380831Y0044773
X0383612Y0030618
X0380831Y0024773
X0388487Y0024069
X0398913Y0103621
X0395989Y0117557
X0408493Y0117577
X0420050Y0033425
X0466307Y0102249
X0462089Y0113394
X0464738Y0110784
X0393493Y0118335
X0383091Y0111223
X0434766Y0148277
X0467589Y0124879
X0462523Y0124283
X0449536Y0152373
X0437386Y0143740
X0395942Y0192300
X0405849Y0178560
X0450436Y0143518
X0414739Y0186778
X0458181Y0157370
X0406052Y0207037
X0414626Y0192665
X0414626Y0196665
X0445949Y0141247
X0406118Y0212455
X0406029Y0200864
X0414658Y0208864
X0426147Y0147540
X0405259Y0190185
X0399984Y0192490
X0405739Y0183834
X0388169Y0172190
X0390842Y0168697
X0387608Y0215632
X0372275Y0215713
X0383905Y0213859
X0378847Y0211695
X0387608Y0213132
X0383905Y0211359
X0372275Y0213213
X0372275Y0210713
X0376347Y0211695
X0376347Y0208695
X0379147Y0208695
X0372275Y0208213
X0379869Y0184221
X0382486Y0184012
X0385667Y0181009
X0379661Y0181426
X0382872Y0181366
X0405912Y0172665
X0387588Y0177616
X0380664Y0170493
X0380664Y0167993
X0380664Y0162793
X0380664Y0165393
X0373564Y0162368
X0370964Y0162368
X0452686Y0152562
X0410299Y0219379
X0467346Y0218085
X0406725Y0186629
X0414658Y0204864
X0391930Y0191941
X0414626Y0168665
X0414626Y0176665
X0460930Y0161306
X0429919Y0141247
X0393493Y0132509
X0394069Y0221708
X0393939Y0206767
X0403419Y0221642
X0396569Y0221708
X0399069Y0221708
X0396439Y0206767
X0398939Y0206767
X0371184Y0137756
X0371184Y0123583
X0371184Y0130670
X0390997Y0136687
X0380595Y0124618
X0385587Y0124618
X0380595Y0129574
X0385587Y0129574
X0390997Y0122513
X0390997Y0131731
X0383937Y0222212
X0390638Y0206760
X0382025Y0188727
X0388658Y0184619
X0382158Y0191941
X0399328Y0185121
X0394690Y0185165
X0403096Y0192421
X0394690Y0180572
X0399373Y0180527
X0395989Y0136687
X0395989Y0122513
X0395989Y0131731
X0414658Y0221864
X0414658Y0216864
X0414658Y0200864
X0414658Y0212864
X0414626Y0172665
X0414626Y0180665
X0426147Y0151540
X0440629Y0152367
X0441727Y0146461
X0467467Y0203393
X0467607Y0195176
X0466479Y0134579
X0464332Y0133298
X0383091Y0128796
X0383091Y0125396
X0393493Y0135909
X0390100Y0281982
X0384159Y0281716
X0392627Y0266114
X0382524Y0265701
X0387611Y0265896
X0415777Y0304470
X0427713Y0321965
X0419177Y0304470
X0427051Y0307470
X0423651Y0307470
X0434925Y0304470
X0431525Y0304470
X0387852Y0256303
X0410927Y0228631
X0464054Y0248371
X0379342Y0267526
X0379342Y0270026
X0376842Y0267526
X0374042Y0267526
X0376842Y0270026
X0374042Y0270026
X0403343Y0315158
X0405843Y0315158
X0393484Y0224421
X0395184Y0231021
X0398373Y0270695
X0395873Y0270695
X0395873Y0268195
X0398373Y0268195
X0401173Y0270695
X0401173Y0268195
X0404833Y0265897
X0407333Y0265897
X0395676Y0248765
X0398176Y0248765
X0400676Y0248765
X0395735Y0236189
X0398235Y0236189
X0400735Y0236189
X0395184Y0228221
X0375879Y0288190
X0373379Y0285690
X0375879Y0285690
X0373379Y0288190
X0375927Y0248891
X0376225Y0236611
X0378782Y0226141
X0372275Y0223661
X0372275Y0231461
X0372275Y0228961
X0375982Y0226141
X0372275Y0226461
X0390905Y0290755
X0382905Y0290755
X0386905Y0290755
X0378679Y0288190
X0378679Y0285690
X0392882Y0279208
X0383852Y0256535
X0391852Y0256535
X0380927Y0248891
X0378427Y0248891
X0380244Y0231786
X0378725Y0236611
X0381225Y0236611
X0383937Y0224712
X0380244Y0229286
X0409484Y0314921
X0398976Y0290845
X0398976Y0288345
X0401476Y0290845
X0401476Y0288345
X0401476Y0293645
X0398976Y0293645
X0396986Y0281307
X0411984Y0314921
X0414999Y0306966
X0419955Y0306966
X0422873Y0309966
X0427829Y0309966
X0430747Y0306966
X0435703Y0306966
X0464054Y0252371
X0400993Y0335589
X0400993Y0331589
X0448323Y0379643
X0421413Y0359053
X0411007Y0356743
X0416574Y0357528
X0412812Y0330617
X0435886Y0353867
X0428420Y0353578
X0400728Y0353152
X0443480Y0344014
X0443424Y0332988
X0412671Y0333418
X0430361Y0323187
X0415129Y0325181
X0422988Y0323627
X0410688Y0344736
X0426138Y0355079
X0434924Y0370309
X0463950Y0348407
X0460950Y0324785
X0460950Y0328185
X0431524Y0370309
X0463950Y0351807
X0446566Y0337917
X0460950Y0340533
X0460950Y0343933
X0463950Y0336059
X0409655Y0331589
X0443508Y0337713
X0410086Y0336795
X0463950Y0332659
X0448391Y0382641
X0440538Y0355372
X0436666Y0322583
X0441296Y0325061
X0426830Y0359026
X0467335Y0359944
X0394883Y0338377
X0394883Y0341777
X0370486Y0377173
X0455885Y0367702
X0450852Y0372054
X0371417Y0353820
X0370160Y0391569
X0383445Y0413611
X0385945Y0413611
X0380945Y0413611
X0378445Y0413611
X0384091Y0401981
X0381591Y0401981
X0381927Y0407039
X0381927Y0409539
X0378927Y0409539
X0383364Y0398278
X0385864Y0398278
X0378927Y0406739
X0378875Y0379088
X0394237Y0379591
X0381237Y0371076
X0384173Y0379028
X0373264Y0379429
X0420422Y0367859
X0412318Y0367903
X0391737Y0377581
X0377237Y0371060
X0434237Y0408104
X0431437Y0408104
X0428637Y0408104
X0433954Y0420375
X0431154Y0420375
X0428354Y0420375
X0418997Y0387210
X0418997Y0384710
X0418997Y0382210
X0394653Y0389402
X0401253Y0387702
X0398453Y0387702
X0406421Y0384651
X0406421Y0382151
X0406421Y0387151
X0391940Y0386317
X0391940Y0388817
X0391940Y0383817
X0376992Y0395248
X0373264Y0370010
X0393893Y0413611
X0392444Y0401949
X0396373Y0407104
X0385237Y0370976
X0389237Y0371070
X0392387Y0342555
X0392387Y0337599
X0401693Y0413611
X0399193Y0413611
X0396693Y0413611
X0409386Y0420393
X0402018Y0402642
X0399518Y0402642
X0394944Y0398949
X0406843Y0396661
X0406843Y0401661
X0406843Y0399161
X0409268Y0408240
X0396373Y0409904
X0394237Y0370899
X0407493Y0354142
X0397374Y0344439
X0398951Y0333711
X0411886Y0420393
X0414386Y0420393
X0418876Y0399161
X0414268Y0408240
X0411768Y0408240
X0418876Y0396661
X0418876Y0401661
X0424479Y0367859
X0416318Y0367903
X0413432Y0346797
X0421231Y0345776
X0421231Y0331255
X0421231Y0338523
X0458454Y0344711
X0458454Y0339755
X0458454Y0324007
X0458454Y0328963
X0430746Y0367813
X0435702Y0367813
X0430439Y0358115
X0435793Y0345738
X0428500Y0345776
X0435793Y0331255
X0428459Y0331255
X0466375Y0366365
X0461454Y0352585
X0461454Y0347629
X0461454Y0331881
X0461454Y0336837
X0448092Y0375770
X0453463Y0370694
X0405301Y0467560
X0459461Y0473805
X0459757Y0463520
X0459414Y0468689
X0414910Y0448931
X0438078Y0447121
X0432440Y0440101
X0432270Y0431112
X0421267Y0452799
X0437835Y0435101
X0438086Y0452601
X0426647Y0452987
X0438098Y0442114
X0432075Y0452718
X0405801Y0475560
X0418801Y0474513
X0385131Y0487382
X0451144Y0468809
X0459645Y0509486
X0376881Y0518564
X0385293Y0466409
X0385694Y0477318
X0397315Y0475560
X0393662Y0470382
X0385634Y0472020
X0393646Y0474382
X0412124Y0443721
X0414924Y0443721
X0395577Y0443893
X0385584Y0443893
X0412124Y0440921
X0414924Y0440921
X0412124Y0438121
X0412124Y0435321
X0414924Y0438121
X0414924Y0435321
X0395577Y0441093
X0395577Y0438293
X0385584Y0441093
X0385584Y0438293
X0375919Y0439318
X0375919Y0442118
X0383210Y0424067
X0385710Y0424067
X0380710Y0424067
X0378210Y0424067
X0429673Y0461607
X0459952Y0496842
X0459929Y0491669
X0460537Y0501905
X0468558Y0499669
X0468558Y0495669
X0464848Y0476535
X0467848Y0476535
X0414275Y0494969
X0424731Y0500204
X0424731Y0495204
X0424731Y0497704
X0427693Y0498943
X0414275Y0499969
X0414275Y0497469
X0424731Y0492704
X0414275Y0492469
X0438644Y0500461
X0435831Y0498923
X0427568Y0502003
X0435789Y0501525
X0464199Y0510184
X0387141Y0484882
X0424876Y0471334
X0468558Y0516609
X0445942Y0506449
X0448442Y0506449
X0450942Y0506449
X0448525Y0519699
X0446025Y0519699
X0448525Y0511512
X0446025Y0511512
X0462126Y0460435
X0465126Y0460435
X0467848Y0464566
X0464848Y0464566
X0433673Y0461607
X0425673Y0461607
X0397315Y0471560
X0376832Y0485580
X0374332Y0485580
X0371832Y0485580
X0376046Y0470001
X0373546Y0470001
X0373971Y0489036
X0376207Y0495636
X0376207Y0492836
X0415433Y0459170
X0422215Y0424939
X0422215Y0427439
X0411754Y0474513
X0397315Y0479560
X0393746Y0478382
X0393652Y0482382
X0369282Y0465288
X0369282Y0468088
X0376099Y0462309
X0376099Y0454309
X0376099Y0458309
X0375919Y0446318
X0375919Y0449118
X0393837Y0466409
X0385584Y0455641
X0385584Y0452841
X0385584Y0450041
X0393833Y0423944
X0395577Y0452841
X0395577Y0450041
X0399133Y0423944
X0401633Y0423944
X0396633Y0423944
X0415453Y0455039
X0411847Y0426740
X0411847Y0424240
X0395577Y0455641
X0427782Y0464026
X0432310Y0436164
X0433724Y0433975
X0418754Y0468607
X0446179Y0447101
X0373504Y0517954
X0393823Y0487382
X0424731Y0510952
X0414275Y0513217
X0414275Y0515717
X0414275Y0510717
X0414275Y0508217
X0424731Y0515952
X0424731Y0513452
X0424731Y0508152
X0435834Y0509580
X0432700Y0516277
X0427693Y0509020
X0438353Y0508685
X0438396Y0511493
X0427693Y0506520
X0442704Y0506427
X0443094Y0491251
X0468558Y0512669
X0468558Y0507669
X0468558Y0503669
X0468558Y0491669
X0451144Y0472809
X0453544Y0461961
X0468850Y0545586
X0455009Y0549712
X0455009Y0546912
X0455009Y0544312
X0455009Y0552312
X0455009Y0554912
X0443004Y0552490
X0452404Y0554990
X0452404Y0552390
X0443004Y0555090
X0452404Y0544390
X0452404Y0546990
X0443004Y0549890
X0452404Y0549790
X0431384Y0549990
X0431384Y0546990
X0431384Y0544390
X0431384Y0555190
X0431384Y0552590
X0428740Y0552590
X0428740Y0555190
X0428740Y0544390
X0428740Y0546990
X0442804Y0544390
X0442804Y0546990
X0428740Y0549990
X0419340Y0555190
X0419340Y0552590
X0419140Y0544790
X0419140Y0547390
X0419340Y0549990
X0419040Y0538890
X0419040Y0536290
X0419040Y0530990
X0419040Y0528390
X0419040Y0533690
X0439804Y0539182
X0442704Y0538990
X0439804Y0536682
X0442704Y0536390
X0431804Y0539182
X0428740Y0538890
X0431804Y0536682
X0428740Y0536290
X0442704Y0531090
X0442704Y0528490
X0428740Y0530990
X0428740Y0528390
X0442704Y0533790
X0428740Y0533690
X0452404Y0538890
X0455104Y0539082
X0452404Y0536290
X0455104Y0536582
X0452404Y0530990
X0452404Y0528390
X0452404Y0533690
X0463104Y0539082
X0468850Y0537507
X0463104Y0536582
X0456469Y0638302
X0453552Y0631779
X0423963Y0625778
X0447921Y0630789
X0441162Y0638313
X0447279Y0637031
X0446987Y0643360
X0443144Y0628667
X0426607Y0709760
X0426607Y0712360
X0431790Y0709799
X0429290Y0712399
X0431790Y0712399
X0429290Y0709799
X0434290Y0709799
X0434290Y0712399
X0436790Y0709799
X0439290Y0709799
X0436790Y0712399
X0439290Y0712399
X0391478Y0690675
X0386350Y0693559
X0388593Y0664232
X0403103Y0678060
X0408103Y0678060
X0405603Y0678060
X0400603Y0678060
X0400603Y0668060
X0403103Y0668060
X0408103Y0668060
X0405603Y0668060
X0410603Y0678060
X0410603Y0668060
X0418226Y0655788
X0417666Y0639838
X0418226Y0648980
X0418226Y0646480
X0420266Y0639838
X0423266Y0639838
X0417666Y0642638
X0420266Y0642638
X0423266Y0642638
X0418226Y0653288
X0423266Y0634238
X0423266Y0637038
X0417666Y0634238
X0417666Y0637038
X0420266Y0634238
X0420266Y0637038
X0417666Y0631438
X0420266Y0631438
X0423266Y0631438
X0441612Y0631011
X0441832Y0626193
X0436369Y0622883
X0447836Y0711199
X0448726Y0655788
X0448726Y0648980
X0448726Y0646480
X0448726Y0653288
X0447279Y0633881
X0464349Y0668016
X0466849Y0668016
X0459349Y0668016
X0461849Y0668016
X0464349Y0678016
X0461849Y0678016
X0459349Y0678016
X0466849Y0678016
X0430600Y0797400
X0421200Y0786400
X0426300Y0797400
X0372300Y0750000
X0389015Y0792725
X0392415Y0792725
X0380607Y0786932
X0380963Y0731000
X0459245Y0807152
X0434100Y0797400
X0380331Y0782627
X0373703Y0782555
X0383391Y0804000
X0432303Y0785067
X0384666Y0814103
X0381631Y0814147
X0371507Y0815303
X0370415Y0766108
X0372400Y0746300
X0423700Y0795500
X0381875Y0740341
X0387958Y0813700
X0424993Y0728291
X0391470Y0732865
X0407000Y0784700
X0371436Y0791188
X0397900Y0789000
X0400023Y0796792
X0397223Y0796792
X0429253Y0759847
X0379800Y0769200
X0376300Y0767300
X0373500Y0767300
X0406200Y0741300
X0407965Y0770196
X0408300Y0755487
X0415696Y0762466
X0400914Y0762675
X0409284Y0741316
X0400900Y0755400
X0415700Y0770200
X0400900Y0770100
X0415700Y0755400
X0406600Y0789000
X0408400Y0792200
X0408400Y0795200
X0379800Y0778000
X0376300Y0779800
X0373101Y0779608
X0393547Y0790056
X0387692Y0790056
X0429210Y0784833
X0377020Y0782535
X0462242Y0809792
X0382675Y0870151
X0460498Y0870334
X0463404Y0846870
X0465492Y0861970
X0383462Y0860535
X0401108Y0878487
X0397431Y0870654
X0396306Y0864409
X0425062Y0883981
X0405466Y0881299
X0404468Y0864407
X0392584Y0875845
X0406770Y0869767
X0386589Y0864408
X0416267Y0829193
X0413767Y0829193
X0413767Y0831693
X0416267Y0831693
X0411267Y0831693
X0411267Y0829193
X0386614Y0868286
X0407193Y0883566
X0406415Y0874840
X0406967Y0878764
X0399876Y0850677
X0402376Y0850677
X0399876Y0842677
X0402376Y0842677
X0411214Y0892109
X0425759Y0878321
X0422379Y0867229
X0425759Y0867121
X0425759Y0875521
X0425759Y0872721
X0425759Y0869921
X0424649Y0858644
X0422149Y0858644
X0424649Y0850644
X0422149Y0850644
X0422149Y0842644
X0424649Y0842644
X0422430Y0834800
X0428759Y0878321
X0428759Y0875521
X0428759Y0872721
X0428759Y0867121
X0432332Y0900449
X0432332Y0894849
X0432332Y0897649
X0432332Y0892049
X0428759Y0869921
X0460455Y0867050
X0463134Y0859203
X0370101Y0953699
X0384856Y0947987
X0382465Y1012430
X0383710Y1007283
X0372858Y0935136
X0380280Y1006071
X0378790Y1001083
X0451460Y0974695
X0370214Y0943812
X0458120Y0974701
X0370214Y0947812
X0378875Y0961862
X0397252Y0962861
X0379245Y0956643
X0378928Y0967812
X0379928Y0949774
X0396671Y0968287
X0393998Y0971780
X0425121Y0932186
X0417121Y0932186
X0409121Y0932186
X0401121Y0932186
X0399173Y0959468
X0401968Y0959111
X0402354Y0956465
X0404971Y0956256
X0405179Y0959051
X0391614Y0930676
X0425121Y0929686
X0417121Y0929686
X0409121Y0929686
X0401121Y0929686
X0417160Y0962261
X0414560Y0962261
X0411960Y0962261
X0413876Y0978109
X0416476Y0978109
X0411276Y0978109
X0404176Y0972484
X0404176Y0969984
X0404176Y0975084
X0404176Y0977684
X0404354Y0982970
X0409554Y0982970
X0406954Y0982970
X0467345Y0996480
X0459860Y1015825
X0459360Y1012325
X0447091Y1019766
X0432652Y1019384
X0429852Y1019384
X0427052Y1019384
X0427078Y1016186
X0429878Y1016186
X0432678Y1016186
X0464795Y1000647
X0453270Y1003763
X0370214Y0971812
X0370214Y0963812
X0392910Y0948536
X0378119Y0953696
X0459360Y1004680
X0451140Y1021793
X0462185Y1016825
X0459885Y1018860
X0443591Y1019766
X0450591Y1004766
X0370214Y0967812
X0370214Y0959812
X0371424Y0937185
X0375040Y0932959
X0385467Y0959950
X0390150Y0959905
X0391614Y0938651
X0381045Y1009444
X0381377Y1003008
X0390150Y0955312
X0385512Y0955356
X0402815Y0951750
X0402682Y0948536
X0396182Y0955858
X0409121Y0936686
X0401121Y0939186
X0409121Y0939186
X0401121Y0936686
X0417121Y0939186
X0417121Y0936686
X0425121Y0939186
X0425121Y0936686
X0453710Y1018825
X0449731Y1000855
X0452319Y1000828
X0456210Y1004680
X0448999Y0994483
X0454815Y0974622
X0467494Y0924532
X0431476Y1118396
X0463604Y1118396
X0450623Y1106867
X0418495Y1106867
X0459700Y1035716
X0459700Y1032266
X0449116Y1104792
X0457123Y1106897
X0416988Y1104792
X0424995Y1106897
X0423340Y1104335
X0468282Y1113797
X0468282Y1110897
X0468282Y1107997
X0420782Y1105552
X0452910Y1105552
X0452091Y1039880
X0450875Y1028416
X0457188Y1101917
X0425060Y1101917
X0443091Y1026266
X0443091Y1034266
X0408847Y1090956
X0412297Y1091227
X0412015Y1088205
X0415015Y1088205
X0415015Y1085205
X0414989Y1082501
X0412015Y1085205
X0411989Y1082501
X0436923Y1109397
X0437023Y1112397
X0434823Y1110897
X0434823Y1113797
X0439123Y1110597
X0441359Y1118801
X0441359Y1116101
X0439908Y1113648
X0446708Y1113648
X0444208Y1113648
X0402695Y1113797
X0404795Y1109397
X0404895Y1112397
X0406995Y1110597
X0409231Y1118801
X0407780Y1113648
X0412080Y1113648
X0414580Y1113648
X0402695Y1110897
X0434823Y1107997
X0436244Y1093088
X0439023Y1107997
X0402695Y1107997
X0406895Y1107997
X0430878Y1081816
X0433378Y1081816
X0436244Y1090288
X0433378Y1084316
X0433378Y1086816
X0430878Y1086816
X0430878Y1084316
X0433378Y1089316
X0433378Y1091816
X0409015Y1085205
X0409015Y1087705
X0408989Y1082501
X0408847Y1093956
X0463604Y1115896
X0464385Y1038534
X0455468Y1104335
X0427810Y1110092
X0431476Y1115896
X0459938Y1110092
X0462913Y1106365
X0429677Y1106955
X0412547Y1060697
X0415047Y1060697
X0412547Y1058097
X0415047Y1058097
X0405047Y1060697
X0410047Y1060697
X0407547Y1060697
X0405047Y1058097
X0410047Y1058097
X0407547Y1058097
X0399285Y1081599
X0430706Y1060498
X0430706Y1062998
X0433206Y1062998
X0433206Y1060498
X0433206Y1057998
X0430706Y1057998
X0430706Y1055498
X0433206Y1055498
X0417677Y1052215
X0450063Y1043140
X0449767Y1047047
X0396415Y1097278
X0398915Y1097278
X0419987Y1098518
X0417171Y1098887
X0425175Y1098767
X0420661Y1113822
X0418181Y1119422
X0418181Y1113822
X0423141Y1119422
X0423141Y1113822
X0420661Y1119422
X0455269Y1113822
X0452789Y1119422
X0452789Y1113822
X0450309Y1119422
X0450309Y1113822
X0455269Y1119422
X0450244Y1093068
X0446863Y1098428
X0452115Y1098518
X0457303Y1098767
X0450244Y1090268
X0443091Y1030266
X0443091Y1022766
X0460277Y1093068
X0460277Y1090268
X0462427Y1030218
X0465785Y1193471
X0461285Y1197471
X0461285Y1193471
X0465785Y1197471
X0380261Y1129692
X0378410Y1131573
X0372501Y1123695
X0432838Y1128821
X0429348Y1129092
X0468850Y1160834
X0462687Y1160834
X0437132Y1158266
X0433063Y1221428
X0429063Y1221428
X0425063Y1221428
X0421063Y1221428
X0417063Y1221428
X0413063Y1221428
X0409063Y1221428
X0405063Y1221428
X0401063Y1221428
X0397063Y1221428
X0449864Y1192621
X0449864Y1190121
X0430934Y1192621
X0430934Y1190121
X0417469Y1190121
X0417469Y1192621
X0422934Y1190121
X0422934Y1192621
X0404004Y1190121
X0404004Y1192621
X0447549Y1186921
X0447549Y1184421
X0447549Y1181921
X0447549Y1179421
X0457559Y1174884
X0455059Y1174884
X0439289Y1174884
X0436789Y1174884
X0427231Y1174884
X0429731Y1174884
X0433249Y1179209
X0433249Y1181709
X0433249Y1184209
X0433249Y1186709
X0411461Y1174884
X0420619Y1186921
X0420619Y1184421
X0420619Y1181921
X0420619Y1179421
X0406319Y1179209
X0406319Y1181709
X0406319Y1184209
X0406319Y1186709
X0408961Y1174884
X0457559Y1172384
X0455059Y1172384
X0455059Y1169884
X0455059Y1167384
X0455059Y1164884
X0455059Y1162384
X0457559Y1162384
X0457559Y1164884
X0457559Y1167384
X0457559Y1169884
X0439289Y1169884
X0439289Y1172384
X0427231Y1164884
X0427231Y1167384
X0427231Y1169884
X0427231Y1172384
X0429731Y1172384
X0429731Y1169884
X0429731Y1167384
X0429731Y1164884
X0429731Y1162384
X0427231Y1162384
X0439289Y1162384
X0439289Y1164884
X0439289Y1167384
X0436789Y1169884
X0436789Y1172384
X0436789Y1162384
X0436789Y1164884
X0436789Y1167384
X0411461Y1172384
X0411461Y1169884
X0411461Y1167384
X0411461Y1164884
X0411461Y1162384
X0403263Y1160834
X0408961Y1172384
X0408961Y1169884
X0408961Y1167384
X0408961Y1164884
X0408961Y1162384
X0369839Y1218940
X0406319Y1209405
X0406319Y1211905
X0406319Y1206905
X0404004Y1200821
X0404004Y1198321
X0406319Y1204405
X0403263Y1152684
X0406105Y1144435
X0406105Y1146935
X0406105Y1141935
X0406105Y1136935
X0406105Y1134435
X0406105Y1131935
X0409231Y1125801
X0407631Y1129301
X0410131Y1129301
X0406105Y1139435
X0409231Y1123101
X0420619Y1212117
X0420619Y1209617
X0420619Y1207117
X0417469Y1198321
X0417469Y1200821
X0420619Y1204617
X0422934Y1198321
X0422934Y1200821
X0412095Y1155213
X0412095Y1152713
X0422495Y1155213
X0422495Y1152713
X0425131Y1125801
X0417631Y1125801
X0420131Y1125801
X0412631Y1129301
X0415131Y1129301
X0417631Y1129301
X0420131Y1129301
X0422631Y1129301
X0425131Y1129301
X0422631Y1125801
X0417231Y1123101
X0419731Y1123101
X0429331Y1144435
X0429331Y1146935
X0437231Y1152402
X0437231Y1154902
X0438233Y1144435
X0438233Y1146935
X0438233Y1141935
X0435733Y1144435
X0435733Y1146935
X0435733Y1141935
X0429331Y1141935
X0438233Y1136935
X0438233Y1134435
X0438233Y1131935
X0435733Y1139435
X0435733Y1136935
X0435733Y1134435
X0435733Y1131935
X0429331Y1131935
X0429331Y1139435
X0429331Y1134435
X0429331Y1136935
X0442259Y1129301
X0439759Y1129301
X0441359Y1125801
X0438233Y1139435
X0441359Y1123101
X0433249Y1206905
X0433249Y1211905
X0433249Y1209405
X0430934Y1198321
X0430934Y1200821
X0433249Y1204405
X0452623Y1155213
X0452623Y1152713
X0443223Y1152713
X0443223Y1155213
X0454759Y1129301
X0457259Y1125801
X0454759Y1125801
X0452259Y1129301
X0449759Y1129301
X0447259Y1129301
X0444759Y1129301
X0452259Y1125801
X0449759Y1125801
X0457259Y1129301
X0451859Y1123101
X0449359Y1123101
X0447549Y1212117
X0447549Y1207117
X0447549Y1209617
X0449864Y1200821
X0449864Y1198321
X0447549Y1204617
X0461459Y1131935
X0461459Y1139435
X0461459Y1134435
X0461459Y1136935
X0461459Y1146935
X0461459Y1141935
X0468850Y1152684
X0462687Y1152684
X0461459Y1144435
X0370202Y1311364
X0370202Y1314764
X0440906Y1289198
X0463290Y1297035
X0404324Y1275889
X0404324Y1271889
X0459290Y1297035
X0413127Y1318011
X0404583Y1316131
X0413640Y1292856
X0403678Y1295426
X0434424Y1286274
X0431885Y1313115
X0454385Y1301845
X0444288Y1314391
X0419545Y1317722
X0409220Y1315516
X0402967Y1319815
X0408787Y1321795
X0404921Y1321819
X0401011Y1307258
X0419977Y1288843
X0407767Y1292198
X0413526Y1288938
X0431867Y1315696
X0454385Y1305245
X0385091Y1300853
X0385091Y1297453
X0430527Y1289198
X0386415Y1321645
X0398584Y1313443
X0451304Y1297045
X0443702Y1257160
X0446702Y1257160
X0446702Y1260160
X0443702Y1260160
X0449702Y1257160
X0449702Y1260160
X0428702Y1260160
X0434702Y1257160
X0434702Y1260160
X0431702Y1257160
X0431702Y1260160
X0428702Y1257160
X0437702Y1257160
X0437702Y1260160
X0440702Y1257160
X0440702Y1260160
X0419702Y1260160
X0419702Y1257160
X0425702Y1260160
X0422702Y1257160
X0422702Y1260160
X0425702Y1257160
X0433063Y1241428
X0433063Y1245428
X0429063Y1241428
X0429063Y1245428
X0425063Y1241428
X0425063Y1245428
X0421063Y1241428
X0421063Y1245428
X0417063Y1241428
X0417063Y1245428
X0413063Y1241428
X0413063Y1245428
X0409063Y1241428
X0409063Y1245428
X0405063Y1241428
X0405063Y1245428
X0401063Y1241428
X0433063Y1225428
X0433063Y1229428
X0433063Y1233428
X0433063Y1237428
X0429063Y1225428
X0429063Y1229428
X0429063Y1233428
X0429063Y1237428
X0425063Y1225428
X0425063Y1229428
X0425063Y1233428
X0425063Y1237428
X0421063Y1225428
X0421063Y1229428
X0421063Y1233428
X0421063Y1237428
X0417063Y1225428
X0417063Y1229428
X0417063Y1233428
X0417063Y1237428
X0413063Y1225428
X0413063Y1229428
X0413063Y1233428
X0413063Y1237428
X0409063Y1225428
X0409063Y1229428
X0409063Y1233428
X0409063Y1237428
X0405063Y1225428
X0405063Y1229428
X0405063Y1233428
X0405063Y1237428
X0401063Y1225428
X0401063Y1229428
X0401063Y1233428
X0401063Y1237428
X0397063Y1225428
X0397063Y1229428
X0397063Y1233428
X0454120Y1269498
X0463216Y1244055
X0463216Y1250760
X0461613Y1286776
X0456213Y1286776
X0463216Y1254164
X0391284Y1307238
X0387644Y1302089
X0387587Y1296675
X0399716Y1295198
X0397695Y1287071
X0423721Y1310523
X0425582Y1291743
X0413354Y1300197
X0423741Y1300115
X0418537Y1300197
X0411174Y1282776
X0413395Y1310481
X0418558Y1310523
X0413374Y1305298
X0423762Y1305298
X0440896Y1311366
X0437991Y1286544
X0451889Y1306023
X0456832Y1299121
X0451304Y1293045
X0451889Y1301067
X0405889Y1417275
X0402489Y1417275
X0419045Y1398874
X0420925Y1390330
X0395770Y1389817
X0398340Y1399779
X0392234Y1364501
X0392234Y1369579
X0404759Y1349072
X0408159Y1349072
X0418610Y1371590
X0425912Y1357141
X0425855Y1360495
X0417305Y1359169
X0395112Y1395690
X0391852Y1389931
X0391757Y1383480
X0410172Y1402446
X0420636Y1383912
X0422729Y1400490
X0418430Y1394237
X0423200Y1397500
X0423400Y1394500
X0416029Y1371572
X0429530Y1325051
X0391691Y1326715
X0439434Y1322369
X0399959Y1352153
X0425283Y1364023
X0419100Y1402200
X0421300Y1415400
X0421200Y1417900
X0468282Y1384297
X0443802Y1360099
X0452642Y1360099
X0464882Y1360099
X0468282Y1408495
X0456042Y1408495
X0443802Y1384297
X0456042Y1384297
X0440402Y1384297
X0468282Y1360099
X0464882Y1408495
X0440402Y1360099
X0464882Y1384297
X0456042Y1360099
X0452642Y1384297
X0452642Y1408495
X0468282Y1372385
X0464882Y1348187
X0456042Y1372385
X0452642Y1372385
X0443802Y1372385
X0468282Y1348187
X0456042Y1396583
X0440402Y1372385
X0443802Y1348187
X0440402Y1348187
X0456042Y1348187
X0464882Y1396583
X0452642Y1396583
X0452642Y1348187
X0464882Y1372385
X0468282Y1396583
X0425283Y1373958
X0436002Y1382252
X0406667Y1419771
X0401711Y1419771
X0403981Y1351568
X0394657Y1377875
X0389188Y1369033
X0435881Y1398800
X0435881Y1394934
X0398112Y1403741
X0410152Y1410928
X0389985Y1405762
X0388600Y1395500
X0414280Y1362561
X0395959Y1352153
X0408937Y1351568
X0389458Y1365466
X0413437Y1384899
X0408212Y1390083
X0408212Y1379695
X0413437Y1379736
X0403111Y1384920
X0403029Y1379716
X0403111Y1390103
X0413395Y1390062
X0404657Y1332967
X0408523Y1332967
X0444580Y1362595
X0439624Y1362595
X0444580Y1357603
X0439624Y1357603
X0439624Y1350683
X0444580Y1350683
X0439624Y1345691
X0444580Y1345691
X0464104Y1357603
X0464104Y1362595
X0451864Y1357603
X0451864Y1362595
X0456820Y1357603
X0456820Y1362595
X0456820Y1350683
X0464104Y1350683
X0451864Y1350683
X0464104Y1345691
X0451864Y1345691
X0456820Y1345691
X0432485Y1325784
X0439624Y1374881
X0439624Y1369889
X0439624Y1381801
X0439624Y1386793
X0444580Y1386793
X0451864Y1381801
X0451864Y1386793
X0456820Y1381801
X0456820Y1386793
X0444580Y1381801
X0444580Y1374881
X0451864Y1369795
X0456820Y1369795
X0444580Y1369889
X0451864Y1374881
X0456820Y1374881
X0456820Y1410991
X0451864Y1410991
X0456820Y1393993
X0451864Y1399079
X0451864Y1405999
X0451864Y1393993
X0456820Y1399079
X0456820Y1405999
X0464104Y1374881
X0464104Y1369889
X0464104Y1410991
X0464104Y1399079
X0464104Y1405999
X0464104Y1394087
X0464104Y1386793
X0464104Y1381801
X0413753Y1516886
X0417153Y1516886
X0395888Y1450022
X0417334Y1477101
X0415202Y1496118
X0413934Y1477101
X0415202Y1499518
X0411000Y1451000
X0404500Y1452500
X0411000Y1454500
X0395370Y1501022
X0398747Y1500959
X0395380Y1485778
X0395199Y1482223
X0411000Y1457500
X0411000Y1460500
X0411000Y1463500
X0397266Y1514647
X0397266Y1518047
X0407970Y1449751
X0393951Y1447455
X0393094Y1423600
X0395894Y1423600
X0419467Y1519706
X0411353Y1519440
X0404053Y1513673
X0394000Y1508100
X0419818Y1474945
X0411147Y1474993
X0415095Y1502750
X0415241Y1492990
X0397220Y1521207
X0397245Y1511640
X0399731Y1442755
X0407854Y1492118
X0407469Y1495035
X0406377Y1499142
X0401990Y1446807
X0454125Y1465913
X0454125Y1502514
X0454125Y1507245
X0454125Y1511976
X0454125Y1496621
X0454125Y1487159
X0454125Y1491890
X0454125Y1476536
X0454125Y1481267
X0454125Y1471805
X0454125Y1461182
X0462786Y1465513
X0462786Y1460782
X0462786Y1516307
X0462786Y1500952
X0462786Y1506845
X0462786Y1511576
X0462786Y1485598
X0462786Y1491490
X0462786Y1496221
X0462786Y1470244
X0462786Y1476136
X0462786Y1480867
X0410596Y1561024
X0391740Y1555829
X0391740Y1540529
X0426701Y1541947
X0391740Y1550729
X0400396Y1561024
X0422539Y1534361
X0391740Y1545629
X0395296Y1561024
X0421454Y1544625
X0405496Y1561024
X0418151Y1552470
X0399373Y1555855
X0419619Y1539978
X0408964Y1531149
X0394391Y1535286
X0394391Y1537786
X0389700Y1536900
X0417461Y1569584
X0401461Y1569560
X0397461Y1569560
X0382017Y1559700
X0381900Y1544800
X0429784Y1548222
X0410626Y1525991
X0420279Y1525978
X0382017Y1551700
X0382017Y1547700
X0382017Y1555700
X0405461Y1569560
X0409461Y1569560
X0400911Y1549936
X0407048Y1549936
X0400911Y1544424
X0407048Y1537902
X0400911Y1537902
X0413461Y1569560
X0421616Y1549885
X0413012Y1549936
X0426196Y1534087
X0413012Y1544098
X0413012Y1537902
X0430657Y1563562
X0437675Y1550158
X0454125Y1604876
X0454125Y1598984
X0454125Y1594253
X0454125Y1589522
X0454125Y1583629
X0454125Y1574167
X0454125Y1563544
X0454125Y1568275
X0454125Y1578898
X0454125Y1558813
X0454125Y1614338
X0454125Y1609607
X0462786Y1603315
X0462786Y1598584
X0462786Y1609207
X0462786Y1587960
X0462786Y1583229
X0462786Y1593853
X0462786Y1572606
X0462786Y1567875
X0462786Y1578498
X0462786Y1563144
X0462786Y1618669
X0462786Y1613938
X0372000Y1644980
X0392000Y1644980
X0412000Y1644980
X0432000Y1644980
X0452000Y1644980
X0472000Y1644980
X0492000Y1644980
X0512000Y1644980
X0532000Y1644980
X0552000Y1644980
X0568279Y1538438
X0557584Y1543411
X0563968Y1541445
X0565400Y1535100
X0567324Y1528151
X0566800Y1541800
X0565600Y1530800
X0560635Y1543531
X0471448Y1604876
X0471448Y1609607
X0471448Y1598984
X0471448Y1583629
X0471448Y1589522
X0471448Y1594253
X0471448Y1578898
X0471448Y1563544
X0471448Y1568275
X0471448Y1574167
X0471448Y1558813
X0471448Y1614338
X0480109Y1593853
X0488771Y1594253
X0480109Y1587960
X0480109Y1583229
X0488771Y1583629
X0488771Y1589522
X0480109Y1572606
X0480109Y1567875
X0488771Y1563544
X0488771Y1568275
X0488771Y1574167
X0480109Y1578498
X0488771Y1578898
X0480109Y1563144
X0488771Y1558813
X0480109Y1618669
X0480109Y1613938
X0488771Y1614338
X0480109Y1603315
X0480109Y1598584
X0480109Y1609207
X0488771Y1598984
X0488771Y1604876
X0488771Y1609607
X0506093Y1558813
X0497432Y1563144
X0506093Y1614338
X0497432Y1618669
X0497432Y1613938
X0497432Y1603315
X0497432Y1598584
X0506093Y1609607
X0497432Y1609207
X0506093Y1598984
X0506093Y1604876
X0497432Y1583229
X0506093Y1594253
X0497432Y1593853
X0506093Y1583629
X0506093Y1589522
X0497432Y1587960
X0506093Y1563544
X0506093Y1568275
X0506093Y1574167
X0497432Y1572606
X0497432Y1567875
X0506093Y1578898
X0497432Y1578498
X0514755Y1618669
X0514755Y1613938
X0514755Y1598584
X0514755Y1609207
X0514755Y1603315
X0514755Y1587960
X0514755Y1583229
X0514755Y1593853
X0514755Y1578498
X0514755Y1572606
X0514755Y1567875
X0514755Y1563144
X0471448Y1465913
X0471448Y1461182
X0471448Y1507245
X0471448Y1502514
X0471448Y1511976
X0471448Y1487159
X0471448Y1491890
X0471448Y1496621
X0471448Y1476536
X0471448Y1471805
X0471448Y1481267
X0488771Y1496621
X0480109Y1485598
X0480109Y1491490
X0488771Y1491890
X0488771Y1487159
X0480109Y1496221
X0480109Y1480867
X0488771Y1481267
X0488771Y1476536
X0488771Y1471805
X0480109Y1470244
X0480109Y1476136
X0488771Y1461182
X0488771Y1465913
X0480109Y1465513
X0480109Y1460782
X0480109Y1516307
X0488771Y1507245
X0488771Y1502514
X0480109Y1500952
X0480109Y1506845
X0480109Y1511576
X0488771Y1511976
X0497432Y1516307
X0497432Y1511576
X0506093Y1507245
X0506093Y1502514
X0497432Y1500952
X0497432Y1506845
X0506093Y1511976
X0506093Y1496621
X0506093Y1491890
X0506093Y1487159
X0497432Y1485598
X0497432Y1491490
X0497432Y1496221
X0506093Y1476536
X0506093Y1471805
X0497432Y1470244
X0497432Y1476136
X0506093Y1481267
X0497432Y1480867
X0506093Y1461182
X0497432Y1460782
X0506093Y1465913
X0497432Y1465513
X0514755Y1496221
X0514755Y1485598
X0514755Y1491490
X0514755Y1470244
X0514755Y1476136
X0514755Y1480867
X0514755Y1465513
X0514755Y1460782
X0514755Y1516307
X0514755Y1500952
X0514755Y1506845
X0514755Y1511576
X0477122Y1384297
X0480522Y1384297
X0489362Y1360099
X0492762Y1360099
X0489362Y1408495
X0492762Y1408495
X0501602Y1384297
X0505002Y1384297
X0513842Y1384297
X0526082Y1360099
X0517242Y1384297
X0529482Y1360099
X0480522Y1408495
X0492762Y1384297
X0489362Y1384297
X0505002Y1360099
X0477122Y1360099
X0501602Y1360099
X0480522Y1360099
X0477122Y1408495
X0538322Y1348187
X0550562Y1348187
X0541722Y1348187
X0550562Y1396583
X0513842Y1348187
X0566202Y1348187
X0562802Y1348187
X0538322Y1360099
X0553962Y1372385
X0526082Y1348187
X0562802Y1396583
X0526082Y1384297
X0513842Y1408495
X0526082Y1372385
X0538322Y1372385
X0517242Y1408495
X0562802Y1372385
X0538322Y1408495
X0513842Y1396583
X0529482Y1348187
X0513842Y1372385
X0541722Y1408495
X0501602Y1372385
X0529482Y1396583
X0538322Y1396583
X0517242Y1396583
X0492762Y1372385
X0541722Y1360099
X0562802Y1360099
X0501602Y1396583
X0566202Y1360099
X0477122Y1348187
X0517242Y1360099
X0529482Y1384297
X0489362Y1396583
X0562802Y1408495
X0477122Y1396583
X0505002Y1348187
X0550562Y1384297
X0492762Y1396583
X0489362Y1372385
X0480522Y1372385
X0480522Y1348187
X0553962Y1384297
X0489362Y1348187
X0513842Y1360099
X0477122Y1372385
X0566202Y1408495
X0501602Y1348187
X0480522Y1396583
X0505002Y1372385
X0550562Y1360099
X0492762Y1348187
X0550562Y1408495
X0562802Y1384297
X0553962Y1360099
X0541722Y1384297
X0553962Y1408495
X0566202Y1384297
X0538322Y1384297
X0526082Y1408495
X0501602Y1408495
X0529482Y1408495
X0505002Y1408495
X0500824Y1374881
X0500824Y1381801
X0500824Y1369889
X0500824Y1386793
X0505780Y1386793
X0518020Y1386793
X0513064Y1386793
X0505780Y1369889
X0518020Y1374881
X0518020Y1381801
X0518020Y1369889
X0513064Y1374881
X0513064Y1381801
X0513064Y1369889
X0505780Y1374881
X0505780Y1381801
X0476344Y1350683
X0481300Y1350683
X0469060Y1350683
X0476344Y1345691
X0481300Y1345691
X0469060Y1345691
X0530260Y1386793
X0537544Y1381801
X0537544Y1369889
X0530260Y1374881
X0530260Y1381801
X0530260Y1369889
X0525304Y1374881
X0525304Y1381801
X0525304Y1369889
X0537544Y1374881
X0469060Y1362595
X0476344Y1357603
X0476344Y1362595
X0481300Y1357603
X0481300Y1362595
X0469060Y1357603
X0525304Y1386793
X0537544Y1386793
X0493540Y1350683
X0488584Y1350683
X0493540Y1345691
X0488584Y1345691
X0542500Y1386793
X0549784Y1386793
X0554740Y1386793
X0554740Y1369889
X0542500Y1381801
X0542500Y1369889
X0549784Y1374881
X0549784Y1381801
X0549784Y1369889
X0542500Y1374881
X0554740Y1374881
X0554740Y1381801
X0488584Y1362595
X0493540Y1357603
X0493540Y1362595
X0488584Y1357603
X0562024Y1386793
X0566980Y1386793
X0566980Y1374881
X0566980Y1381801
X0566980Y1369889
X0562024Y1374881
X0562024Y1381801
X0562024Y1369889
X0469060Y1374881
X0476344Y1374881
X0469060Y1369889
X0476344Y1369889
X0469060Y1410991
X0469060Y1405999
X0469060Y1394087
X0469060Y1399079
X0469060Y1381801
X0469060Y1386793
X0476344Y1381801
X0476344Y1386793
X0481300Y1374881
X0481300Y1369889
X0488584Y1369889
X0493540Y1369889
X0493540Y1374881
X0488584Y1374881
X0493540Y1410991
X0481300Y1410991
X0488584Y1410991
X0488584Y1399079
X0488584Y1405999
X0481300Y1394087
X0488584Y1394087
X0476344Y1399079
X0476344Y1405999
X0476344Y1394087
X0493540Y1399079
X0493540Y1405999
X0493540Y1394087
X0481300Y1399079
X0481300Y1405999
X0481300Y1386793
X0481300Y1381801
X0493540Y1381801
X0493540Y1386793
X0488584Y1381801
X0488584Y1386793
X0476344Y1410991
X0505780Y1345691
X0518020Y1345691
X0513064Y1350683
X0505780Y1350683
X0518020Y1350683
X0500824Y1345691
X0500824Y1350683
X0505780Y1394087
X0513064Y1399079
X0513064Y1405999
X0513064Y1394087
X0500824Y1399079
X0500824Y1405999
X0505780Y1399079
X0505780Y1405999
X0500824Y1394087
X0500824Y1357603
X0500824Y1362595
X0518020Y1362595
X0513064Y1357603
X0513064Y1362595
X0505780Y1357603
X0505780Y1362595
X0518020Y1357603
X0513064Y1345691
X0513064Y1410991
X0500824Y1410991
X0505780Y1410991
X0537544Y1362595
X0530260Y1357603
X0525304Y1357603
X0530260Y1362595
X0525304Y1362595
X0537544Y1357603
X0537544Y1345691
X0530260Y1350683
X0525304Y1350683
X0537544Y1350683
X0530260Y1345691
X0525304Y1345691
X0525304Y1410991
X0530260Y1410991
X0518020Y1410991
X0518020Y1399079
X0518020Y1405999
X0525304Y1399079
X0525304Y1405999
X0518020Y1394087
X0525304Y1394087
X0530260Y1399079
X0530260Y1405999
X0530260Y1394087
X0554740Y1350683
X0549784Y1350683
X0542500Y1350683
X0549784Y1345597
X0542500Y1345691
X0554740Y1345597
X0537544Y1394087
X0542500Y1394087
X0549784Y1399079
X0549784Y1405999
X0549784Y1393993
X0537544Y1399079
X0537544Y1405999
X0542500Y1399079
X0542500Y1405999
X0549784Y1357603
X0542500Y1357603
X0549784Y1362595
X0542500Y1362595
X0554740Y1357603
X0554740Y1362595
X0549784Y1410991
X0537544Y1410991
X0542500Y1410991
X0554740Y1393993
X0562024Y1394087
X0562024Y1405999
X0562024Y1399079
X0566980Y1394087
X0566980Y1405999
X0566980Y1399079
X0554740Y1399079
X0554740Y1405999
X0562024Y1362595
X0566980Y1362595
X0566980Y1357603
X0562024Y1357603
X0566980Y1350683
X0566980Y1345691
X0562024Y1345691
X0562024Y1350683
X0562024Y1410991
X0566980Y1410991
X0554740Y1410991
X0550562Y1372385
X0541722Y1396583
X0541722Y1372385
X0566202Y1396583
X0526082Y1396583
X0553962Y1396583
X0517242Y1372385
X0566202Y1372385
X0529482Y1372385
X0517242Y1348187
X0505002Y1396583
X0553962Y1348187
X0487600Y1302100
X0490100Y1302100
X0504647Y1260160
X0507347Y1260160
X0498647Y1260160
X0498647Y1257160
X0495647Y1257160
X0492647Y1257160
X0492647Y1260160
X0495647Y1260160
X0501647Y1260160
X0501647Y1257160
X0507347Y1257160
X0504647Y1257160
X0483647Y1260160
X0483647Y1257160
X0480647Y1260160
X0477647Y1260160
X0477647Y1257160
X0480647Y1257160
X0486647Y1260160
X0486647Y1257160
X0489647Y1257160
X0489647Y1260160
X0471647Y1260160
X0471647Y1257160
X0474647Y1257160
X0474647Y1260160
X0510562Y1246194
X0510562Y1242194
X0514562Y1246194
X0514562Y1242194
X0498562Y1246194
X0498562Y1242194
X0502562Y1246194
X0502562Y1242194
X0506562Y1246194
X0506562Y1242194
X0494562Y1242194
X0494562Y1246194
X0510562Y1238194
X0510562Y1234194
X0510562Y1230194
X0510562Y1226194
X0514562Y1238194
X0514562Y1234194
X0514562Y1230194
X0514562Y1226194
X0518562Y1234194
X0518562Y1230194
X0518562Y1226194
X0522562Y1226194
X0494562Y1238194
X0494562Y1234194
X0494562Y1230194
X0494562Y1226194
X0498562Y1238194
X0498562Y1234194
X0498562Y1230194
X0498562Y1226194
X0502562Y1238194
X0502562Y1234194
X0502562Y1230194
X0502562Y1226194
X0506562Y1238194
X0506562Y1234194
X0506562Y1230194
X0506562Y1226194
X0520548Y1287181
X0514363Y1287370
X0517374Y1287222
X0484800Y1302000
X0564890Y1218169
X0560211Y1185164
X0566058Y1185164
X0560211Y1172564
X0566058Y1172564
X0560211Y1159964
X0566058Y1159964
X0560211Y1147364
X0566058Y1147364
X0560211Y1134764
X0566058Y1134764
X0568532Y1200001
X0495236Y1129094
X0498727Y1128759
X0502562Y1158200
X0510562Y1222194
X0514562Y1222194
X0518562Y1222194
X0522562Y1222194
X0494562Y1222194
X0498562Y1222194
X0502562Y1222194
X0506562Y1222194
X0523066Y1192621
X0523066Y1190121
X0496136Y1192621
X0496136Y1190121
X0504136Y1192621
X0504136Y1190121
X0477206Y1190121
X0477206Y1192621
X0490671Y1190121
X0490671Y1192621
X0520646Y1174884
X0523146Y1174884
X0520751Y1179421
X0520751Y1181921
X0520751Y1184421
X0520751Y1186921
X0502376Y1174884
X0495318Y1174884
X0492818Y1174884
X0493821Y1179421
X0493821Y1181921
X0493821Y1184421
X0493821Y1186921
X0504876Y1174884
X0506451Y1186709
X0506451Y1184209
X0506451Y1181709
X0506451Y1179209
X0477048Y1174884
X0479521Y1186709
X0479521Y1184209
X0479521Y1181709
X0479521Y1179209
X0474548Y1174884
X0528274Y1160834
X0520646Y1172384
X0523146Y1172384
X0523146Y1169884
X0523146Y1167384
X0523146Y1164884
X0523146Y1162384
X0520646Y1162384
X0520646Y1164884
X0520646Y1167384
X0520646Y1169884
X0495318Y1162384
X0495318Y1164884
X0495318Y1167384
X0495318Y1169884
X0495318Y1172384
X0492818Y1172384
X0492818Y1169884
X0492818Y1167384
X0492818Y1164884
X0492818Y1162384
X0504876Y1162384
X0504876Y1164884
X0504876Y1167384
X0504876Y1169884
X0504876Y1172384
X0502376Y1162384
X0502376Y1164884
X0502376Y1167384
X0502376Y1169884
X0502376Y1172384
X0477048Y1162384
X0477048Y1164884
X0477048Y1167384
X0477048Y1169884
X0477048Y1172384
X0474548Y1162384
X0474548Y1164884
X0474548Y1167384
X0474548Y1169884
X0474548Y1172384
X0469192Y1134435
X0469192Y1136935
X0469192Y1139435
X0471692Y1131935
X0471692Y1134435
X0471692Y1136935
X0471692Y1139435
X0473218Y1129301
X0474818Y1125801
X0474818Y1123101
X0471692Y1144435
X0469192Y1141935
X0469192Y1146935
X0469192Y1144435
X0471692Y1141935
X0471692Y1146935
X0469192Y1131935
X0482818Y1123101
X0479521Y1209405
X0479521Y1211905
X0479521Y1206905
X0477206Y1200821
X0479521Y1204405
X0490671Y1200821
X0490671Y1198321
X0477206Y1198321
X0488082Y1152713
X0488082Y1155213
X0477682Y1155213
X0477682Y1152713
X0488218Y1129301
X0490718Y1125801
X0488218Y1125801
X0485718Y1129301
X0483218Y1129301
X0480718Y1129301
X0478218Y1129301
X0475718Y1129301
X0485718Y1125801
X0483218Y1125801
X0490718Y1129301
X0485318Y1123101
X0502562Y1155213
X0502562Y1152713
X0494918Y1141935
X0494918Y1144435
X0494918Y1146935
X0501320Y1141935
X0501320Y1146935
X0501320Y1144435
X0503820Y1141935
X0503820Y1146935
X0503820Y1144435
X0494918Y1131935
X0494918Y1139435
X0494918Y1134435
X0494918Y1136935
X0501320Y1131935
X0501320Y1134435
X0501320Y1136935
X0501320Y1139435
X0503820Y1131935
X0503820Y1134435
X0503820Y1136935
X0503820Y1139435
X0507846Y1129301
X0505346Y1129301
X0506946Y1125801
X0506946Y1123101
X0493821Y1212117
X0493821Y1209617
X0493821Y1207117
X0506451Y1209405
X0506451Y1211905
X0506451Y1206905
X0496136Y1198321
X0496136Y1200821
X0493821Y1204617
X0504136Y1200821
X0504136Y1198321
X0506451Y1204405
X0517446Y1123101
X0514946Y1123101
X0520751Y1212117
X0520751Y1209617
X0520751Y1207117
X0523066Y1198321
X0523066Y1200821
X0520751Y1204617
X0508810Y1155213
X0508810Y1152713
X0518210Y1152713
X0518210Y1155213
X0520346Y1129301
X0522846Y1125801
X0520346Y1125801
X0517846Y1129301
X0515346Y1129301
X0512846Y1129301
X0510346Y1129301
X0517846Y1125801
X0515346Y1125801
X0522846Y1129301
X0527046Y1141935
X0527046Y1144435
X0527046Y1146935
X0528274Y1152684
X0527046Y1136935
X0527046Y1134435
X0527046Y1139435
X0527046Y1131935
X0566502Y1202103
X0563673Y1204932
X0566020Y1177691
X0560211Y1177691
X0560211Y1165091
X0566020Y1165091
X0560211Y1152491
X0566020Y1152491
X0560211Y1127291
X0566020Y1127291
X0560211Y1139891
X0566020Y1139891
X0497063Y1118396
X0529191Y1118396
X0484082Y1106867
X0516210Y1106867
X0485633Y1036155
X0485678Y1039880
X0519500Y1028377
X0565057Y1030672
X0568057Y1030672
X0560211Y1122164
X0566058Y1122164
X0560211Y1109564
X0566058Y1109564
X0567484Y1024003
X0514843Y1030766
X0545566Y1023731
X0556493Y1118351
X0482575Y1104792
X0473639Y1030952
X0475588Y1043055
X0522710Y1106897
X0470610Y1033783
X0470978Y1046591
X0490582Y1106897
X0471755Y1038665
X0562057Y1030563
X0559057Y1030563
X0514703Y1104792
X0471558Y1029482
X0493397Y1110092
X0525525Y1110092
X0529191Y1115896
X0502510Y1109397
X0500410Y1110897
X0502610Y1112397
X0500410Y1113797
X0504710Y1110597
X0506946Y1118801
X0506946Y1116101
X0505495Y1113648
X0512295Y1113648
X0509795Y1113648
X0470382Y1109397
X0470482Y1112397
X0472582Y1110597
X0474818Y1118801
X0474818Y1116101
X0473367Y1113648
X0477667Y1113648
X0480167Y1113648
X0500410Y1107997
X0501831Y1093088
X0504610Y1107997
X0472482Y1107997
X0474277Y1093048
X0501831Y1090288
X0494003Y1084296
X0496503Y1084296
X0499003Y1084296
X0501503Y1084296
X0501503Y1086796
X0499003Y1086796
X0496503Y1086796
X0494003Y1086796
X0476017Y1086724
X0476017Y1084224
X0476017Y1081724
X0478517Y1081724
X0478517Y1084224
X0478517Y1086724
X0491503Y1084296
X0491503Y1086796
X0474348Y1090171
X0477607Y1089942
X0477765Y1093432
X0521055Y1104335
X0497063Y1115896
X0488927Y1104335
X0490647Y1101917
X0522775Y1101917
X0551673Y1023900
X0528500Y1106365
X0496372Y1106298
X0486369Y1105552
X0518497Y1105552
X0500677Y1060697
X0498177Y1060697
X0493177Y1060697
X0495677Y1060697
X0503177Y1060697
X0500677Y1058097
X0498177Y1058097
X0493177Y1058097
X0495677Y1058097
X0503177Y1058097
X0505981Y1052487
X0478648Y1060498
X0478648Y1062998
X0476148Y1062998
X0476148Y1060498
X0478648Y1057998
X0478648Y1055498
X0476148Y1055498
X0476148Y1057998
X0469495Y1023303
X0480322Y1098428
X0485574Y1098518
X0490762Y1098767
X0475495Y1023303
X0481495Y1023303
X0488728Y1113822
X0483768Y1119422
X0486248Y1119422
X0486248Y1113822
X0483768Y1113822
X0488728Y1119422
X0506566Y1030766
X0515896Y1119422
X0515896Y1113822
X0520856Y1119422
X0522890Y1098767
X0515831Y1093068
X0512450Y1098428
X0517702Y1098518
X0515831Y1090568
X0519792Y1031271
X0520856Y1113822
X0518376Y1119422
X0518376Y1113822
X0557681Y1035088
X0560211Y1114691
X0566020Y1114691
X0566020Y1102091
X0560211Y1102091
X0565451Y1035102
X0488041Y1020440
X0552238Y0959102
X0554696Y1018469
X0498524Y0997590
X0560912Y1009655
X0558112Y1009655
X0491616Y0938771
X0514690Y1004766
X0503144Y0957934
X0530473Y0961728
X0514690Y0996766
X0514649Y1020266
X0568923Y0988813
X0556923Y0988813
X0552923Y0988813
X0560923Y0988813
X0545094Y1013678
X0564923Y0988813
X0471068Y0930235
X0479613Y0952189
X0473992Y0952546
X0474540Y0927341
X0476475Y0952249
X0489163Y0977163
X0551485Y1006648
X0544719Y1007522
X0548852Y1018307
X0523289Y0939195
X0503933Y0981392
X0493091Y0989550
X0527879Y0952189
X0506702Y0978947
X0487091Y0989550
X0521353Y0952266
X0512232Y0985172
X0522544Y0992854
X0520146Y0939241
X0556923Y0980523
X0560923Y0980443
X0542793Y0998507
X0494315Y0941212
X0477857Y1004375
X0480711Y0999941
X0475018Y0992568
X0471876Y0937236
X0506888Y0985171
X0504088Y0985171
X0506566Y0996766
X0506566Y1008766
X0514566Y1000766
X0506566Y1012266
X0514566Y1016266
X0563103Y0951807
X0566303Y0951807
X0562328Y0957307
X0498435Y1008766
X0498585Y1016266
X0565003Y0936807
X0568503Y0936807
X0528674Y0964851
X0469495Y1017303
X0469495Y1011303
X0481495Y1017303
X0475495Y1011303
X0481495Y1011303
X0490143Y0989521
X0483636Y0952152
X0488388Y0938903
X0481943Y0924633
X0506566Y1004766
X0506566Y1000766
X0493050Y0976078
X0499595Y0963963
X0506566Y1016266
X0514886Y0952189
X0524475Y0952290
X0516256Y0939157
X0509471Y0981608
X0541766Y1018368
X0552923Y0997860
X0548215Y1006560
X0568362Y1011762
X0568362Y1008262
X0556923Y0997860
X0568923Y0997860
X0560923Y0997860
X0564923Y0997860
X0517702Y0826600
X0479700Y0847600
X0567827Y0884000
X0509665Y0824512
X0490706Y0859339
X0564165Y0894411
X0498507Y0865392
X0503383Y0863025
X0471110Y0921577
X0471726Y0883705
X0495700Y0849389
X0495470Y0844271
X0477574Y0860815
X0524741Y0845149
X0530741Y0845149
X0548665Y0850399
X0537300Y0842900
X0544741Y0823149
X0495073Y0835586
X0494677Y0830468
X0557836Y0851669
X0556326Y0829989
X0531313Y0826630
X0479448Y0828594
X0509791Y0881932
X0472399Y0839566
X0546940Y0871389
X0531076Y0913190
X0530968Y0888283
X0538468Y0888033
X0533143Y0897910
X0516902Y0910251
X0508248Y0873319
X0559214Y0897425
X0561134Y0869291
X0509017Y0905295
X0520870Y0874694
X0548327Y0905295
X0540968Y0878360
X0537279Y0897943
X0528975Y0898346
X0533468Y0878533
X0521572Y0901500
X0559260Y0891043
X0559887Y0877196
X0559295Y0874267
X0568990Y0844721
X0546241Y0843149
X0511741Y0846649
X0514682Y0834590
X0550087Y0829836
X0525159Y0913818
X0489572Y0822805
X0525718Y0873821
X0567559Y0824661
X0560813Y0840574
X0546855Y0829949
X0534000Y0843000
X0532316Y0833649
X0534632Y0849830
X0522481Y0824661
X0475046Y0885952
X0474678Y0857919
X0475032Y0843252
X0488469Y0857013
X0491527Y0843206
X0491453Y0834546
X0481593Y0826387
X0499640Y0861538
X0497467Y0833027
X0503741Y0846830
X0492799Y0846488
X0506246Y0824689
X0491655Y0829173
X0509673Y0900295
X0511025Y0911443
X0521115Y0897500
X0509428Y0888390
X0523272Y0880067
X0508049Y0877789
X0517832Y0834558
X0520720Y0846133
X0527346Y0911458
X0528868Y0873683
X0536641Y0838649
X0527733Y0847026
X0531313Y0822693
X0544793Y0899220
X0545144Y0909025
X0548521Y0874859
X0548521Y0877859
X0545237Y0850319
X0549241Y0841388
X0545981Y0846389
X0541129Y0838865
X0541129Y0828335
X0548464Y0823156
X0559196Y0846296
X0567316Y0827724
X0560263Y0829989
X0563099Y0829943
X0560814Y0901022
X0524598Y0753387
X0513504Y0755804
X0564362Y0757979
X0563200Y0739600
X0469300Y0799500
X0513551Y0773203
X0504641Y0789139
X0520833Y0773389
X0504508Y0783817
X0557847Y0744599
X0513278Y0783286
X0557751Y0750851
X0562001Y0732834
X0508324Y0741035
X0511724Y0741035
X0517731Y0741071
X0521131Y0741071
X0527585Y0741593
X0530985Y0741593
X0558616Y0732530
X0562400Y0818900
X0556741Y0820149
X0544878Y0816309
X0544741Y0809649
X0544515Y0793875
X0567126Y0779066
X0560263Y0782207
X0537578Y0772428
X0507095Y0814784
X0520741Y0805149
X0519891Y0795848
X0539449Y0782389
X0538985Y0736593
X0540578Y0793889
X0556326Y0793743
X0522697Y0797102
X0535585Y0736593
X0550420Y0793743
X0545768Y0781600
X0549168Y0781600
X0501495Y0770457
X0504895Y0770457
X0473654Y0821234
X0515422Y0753455
X0509096Y0753072
X0567559Y0803008
X0561001Y0806889
X0531313Y0812850
X0532304Y0806649
X0518565Y0811973
X0518157Y0803973
X0489406Y0797558
X0506166Y0793224
X0520549Y0761982
X0567428Y0750145
X0557813Y0747814
X0520159Y0758832
X0517194Y0773232
X0558294Y0784911
X0562231Y0784911
X0558241Y0796389
X0542599Y0782389
X0551524Y0784889
X0554357Y0784889
X0542546Y0784911
X0532449Y0782389
X0531260Y0794934
X0531501Y0792331
X0534672Y0785037
X0509063Y0782867
X0508130Y0787488
X0509316Y0793224
X0522316Y0793574
X0500717Y0767961
X0505673Y0767961
X0507546Y0738539
X0521909Y0738575
X0516953Y0738575
X0512502Y0738539
X0508237Y0723585
X0532278Y0762736
X0542275Y0760782
X0532450Y0767474
X0526807Y0739097
X0531763Y0739097
X0534807Y0734097
X0539763Y0734097
X0552188Y0766577
X0552384Y0762892
X0564276Y0776701
X0559625Y0739609
X0561886Y0728138
X0485824Y0819787
X0486246Y0804497
X0504341Y0812040
X0521565Y0820931
X0521178Y0814001
X0531666Y0815724
X0545741Y0804149
X0553871Y0811298
X0540807Y0816556
X0559741Y0822149
X0561061Y0803606
X0567316Y0806224
X0567559Y0812850
X0561401Y0811242
X0499528Y0657843
X0524493Y0692443
X0529493Y0694943
X0481742Y0657477
X0526993Y0692443
X0529501Y0702622
X0526699Y0706388
X0529493Y0699943
X0529493Y0697443
X0536087Y0702364
X0518812Y0662874
X0521868Y0666577
X0506278Y0628078
X0493778Y0633724
X0499258Y0633716
X0504265Y0633736
X0511278Y0633473
X0515267Y0627908
X0493661Y0627713
X0521778Y0642184
X0562374Y0721593
X0488765Y0667224
X0496070Y0665976
X0551475Y0661504
X0521540Y0686319
X0520799Y0692384
X0518299Y0692384
X0515504Y0701351
X0518389Y0706388
X0523929Y0706388
X0514531Y0716398
X0512530Y0718301
X0498284Y0678953
X0498284Y0681453
X0515484Y0695757
X0529469Y0706230
X0515649Y0706388
X0515573Y0692515
X0529493Y0692443
X0535738Y0687489
X0538316Y0687357
X0521159Y0706388
X0526264Y0664056
X0561570Y0692809
X0559070Y0704209
X0561570Y0696209
X0529664Y0664056
X0559070Y0688209
X0561570Y0712209
X0534264Y0661556
X0537664Y0661556
X0559070Y0684809
X0559070Y0700809
X0559070Y0720209
X0561570Y0708809
X0559070Y0716809
X0522200Y0677613
X0486837Y0704706
X0486837Y0701306
X0483059Y0662649
X0543101Y0698772
X0484772Y0625311
X0540379Y0719785
X0502832Y0720491
X0500714Y0708755
X0547276Y0675521
X0547227Y0678299
X0504966Y0678098
X0510425Y0683246
X0502755Y0657694
X0481165Y0646036
X0494465Y0657772
X0484772Y0629311
X0523616Y0625013
X0485303Y0681841
X0491324Y0667293
X0494632Y0654622
X0518067Y0699378
X0526951Y0699443
X0522628Y0703884
X0469349Y0668016
X0469349Y0678016
X0484341Y0705484
X0484341Y0700528
X0485005Y0659771
X0493778Y0641817
X0499278Y0641817
X0500705Y0705524
X0503311Y0715652
X0499012Y0699819
X0501618Y0698355
X0522410Y0694881
X0518001Y0694940
X0511990Y0686365
X0518812Y0665867
X0510215Y0627948
X0512404Y0629362
X0523596Y0628242
X0518530Y0703584
X0526276Y0721339
X0532628Y0720776
X0526933Y0703820
X0535387Y0712617
X0526956Y0694959
X0539111Y0681459
X0534940Y0684489
X0530796Y0661387
X0524941Y0661387
X0538442Y0664052
X0533486Y0664052
X0524653Y0643595
X0526756Y0638805
X0538826Y0639050
X0538826Y0636250
X0526756Y0633205
X0526756Y0636005
X0538826Y0633450
X0556574Y0720987
X0556574Y0704987
X0556574Y0716031
X0556574Y0688987
X0556574Y0700031
X0556574Y0684031
X0550274Y0658676
X0559074Y0708031
X0559074Y0712987
X0559074Y0692031
X0559074Y0696987
X0493580Y0616905
X0497448Y0610548
X0493392Y0622285
X0524770Y0605637
X0482905Y0527726
X0520770Y0597130
X0516770Y0605443
X0520770Y0605443
X0541245Y0578986
X0520945Y0590801
X0529601Y0596089
X0540770Y0596729
X0535819Y0578405
X0534820Y0596782
X0508258Y0607762
X0508258Y0610562
X0511058Y0607762
X0511058Y0610562
X0505458Y0607762
X0502658Y0607762
X0502658Y0610562
X0505458Y0610562
X0508086Y0591215
X0502486Y0591215
X0505286Y0591215
X0532426Y0576484
X0544738Y0581659
X0532069Y0573689
X0529423Y0573303
X0508086Y0581222
X0502486Y0581222
X0505286Y0581222
X0529214Y0570686
X0532009Y0570478
X0500929Y0563194
X0503729Y0563194
X0503729Y0571194
X0500929Y0571194
X0530988Y0548344
X0525988Y0548344
X0528488Y0548344
X0525288Y0542877
X0525288Y0545377
X0525288Y0540377
X0509955Y0540458
X0518416Y0544895
X0513658Y0542231
X0521216Y0541895
X0521216Y0544895
X0518716Y0541895
X0500929Y0555194
X0503729Y0555194
X0533488Y0548344
X0525288Y0537877
X0513658Y0539731
X0509955Y0537958
X0535219Y0558497
X0535219Y0566797
X0535219Y0563697
X0535219Y0561097
X0535219Y0553297
X0535219Y0555897
X0491445Y0541135
X0491511Y0546553
X0491534Y0552726
X0482905Y0544726
X0491818Y0534909
X0482836Y0534249
X0544770Y0605443
X0536770Y0605443
X0484772Y0621311
X0524770Y0597232
X0521494Y0582747
X0482905Y0548726
X0518940Y0617853
X0518940Y0620653
X0538826Y0619758
X0538826Y0616958
X0538826Y0614158
X0526756Y0619513
X0526756Y0616713
X0526756Y0613913
X0487209Y0611071
X0504079Y0529169
X0498494Y0531882
X0500994Y0531882
X0502379Y0525369
X0503494Y0531882
X0495444Y0531948
X0502379Y0522569
X0532281Y0532849
X0529481Y0532849
X0491340Y0611091
X0486738Y0591215
X0489538Y0591215
X0489538Y0581222
X0486738Y0581222
X0482905Y0540726
X0482905Y0552726
X0482737Y0537215
X0482905Y0531726
X0492338Y0591215
X0492338Y0581222
X0496729Y0571194
X0493929Y0571194
X0496729Y0563194
X0493929Y0563194
X0496729Y0555194
X0493929Y0555194
X0506925Y0546830
X0519875Y0608311
X0521494Y0572975
X0521581Y0527449
X0517319Y0524304
X0518781Y0527449
X0513626Y0531378
X0513626Y0528578
X0524708Y0572842
X0525288Y0529929
X0525288Y0527129
X0525288Y0524629
X0532770Y0605443
X0528314Y0590145
X0532908Y0590190
X0528816Y0579475
X0528270Y0585507
X0532863Y0585507
X0540770Y0605443
X0518240Y0459371
X0522756Y0461818
X0520823Y0442603
X0513310Y0462004
X0504729Y0461419
X0512943Y0443071
X0503682Y0448419
X0496729Y0461919
X0473658Y0475509
X0489485Y0431417
X0473658Y0470509
X0481485Y0431917
X0501649Y0482165
X0517310Y0470045
X0504729Y0469905
X0528716Y0461652
X0528716Y0459152
X0526216Y0461652
X0526216Y0459152
X0528716Y0456652
X0526216Y0456652
X0528247Y0498151
X0528547Y0495151
X0531047Y0495151
X0535119Y0498633
X0535119Y0496133
X0535119Y0493633
X0531047Y0498151
X0523489Y0495487
X0519786Y0493714
X0523489Y0492987
X0492736Y0495982
X0535119Y0491133
X0519786Y0491214
X0502493Y0495917
X0500890Y0500202
X0501224Y0492050
X0496729Y0470419
X0492736Y0491982
X0481485Y0439900
X0489485Y0439903
X0485485Y0439903
X0497095Y0481467
X0503729Y0439919
X0510825Y0485138
X0513325Y0485138
X0513910Y0482425
X0512210Y0475825
X0512210Y0478625
X0508325Y0485138
X0505476Y0485128
X0500729Y0469905
X0511753Y0459339
X0509253Y0459339
X0509253Y0454339
X0509253Y0456839
X0511753Y0456839
X0511753Y0454339
X0496828Y0517401
X0499328Y0517401
X0501828Y0517401
X0496887Y0504825
X0499387Y0504825
X0501887Y0504825
X0528612Y0480705
X0535119Y0476086
X0531412Y0480705
X0526902Y0475946
X0526902Y0478446
X0535119Y0478586
X0535119Y0481086
X0535119Y0483886
X0523457Y0484634
X0523457Y0482134
X0492736Y0483982
X0492736Y0478982
X0497776Y0448466
X0503682Y0455466
X0493485Y0439903
X0482484Y0444517
X0488438Y0425464
X0513310Y0470045
X0521310Y0470045
X0508729Y0469905
X0523583Y0447201
X0523705Y0444269
X0510022Y0446352
X0514608Y0445874
X0512845Y0434508
X0516845Y0434508
X0520845Y0434508
X0552905Y0430829
X0492736Y0499982
X0492736Y0487982
X0518838Y0516979
X0521338Y0516979
X0516338Y0516979
X0517319Y0521804
X0516756Y0500086
X0519136Y0504699
X0516636Y0504699
X0521636Y0504699
X0530436Y0519544
X0525436Y0519544
X0527936Y0519544
X0525288Y0522129
X0532936Y0519544
X0471048Y0464566
X0473658Y0467215
X0482193Y0468784
X0482193Y0472784
X0482193Y0476784
X0488438Y0418417
X0470796Y0394592
X0506500Y0379687
X0531636Y0349057
X0530144Y0376062
X0533115Y0371856
X0533211Y0364746
X0531612Y0354272
X0526388Y0351301
X0528812Y0369164
X0532659Y0359557
X0490885Y0382570
X0491843Y0351089
X0496023Y0362913
X0491053Y0365423
X0495750Y0377531
X0497048Y0369450
X0490885Y0373589
X0492817Y0357111
X0469530Y0366754
X0481724Y0378089
X0481724Y0369089
X0481724Y0373589
X0481724Y0382589
X0531953Y0385749
X0533189Y0390723
X0553563Y0384987
X0551620Y0390723
X0541706Y0386223
X0542034Y0392209
X0531953Y0380749
X0495203Y0386890
X0491289Y0391589
X0490985Y0412342
X0531992Y0397552
X0551536Y0381723
X0472913Y0378089
X0472913Y0382589
X0472913Y0391589
X0472913Y0387089
X0551536Y0363723
X0551536Y0368223
X0551536Y0372723
X0551536Y0377223
X0472913Y0373589
X0472913Y0369089
X0551536Y0345723
X0551536Y0350223
X0551536Y0354723
X0551536Y0359223
X0472608Y0352495
X0472913Y0360089
X0472810Y0347995
X0492317Y0376252
X0530215Y0364422
X0533027Y0351836
X0524206Y0354119
X0470389Y0389553
X0497424Y0354559
X0482532Y0418464
X0481724Y0387089
X0481724Y0391589
X0483541Y0380306
X0483736Y0371266
X0483584Y0375840
X0483242Y0366481
X0535142Y0397552
X0541706Y0381723
X0553731Y0388487
X0541644Y0389047
X0537612Y0265896
X0472673Y0249108
X0532525Y0265701
X0540101Y0281982
X0534160Y0281716
X0475293Y0244571
X0482636Y0256394
X0542628Y0266114
X0519638Y0314346
X0479686Y0228646
X0488682Y0227824
X0537853Y0256303
X0560928Y0228631
X0490989Y0244297
X0514769Y0312953
X0511790Y0313804
X0515074Y0258880
X0484427Y0230556
X0489288Y0238714
X0493272Y0230117
X0566416Y0248371
X0529343Y0267526
X0526843Y0267526
X0529343Y0270026
X0526843Y0270026
X0524043Y0267526
X0524043Y0270026
X0517649Y0264180
X0515149Y0264180
X0488769Y0246874
X0478643Y0232971
X0483412Y0242078
X0476725Y0226320
X0545874Y0270695
X0548374Y0270695
X0551174Y0268195
X0554834Y0265897
X0551174Y0270695
X0548374Y0268195
X0545874Y0268195
X0545677Y0248765
X0548177Y0248765
X0550677Y0248765
X0545736Y0236189
X0548236Y0236189
X0550736Y0236189
X0543485Y0224421
X0545185Y0228221
X0545185Y0231021
X0557334Y0265897
X0485053Y0238689
X0475651Y0238589
X0478617Y0236121
X0485827Y0247292
X0493288Y0238714
X0478536Y0253198
X0511342Y0311124
X0523380Y0288190
X0523380Y0285690
X0515366Y0293796
X0517866Y0293796
X0511820Y0226226
X0511820Y0223726
X0511820Y0228726
X0511820Y0231226
X0522276Y0231461
X0522276Y0228961
X0522276Y0226461
X0522276Y0223661
X0540906Y0290755
X0536906Y0290755
X0532906Y0290755
X0528680Y0288190
X0525880Y0288190
X0528680Y0285690
X0525880Y0285690
X0525928Y0248891
X0533853Y0256535
X0530928Y0248891
X0528428Y0248891
X0530245Y0231786
X0528726Y0236611
X0531226Y0236611
X0526226Y0236611
X0533938Y0224712
X0525983Y0226141
X0528783Y0226141
X0530245Y0229286
X0551477Y0293645
X0548977Y0293645
X0546987Y0281307
X0542883Y0279208
X0541853Y0256535
X0566416Y0252371
X0548977Y0290845
X0548977Y0288345
X0551477Y0290845
X0551477Y0288345
X0537128Y0148277
X0551898Y0152373
X0472611Y0124663
X0564885Y0124283
X0539748Y0143740
X0552798Y0143518
X0477592Y0125107
X0473955Y0138838
X0564740Y0186778
X0560543Y0157370
X0480106Y0148717
X0486206Y0143762
X0556053Y0207037
X0564627Y0192665
X0564627Y0196665
X0556119Y0212455
X0548311Y0141247
X0556030Y0200864
X0564659Y0208864
X0528509Y0147540
X0487008Y0206806
X0484508Y0206806
X0486672Y0201748
X0489672Y0202048
X0482735Y0210509
X0485235Y0210509
X0490154Y0195176
X0486672Y0199248
X0482654Y0195176
X0485154Y0195176
X0489672Y0199248
X0487654Y0195176
X0537589Y0177616
X0555740Y0183834
X0549985Y0192490
X0555913Y0172665
X0555850Y0178560
X0540843Y0168697
X0537609Y0215632
X0522276Y0215713
X0526348Y0211695
X0529148Y0208695
X0526348Y0208695
X0537609Y0213132
X0528848Y0211695
X0533906Y0213859
X0533906Y0211359
X0522276Y0210713
X0522276Y0213213
X0522276Y0208213
X0511820Y0212978
X0511820Y0215478
X0511820Y0210478
X0511820Y0207978
X0532487Y0184012
X0529870Y0184221
X0532873Y0181366
X0529662Y0181426
X0535668Y0181009
X0538170Y0172190
X0555260Y0190185
X0555048Y0152562
X0560300Y0219379
X0473946Y0216385
X0470146Y0218085
X0476659Y0221970
X0476659Y0219470
X0476659Y0216970
X0564659Y0204864
X0556726Y0186629
X0541931Y0191941
X0564627Y0168665
X0564627Y0176665
X0563292Y0161306
X0532281Y0141247
X0479065Y0142862
X0530665Y0167993
X0530665Y0170493
X0530665Y0165393
X0530665Y0162793
X0523565Y0162368
X0520965Y0162368
X0492775Y0125428
X0492775Y0128828
X0485475Y0132515
X0485475Y0135915
X0533092Y0125396
X0543494Y0132509
X0533092Y0128796
X0544070Y0221708
X0553420Y0221642
X0546570Y0221708
X0549070Y0221708
X0543940Y0206767
X0546440Y0206767
X0548940Y0206767
X0472226Y0201683
X0469967Y0203393
X0473655Y0206838
X0475407Y0195176
X0472226Y0198883
X0472607Y0195176
X0470107Y0195176
X0472332Y0133298
X0491607Y0213539
X0476155Y0206838
X0483859Y0150847
X0487875Y0137757
X0483075Y0137757
X0480971Y0141228
X0479065Y0146012
X0483075Y0123584
X0490375Y0130670
X0490375Y0123583
X0487875Y0130670
X0487875Y0123584
X0483075Y0130670
X0495075Y0137756
X0504547Y0137756
X0504552Y0130670
X0495075Y0123583
X0495075Y0130670
X0521185Y0137756
X0509251Y0137756
X0521185Y0123583
X0521185Y0130670
X0513185Y0123583
X0513185Y0130670
X0533938Y0222212
X0532026Y0188727
X0532159Y0191941
X0538659Y0184619
X0528509Y0151540
X0535588Y0129574
X0535588Y0124618
X0530596Y0129574
X0530596Y0124618
X0540639Y0206760
X0544691Y0185165
X0549329Y0185121
X0553097Y0192421
X0544691Y0180572
X0549374Y0180527
X0542991Y0152367
X0540998Y0136687
X0545990Y0136687
X0544089Y0146461
X0540998Y0131731
X0540998Y0122513
X0545990Y0131731
X0545990Y0122513
X0564659Y0216864
X0564659Y0221864
X0564659Y0200864
X0564659Y0212864
X0564627Y0172665
X0564627Y0180665
X0568841Y0134579
X0567290Y0130898
X0543494Y0135909
X0473032Y0110784
X0487925Y0095111
X0540751Y0097475
X0503075Y0095236
X0547732Y0100625
X0556394Y0103621
X0523943Y0104249
X0523943Y0107649
X0513008Y0095236
X0492294Y0106561
X0552105Y0112083
X0512958Y0099961
X0564255Y0086046
X0560701Y0085731
X0508637Y0090615
X0546293Y0072615
X0503325Y0090650
X0546293Y0076587
X0540682Y0106186
X0533747Y0103783
X0474058Y0116594
X0474058Y0119594
X0530197Y0098551
X0483675Y0097667
X0554211Y0080581
X0554198Y0068581
X0557973Y0055513
X0565207Y0094279
X0563433Y0060438
X0561258Y0094351
X0560573Y0060513
X0564451Y0119594
X0564451Y0116594
X0479331Y0102495
X0558341Y0088801
X0521872Y0079993
X0521872Y0077393
X0521872Y0074793
X0521872Y0085193
X0521872Y0082593
X0492529Y0097667
X0521916Y0092874
X0492135Y0103411
X0485475Y0121742
X0492775Y0111255
X0492775Y0114655
X0485475Y0118342
X0533092Y0111223
X0543494Y0118335
X0533092Y0114623
X0543494Y0121735
X0470307Y0102249
X0474307Y0102249
X0490375Y0116497
X0490375Y0109410
X0487875Y0116497
X0483075Y0116497
X0479331Y0106495
X0477324Y0109172
X0480324Y0109172
X0485404Y0044773
X0485404Y0024773
X0512725Y0053597
X0506653Y0121652
X0495075Y0109410
X0495075Y0102323
X0495075Y0116496
X0503327Y0116496
X0503327Y0109410
X0503075Y0102323
X0503537Y0085584
X0506091Y0092849
X0503537Y0082984
X0503537Y0080384
X0503537Y0075184
X0503537Y0077784
X0492725Y0053597
X0530468Y0094017
X0538477Y0094017
X0534468Y0094017
X0530831Y0044773
X0530831Y0024773
X0521185Y0102323
X0521185Y0109410
X0521185Y0116496
X0513185Y0109410
X0513185Y0116496
X0513051Y0103037
X0537747Y0103783
X0530596Y0110445
X0535588Y0115401
X0535588Y0110445
X0530596Y0115401
X0530197Y0101701
X0526468Y0094017
X0548914Y0103621
X0545990Y0117557
X0540998Y0117557
X0543545Y0076140
X0543545Y0080140
X0543545Y0084140
X0568669Y0102249
X0564451Y0113394
X0567100Y0110784
X0556920Y0117261
X0558316Y0091951
X0563224Y0096813
X0561123Y0055513
X0566287Y0060922
X0484043Y0004469
X0531518Y0005374
X0550421Y0003000
X0570421Y0003000
X0586405Y0004469
X0575394Y0110784
X0570394Y0110784
X0590287Y0095111
X0643113Y0097475
X0605437Y0095236
X0650094Y0100625
X0658756Y0103621
X0626305Y0107649
X0626305Y0104249
X0594656Y0106561
X0654467Y0112083
X0615320Y0099961
X0615370Y0095236
X0666617Y0086046
X0663063Y0085731
X0610999Y0090615
X0648655Y0072615
X0605687Y0090650
X0648655Y0076587
X0643044Y0106186
X0636109Y0103783
X0576420Y0119594
X0576420Y0116594
X0632559Y0098551
X0586037Y0097667
X0656573Y0080581
X0656560Y0068581
X0657507Y0058013
X0667569Y0094279
X0665795Y0060438
X0663620Y0094351
X0662935Y0060513
X0569114Y0086012
X0666813Y0119594
X0666813Y0116594
X0581693Y0102495
X0660703Y0088801
X0569114Y0094374
X0624234Y0079993
X0624234Y0077393
X0624234Y0085193
X0624234Y0082593
X0624234Y0074793
X0594891Y0097667
X0624278Y0092874
X0594497Y0103411
X0595137Y0114655
X0587837Y0121742
X0595137Y0111255
X0587837Y0118342
X0635454Y0111223
X0635454Y0114623
X0645856Y0121735
X0572669Y0102249
X0585437Y0116497
X0581693Y0106495
X0579686Y0109172
X0582686Y0109172
X0576669Y0102249
X0587766Y0044773
X0587766Y0024773
X0597437Y0116496
X0597437Y0109410
X0597437Y0102323
X0592737Y0116497
X0590237Y0116497
X0592737Y0109410
X0595087Y0053597
X0615547Y0109410
X0615547Y0116496
X0605689Y0116496
X0605689Y0109410
X0605437Y0102323
X0615413Y0103037
X0605899Y0085584
X0608453Y0092849
X0605899Y0075184
X0605899Y0077784
X0605899Y0082984
X0605899Y0080384
X0615087Y0053597
X0623547Y0102323
X0632958Y0115401
X0623547Y0116496
X0623547Y0109410
X0632958Y0110445
X0632559Y0101701
X0632830Y0094017
X0628830Y0094017
X0636830Y0094017
X0633248Y0044884
X0640109Y0103783
X0651276Y0103621
X0648352Y0117557
X0637950Y0115401
X0637950Y0110445
X0643360Y0117557
X0640839Y0094017
X0645907Y0080140
X0645907Y0084140
X0645907Y0076140
X0666813Y0113394
X0659282Y0117261
X0660678Y0091951
X0665423Y0096853
X0666209Y0057297
X0668649Y0060922
X0645856Y0118335
X0639490Y0148277
X0569951Y0124879
X0667247Y0124283
X0654260Y0152373
X0574973Y0124663
X0642110Y0143740
X0655160Y0143518
X0579954Y0125107
X0576317Y0138838
X0667102Y0186778
X0662905Y0157370
X0582468Y0148717
X0658415Y0207037
X0588568Y0143762
X0666989Y0192665
X0666989Y0196665
X0658481Y0212455
X0658392Y0200864
X0667021Y0208864
X0650673Y0141247
X0589370Y0206806
X0592034Y0202048
X0586870Y0206806
X0589034Y0201748
X0585097Y0210509
X0587597Y0210509
X0592034Y0199248
X0592516Y0195176
X0590016Y0195176
X0589034Y0199248
X0585016Y0195176
X0587516Y0195176
X0658102Y0183834
X0643205Y0168697
X0639971Y0215632
X0624638Y0215713
X0639971Y0213132
X0624638Y0210713
X0624638Y0213213
X0631210Y0211695
X0636268Y0213859
X0636268Y0211359
X0624638Y0208213
X0631510Y0208695
X0628710Y0208695
X0628710Y0211695
X0614182Y0207978
X0614182Y0212978
X0614182Y0215478
X0614182Y0210478
X0634849Y0184012
X0632232Y0184221
X0638030Y0181009
X0635235Y0181366
X0632024Y0181426
X0652347Y0192490
X0658212Y0178560
X0657622Y0190185
X0640532Y0172190
X0639951Y0177616
X0658275Y0172665
X0657410Y0152562
X0662662Y0219379
X0572508Y0218085
X0569708Y0218085
X0579021Y0221970
X0579021Y0219470
X0579021Y0216970
X0576308Y0216385
X0667021Y0204864
X0659088Y0186629
X0644293Y0191941
X0666989Y0168665
X0666989Y0176665
X0665654Y0161306
X0634643Y0141247
X0581427Y0142862
X0630871Y0147540
X0633027Y0167993
X0633027Y0170493
X0633027Y0162793
X0633027Y0165393
X0623327Y0162368
X0625927Y0162368
X0620727Y0162368
X0595137Y0128828
X0587837Y0132515
X0595137Y0125428
X0587837Y0135915
X0635454Y0125396
X0645856Y0135909
X0645856Y0132509
X0651432Y0221708
X0646432Y0221708
X0648932Y0221708
X0648802Y0206767
X0651302Y0206767
X0646302Y0206767
X0655782Y0221642
X0569829Y0203393
X0574588Y0201683
X0572329Y0203393
X0572469Y0195176
X0569969Y0195176
X0576017Y0206838
X0578517Y0206838
X0574588Y0198883
X0577769Y0195176
X0574969Y0195176
X0586221Y0150847
X0585437Y0137757
X0583333Y0141228
X0581427Y0146012
X0585437Y0130670
X0585437Y0123584
X0574694Y0133298
X0593969Y0213539
X0590237Y0137757
X0597437Y0137756
X0592737Y0130670
X0590237Y0130670
X0590237Y0123584
X0592737Y0123583
X0597437Y0130670
X0597437Y0123583
X0612138Y0137756
X0606909Y0137756
X0606914Y0130670
X0615547Y0123583
X0615547Y0130670
X0605861Y0124576
X0634388Y0188727
X0634521Y0191941
X0630871Y0151540
X0623547Y0137756
X0632958Y0129574
X0623547Y0130670
X0623547Y0123583
X0632958Y0124618
X0636300Y0222212
X0643001Y0206760
X0641021Y0184619
X0647053Y0185165
X0651691Y0185121
X0651736Y0180527
X0647053Y0180572
X0645353Y0152367
X0648352Y0136687
X0643360Y0136687
X0646451Y0146461
X0648352Y0131731
X0648352Y0122513
X0637950Y0129574
X0637950Y0124618
X0643360Y0131731
X0643360Y0122513
X0667021Y0216864
X0667021Y0221864
X0667021Y0212864
X0667021Y0200864
X0655459Y0192421
X0666989Y0180665
X0666989Y0172665
X0635454Y0128796
X0584998Y0256394
X0636522Y0281716
X0634887Y0265701
X0644990Y0266114
X0575035Y0249108
X0639974Y0265896
X0577655Y0244571
X0642463Y0281982
X0592900Y0309871
X0582048Y0228646
X0640215Y0256303
X0663290Y0228631
X0591044Y0227824
X0593351Y0244297
X0617436Y0258880
X0591650Y0238714
X0595634Y0230117
X0586789Y0230556
X0631705Y0270026
X0626405Y0270026
X0629205Y0270026
X0631705Y0267526
X0626405Y0267526
X0629205Y0267526
X0620011Y0264180
X0617511Y0264180
X0668886Y0248371
X0581005Y0232971
X0591131Y0246874
X0585774Y0242078
X0579087Y0226320
X0647547Y0231021
X0645847Y0224421
X0647547Y0228221
X0648236Y0268195
X0648236Y0270695
X0650736Y0270695
X0653536Y0268195
X0653536Y0270695
X0650736Y0268195
X0648039Y0248765
X0650539Y0248765
X0653039Y0248765
X0653098Y0236189
X0648098Y0236189
X0650598Y0236189
X0659696Y0265897
X0657196Y0265897
X0580898Y0253198
X0578013Y0238589
X0580979Y0236121
X0588189Y0247292
X0587415Y0238689
X0590178Y0309760
X0595650Y0238714
X0620228Y0293796
X0617728Y0293796
X0614182Y0228726
X0614182Y0231226
X0614182Y0226226
X0614182Y0223726
X0635268Y0290755
X0628242Y0288190
X0625742Y0285690
X0628242Y0285690
X0625742Y0288190
X0631042Y0285690
X0631042Y0288190
X0636215Y0256535
X0628290Y0248891
X0633290Y0248891
X0630790Y0248891
X0628588Y0236611
X0632607Y0231786
X0631088Y0236611
X0633588Y0236611
X0624638Y0228961
X0628345Y0226141
X0624638Y0226461
X0631145Y0226141
X0624638Y0223661
X0632607Y0229286
X0636300Y0224712
X0624638Y0231461
X0651339Y0288345
X0653839Y0290845
X0653839Y0288345
X0643268Y0290755
X0639268Y0290755
X0653839Y0293645
X0651339Y0293645
X0651339Y0290845
X0649349Y0281307
X0645245Y0279208
X0644215Y0256535
X0668778Y0252371
X0569938Y0378317
X0573479Y0374705
X0661761Y0382109
X0584679Y0336285
X0578193Y0336391
X0605147Y0382600
X0662766Y0401482
X0662766Y0412255
X0662766Y0415655
X0662766Y0398082
X0605778Y0408574
X0595376Y0415687
X0605778Y0391001
X0605778Y0419347
X0605778Y0394401
X0597776Y0398113
X0605778Y0405174
X0597776Y0401513
X0595376Y0412287
X0605147Y0378600
X0581487Y0336676
X0570634Y0375453
X0597872Y0411509
X0597872Y0416465
X0595280Y0397335
X0600272Y0402291
X0595280Y0402291
X0603282Y0409352
X0603282Y0404396
X0603282Y0395179
X0600272Y0397335
X0603282Y0390223
X0603282Y0418569
X0592880Y0411509
X0592880Y0416465
X0608274Y0418569
X0608274Y0409352
X0608274Y0404396
X0608274Y0395179
X0608274Y0390223
X0634455Y0417500
X0634455Y0410413
X0634455Y0403327
X0634455Y0396240
X0634455Y0389154
X0652381Y0414823
X0642488Y0412571
X0647604Y0396240
X0643534Y0404911
X0642255Y0396240
X0649074Y0389154
X0642255Y0389154
X0667666Y0389153
X0665166Y0417500
X0660366Y0417500
X0667666Y0417499
X0660366Y0396240
X0667666Y0410413
X0665166Y0410413
X0667666Y0403326
X0665166Y0403327
X0667666Y0396240
X0665166Y0396240
X0660366Y0410413
X0660366Y0403327
X0660366Y0389154
X0606026Y0455921
X0598462Y0504684
X0602462Y0458711
X0604606Y0463600
X0607789Y0453682
X0662766Y0479868
X0662766Y0429828
X0662766Y0494041
X0662766Y0444002
X0662766Y0426428
X0662766Y0520602
X0662766Y0440602
X0662766Y0490641
X0662766Y0476468
X0595376Y0429860
X0595376Y0516921
X0595376Y0486960
X0605778Y0494073
X0595376Y0483560
X0595376Y0472787
X0595376Y0469387
X0605778Y0520633
X0605778Y0476499
X0605778Y0436921
X0595376Y0426460
X0595376Y0444033
X0595376Y0440633
X0595376Y0513521
X0605778Y0490673
X0605778Y0479899
X0605778Y0422747
X0605778Y0433521
X0605262Y0458711
X0634455Y0481713
X0608274Y0475721
X0608274Y0480677
X0597872Y0473565
X0592880Y0473565
X0597872Y0482782
X0592880Y0482782
X0603282Y0475721
X0603282Y0480677
X0660366Y0481713
X0665166Y0481712
X0667666Y0481712
X0660366Y0474626
X0667666Y0474626
X0665166Y0474626
X0651308Y0472772
X0642255Y0474626
X0642516Y0480828
X0652155Y0479104
X0634455Y0474626
X0592880Y0425682
X0597872Y0425682
X0603282Y0423525
X0597872Y0468609
X0592880Y0468609
X0593690Y0450750
X0592880Y0444811
X0597872Y0444811
X0592880Y0430638
X0597872Y0430638
X0592880Y0439855
X0597872Y0439855
X0603282Y0437699
X0603282Y0432743
X0608274Y0437699
X0608274Y0432743
X0608274Y0423525
X0634455Y0467539
X0634455Y0445847
X0634455Y0438760
X0634455Y0431673
X0634455Y0424587
X0652566Y0467539
X0642255Y0467539
X0643986Y0445847
X0653399Y0447953
X0651364Y0436447
X0651759Y0429832
X0643675Y0426299
X0651689Y0422864
X0660366Y0445847
X0665166Y0445847
X0660366Y0438760
X0660366Y0431673
X0667666Y0431673
X0667666Y0438760
X0665166Y0438760
X0665166Y0431673
X0660366Y0424586
X0667666Y0424586
X0665166Y0424586
X0660366Y0467539
X0667666Y0467539
X0592880Y0512743
X0597872Y0512743
X0603282Y0519855
X0597872Y0517699
X0592880Y0517699
X0603282Y0494851
X0597872Y0487738
X0592880Y0487738
X0603282Y0489895
X0608274Y0519855
X0608274Y0494851
X0608274Y0489895
X0634455Y0518760
X0634455Y0511673
X0634455Y0495886
X0634455Y0488799
X0642255Y0511673
X0642255Y0518760
X0651166Y0510565
X0647915Y0516841
X0652566Y0495886
X0644466Y0498834
X0652042Y0487711
X0660366Y0518760
X0660366Y0511673
X0667666Y0511673
X0665166Y0518760
X0667666Y0518760
X0660366Y0495886
X0665166Y0495886
X0667666Y0488799
X0665166Y0488799
X0660366Y0488799
X0661760Y0558917
X0661760Y0561420
X0648211Y0610400
X0605011Y0619600
X0605011Y0603600
X0632701Y0550907
X0630201Y0550907
X0632701Y0553407
X0630201Y0553407
X0632009Y0545263
X0632009Y0541863
X0657581Y0577937
X0631862Y0568475
X0632119Y0570962
X0629772Y0569928
X0628425Y0572070
X0634471Y0566929
X0634185Y0569426
X0599110Y0552466
X0666180Y0616317
X0660546Y0618400
X0665586Y0595500
X0665086Y0604567
X0660586Y0606929
X0666244Y0610072
X0642414Y0545528
X0660827Y0612592
X0651149Y0577716
X0661760Y0551683
X0662766Y0538175
X0662766Y0524002
X0662766Y0534775
X0605778Y0538206
X0605778Y0524033
X0595376Y0527694
X0595376Y0531094
X0605778Y0534806
X0604979Y0607588
X0605011Y0615600
X0604982Y0596095
X0602695Y0594668
X0604180Y0592354
X0604241Y0589556
X0604979Y0599588
X0602756Y0597580
X0597789Y0536382
X0597872Y0526916
X0603282Y0534028
X0603282Y0538984
X0603282Y0524811
X0592880Y0531872
X0597872Y0531872
X0592880Y0526916
X0608274Y0524811
X0608274Y0534028
X0608274Y0538984
X0614176Y0562003
X0614461Y0555234
X0634200Y0595108
X0633736Y0602197
X0634455Y0547106
X0634455Y0540020
X0634455Y0532933
X0634455Y0525847
X0648211Y0614400
X0648211Y0606400
X0648211Y0594400
X0648211Y0598400
X0648211Y0602400
X0642726Y0574102
X0643953Y0560675
X0642185Y0562443
X0644494Y0572334
X0642740Y0552872
X0642862Y0550123
X0642255Y0525847
X0660366Y0595118
X0660366Y0602205
X0660826Y0572914
X0660826Y0575414
X0660826Y0565414
X0660826Y0567914
X0660826Y0570414
X0660366Y0547106
X0660366Y0554193
X0660366Y0540020
X0660366Y0532933
X0660366Y0525847
X0667666Y0525846
X0665166Y0525846
X0665166Y0540020
X0665166Y0532933
X0667666Y0532933
X0605011Y0623600
X0659209Y0691851
X0661018Y0707592
X0662092Y0666275
X0657967Y0662981
X0650958Y0668153
X0658064Y0650119
X0658233Y0646449
X0665643Y0646055
X0609472Y0634946
X0650958Y0677843
X0648352Y0645467
X0647361Y0653161
X0661768Y0705043
X0656157Y0691851
X0661776Y0662981
X0655752Y0668885
X0573778Y0747437
X0575979Y0732517
X0586060Y0793145
X0576556Y0728219
X0582737Y0819831
X0582100Y0787600
X0571984Y0784507
X0583102Y0767137
X0585912Y0778470
X0588659Y0790336
X0578271Y0763556
X0570038Y0752339
X0588231Y0801520
X0588272Y0804601
X0588377Y0807536
X0588345Y0798030
X0571493Y0763090
X0578204Y0775137
X0587183Y0785008
X0577638Y0769772
X0581001Y0810973
X0570578Y0749800
X0584624Y0781850
X0569186Y0787332
X0570695Y0767052
X0574620Y0772724
X0573805Y0728301
X0579758Y0817753
X0583501Y0800831
X0581001Y0814123
X0580327Y0892000
X0604715Y0914640
X0583065Y0903294
X0586136Y0908935
X0601084Y0913544
X0592110Y0895611
X0592272Y0877262
X0572476Y0845535
X0573300Y0829600
X0581158Y0823473
X0579827Y0888000
X0588001Y0829624
X0577501Y0829069
X0622270Y0864781
X0569577Y0886913
X0572171Y0842346
X0597129Y0913386
X0582706Y0908959
X0579251Y0903364
X0592238Y0880612
X0579827Y0884000
X0591754Y0956979
X0586103Y0961807
X0570603Y0957207
X0593658Y1021954
X0593658Y1009354
X0599113Y1012354
X0593613Y1012354
X0591403Y0936007
X0591403Y0938807
X0585703Y0941307
X0589203Y0941407
X0577704Y1016827
X0571857Y1016827
X0612923Y0997860
X0572923Y0988813
X0596923Y0988813
X0604923Y0988813
X0592923Y0988813
X0608923Y0988813
X0588923Y0988813
X0580923Y0988813
X0576923Y0988813
X0608965Y0966414
X0616923Y0988813
X0600923Y0988813
X0584923Y0988813
X0602484Y0965764
X0597556Y0965829
X0573895Y0965319
X0605733Y0941137
X0609133Y0941137
X0618878Y1011914
X0573103Y0941307
X0569403Y0951807
X0576003Y0935107
X0581703Y0940907
X0577903Y0940907
X0577303Y0954507
X0581903Y0954507
X0589603Y0952907
X0571857Y1009354
X0577249Y0965445
X0606142Y0965665
X0602385Y0940920
X0577666Y1021954
X0581166Y1021954
X0584923Y0997860
X0572923Y0997860
X0581166Y1009354
X0577666Y1009354
X0588923Y0997860
X0576923Y0997860
X0580923Y0997860
X0602603Y1012354
X0600923Y0997860
X0604923Y0997860
X0592923Y0997860
X0596923Y0997860
X0608923Y0997860
X0616923Y0997860
X0612489Y0941024
X0617894Y1043955
X0582012Y1102091
X0582012Y1114691
X0593613Y1024954
X0599113Y1024954
X0581967Y1117691
X0587467Y1117691
X0587467Y1105091
X0581967Y1105091
X0571857Y1029427
X0577704Y1029427
X0587880Y1034834
X0617634Y1049283
X0612955Y1062941
X0606434Y1041904
X0607993Y1036920
X0610780Y1051037
X0603682Y1053457
X0621479Y1030482
X0621592Y1033862
X0569520Y1114691
X0569520Y1102091
X0590957Y1117691
X0590957Y1105091
X0591898Y1035011
X0604405Y1034870
X0602603Y1024954
X0620715Y1046785
X0619086Y1056453
X0620151Y1040363
X0582012Y1152491
X0582012Y1165091
X0582012Y1177691
X0582012Y1139891
X0582012Y1127291
X0587467Y1142891
X0581967Y1142891
X0581967Y1130291
X0587467Y1130291
X0587467Y1155491
X0581967Y1155491
X0587467Y1168091
X0581967Y1168091
X0587467Y1180691
X0581967Y1180691
X0594183Y1220068
X0569135Y1214372
X0575620Y1207737
X0622736Y1159350
X0626476Y1155610
X0622736Y1151870
X0569520Y1177691
X0569520Y1165091
X0569520Y1152491
X0569520Y1127291
X0569520Y1139891
X0584024Y1209607
X0578298Y1215195
X0590957Y1168091
X0590957Y1142891
X0590957Y1155491
X0590957Y1130291
X0590957Y1180691
X0592634Y1234921
X0583520Y1230407
X0586502Y1227300
X0592885Y1229402
X0593519Y1224472
X0569882Y1223749
X0666408Y1384297
X0654168Y1408495
X0663008Y1384297
X0650768Y1408495
X0650768Y1360099
X0641928Y1384297
X0638528Y1384297
X0654168Y1360099
X0650768Y1396583
X0666408Y1372385
X0641928Y1372385
X0663008Y1372385
X0650768Y1348187
X0654168Y1348187
X0654168Y1396583
X0638528Y1372385
X0663008Y1348187
X0663008Y1396583
X0654168Y1372385
X0666408Y1348187
X0638528Y1396583
X0666408Y1396583
X0626288Y1396583
X0650768Y1372385
X0629688Y1396583
X0641928Y1396583
X0663008Y1408495
X0666408Y1408495
X0650768Y1384297
X0663008Y1360099
X0629688Y1408495
X0641928Y1408495
X0666408Y1360099
X0654168Y1384297
X0649990Y1362595
X0649990Y1357603
X0649990Y1345691
X0649990Y1350683
X0667186Y1362595
X0667186Y1357603
X0662230Y1362595
X0662230Y1357603
X0654946Y1362595
X0654946Y1357603
X0662230Y1345691
X0654946Y1345691
X0667186Y1345691
X0667186Y1350683
X0662230Y1350683
X0654946Y1350683
X0630466Y1410991
X0637750Y1386793
X0625510Y1410991
X0630466Y1405999
X0630466Y1399079
X0637750Y1369889
X0637750Y1381801
X0637750Y1374881
X0625510Y1394087
X0625510Y1405999
X0625510Y1399079
X0630466Y1394087
X0654946Y1374881
X0649990Y1369889
X0654946Y1369889
X0649990Y1374881
X0642706Y1399079
X0642706Y1369889
X0642706Y1381801
X0642706Y1374881
X0637750Y1394087
X0642706Y1394087
X0637750Y1405999
X0637750Y1399079
X0642706Y1405999
X0654946Y1386793
X0654946Y1381801
X0649990Y1386793
X0649990Y1381801
X0642706Y1410991
X0642706Y1386793
X0637750Y1410991
X0662230Y1386793
X0667186Y1386793
X0649990Y1410991
X0655046Y1410991
X0662230Y1381801
X0662230Y1374881
X0667186Y1369889
X0649990Y1394087
X0667186Y1381801
X0667186Y1374881
X0649990Y1405999
X0649990Y1399079
X0655046Y1394087
X0655046Y1405999
X0655046Y1399079
X0662230Y1369889
X0662230Y1410991
X0662230Y1399079
X0662230Y1393993
X0662230Y1405999
X0667186Y1393993
X0667186Y1405999
X0667186Y1399079
X0667186Y1410991
X0638528Y1408495
X0626288Y1408495
X0591872Y1518071
X0591481Y1509313
X0577931Y1505687
X0591487Y1501687
X0590826Y1495688
X0572432Y1521462
X0588859Y1490895
X0581803Y1509687
X0572849Y1518702
X0582027Y1502800
X0578859Y1497758
X0581803Y1493687
X0588507Y1514141
X0587689Y1505724
X0592978Y1514812
X0587858Y1517942
X0583740Y1520640
X0583800Y1518000
X0627354Y1496621
X0636015Y1496221
X0627354Y1491890
X0636015Y1491490
X0636015Y1485598
X0627354Y1487159
X0636015Y1470244
X0627354Y1471805
X0627354Y1481267
X0636015Y1480867
X0627354Y1476536
X0636015Y1476136
X0627354Y1456451
X0627354Y1465913
X0636015Y1465513
X0627354Y1461182
X0636015Y1460782
X0636015Y1516307
X0636015Y1506845
X0636015Y1500952
X0627354Y1502514
X0636015Y1511576
X0627354Y1511976
X0627354Y1507245
X0653338Y1460782
X0644677Y1465913
X0644677Y1456451
X0644677Y1461182
X0653338Y1465513
X0653338Y1516307
X0644677Y1507245
X0644677Y1502514
X0653338Y1506845
X0653338Y1500952
X0653338Y1511576
X0644677Y1511976
X0653338Y1485598
X0653338Y1496221
X0644677Y1487159
X0644677Y1491890
X0644677Y1496621
X0653338Y1491490
X0644677Y1481267
X0653338Y1476136
X0653338Y1470244
X0653338Y1480867
X0644677Y1471805
X0644677Y1476536
X0662000Y1471805
X0662000Y1476536
X0662000Y1481267
X0662000Y1461182
X0662000Y1465913
X0662000Y1456451
X0662000Y1507245
X0662000Y1502514
X0662000Y1511976
X0662000Y1487159
X0662000Y1491890
X0662000Y1496621
X0579809Y1528163
X0583809Y1533025
X0587809Y1528389
X0613738Y1546507
X0595809Y1532133
X0621727Y1556800
X0572507Y1541375
X0577571Y1544013
X0583809Y1541607
X0587809Y1545854
X0591809Y1542407
X0595809Y1546214
X0575809Y1532912
X0570796Y1530309
X0580700Y1544100
X0598800Y1546400
X0591858Y1523542
X0575332Y1523740
X0569349Y1541947
X0577645Y1540982
X0573784Y1530646
X0583661Y1529142
X0627354Y1609607
X0636015Y1609207
X0627354Y1598984
X0636015Y1598584
X0636015Y1603315
X0627354Y1604876
X0636015Y1587960
X0627354Y1589522
X0627354Y1583629
X0636015Y1583229
X0627354Y1594253
X0636015Y1593853
X0627354Y1578898
X0636015Y1578498
X0636015Y1572606
X0627354Y1574167
X0627354Y1568275
X0636015Y1567875
X0627354Y1563544
X0636015Y1563144
X0627354Y1558813
X0627354Y1614338
X0636015Y1613938
X0636015Y1618669
X0644677Y1563544
X0653338Y1563144
X0644677Y1558813
X0653338Y1618669
X0644677Y1614338
X0653338Y1598584
X0653338Y1603315
X0644677Y1609607
X0644677Y1604876
X0644677Y1598984
X0653338Y1609207
X0644677Y1583629
X0653338Y1583229
X0644677Y1589522
X0644677Y1594253
X0653338Y1593853
X0653338Y1587960
X0644677Y1568275
X0653338Y1567875
X0644677Y1574167
X0644677Y1578898
X0653338Y1578498
X0653338Y1572606
X0653338Y1613938
X0662000Y1558813
X0662000Y1563544
X0662000Y1614338
X0662000Y1609607
X0662000Y1604876
X0662000Y1598984
X0662000Y1583629
X0662000Y1589522
X0662000Y1594253
X0662000Y1574167
X0662000Y1578898
X0662000Y1568275
X0612000Y1644980
X0632000Y1644980
X0652000Y1644980
X0729600Y1625165
X0738325Y1634485
X0743331Y1627871
X0762776Y1629415
X0747590Y1627871
X0752150Y1627871
X0672000Y1644980
X0692000Y1644980
X0712000Y1644980
X0732000Y1644980
X0752000Y1644980
X0732268Y1618260
X0740530Y1524113
X0768361Y1610083
X0763542Y1590186
X0759802Y1590864
X0738775Y1597866
X0749704Y1608631
X0749786Y1590517
X0736067Y1611892
X0732825Y1604100
X0737892Y1602340
X0741705Y1622015
X0756358Y1613767
X0762671Y1619367
X0755187Y1580821
X0747140Y1581335
X0744924Y1617709
X0766433Y1583713
X0735878Y1617010
X0748924Y1617709
X0740640Y1586885
X0751140Y1581335
X0767310Y1599164
X0756358Y1616917
X0670661Y1567875
X0670661Y1578498
X0670661Y1572606
X0679322Y1568275
X0679322Y1574167
X0679322Y1578898
X0679322Y1563544
X0670661Y1563144
X0679322Y1558813
X0670661Y1613938
X0670661Y1618669
X0679322Y1614338
X0679322Y1598984
X0670661Y1609207
X0670661Y1598584
X0670661Y1603315
X0679322Y1609607
X0679322Y1604876
X0679322Y1589522
X0679322Y1594253
X0670661Y1583229
X0670661Y1593853
X0670661Y1587960
X0679322Y1583629
X0696645Y1583629
X0687984Y1593853
X0687984Y1587960
X0696645Y1594253
X0696645Y1589522
X0687984Y1567875
X0696645Y1568275
X0687984Y1578498
X0687984Y1572606
X0696645Y1578898
X0696645Y1574167
X0687984Y1563144
X0696645Y1563544
X0696645Y1558813
X0687984Y1618669
X0696645Y1614338
X0687984Y1613938
X0696645Y1604876
X0687984Y1609207
X0687984Y1598584
X0687984Y1603315
X0696645Y1609607
X0696645Y1598984
X0687984Y1583229
X0749439Y1458777
X0760398Y1440276
X0768812Y1453306
X0765713Y1437365
X0755035Y1443524
X0768910Y1437741
X0742655Y1445733
X0670661Y1480867
X0679322Y1471805
X0679322Y1476536
X0679322Y1481267
X0670661Y1476136
X0670661Y1470244
X0670661Y1465513
X0670661Y1460782
X0679322Y1465913
X0679322Y1456451
X0679322Y1461182
X0670661Y1516307
X0670661Y1511576
X0679322Y1507245
X0679322Y1502514
X0679322Y1511976
X0670661Y1506845
X0670661Y1500952
X0679322Y1491890
X0679322Y1496621
X0670661Y1491490
X0670661Y1485598
X0670661Y1496221
X0679322Y1487159
X0687984Y1480867
X0696645Y1476537
X0696645Y1471806
X0696645Y1481268
X0687984Y1476136
X0687984Y1470244
X0687984Y1465513
X0687984Y1460782
X0696645Y1465914
X0696645Y1456452
X0696645Y1461183
X0687984Y1516307
X0687984Y1506845
X0687984Y1500952
X0687984Y1511576
X0696645Y1507246
X0696645Y1502515
X0696645Y1511977
X0696645Y1487160
X0696645Y1496622
X0687984Y1491490
X0687984Y1485598
X0687984Y1496221
X0696645Y1491891
X0727608Y1408401
X0703128Y1408495
X0711968Y1384297
X0690888Y1384297
X0675248Y1408495
X0727608Y1360099
X0736448Y1384297
X0760928Y1384297
X0675248Y1360099
X0715368Y1384297
X0739848Y1384297
X0724208Y1360099
X0678648Y1360099
X0687488Y1384297
X0748688Y1360099
X0678648Y1408495
X0699728Y1360099
X0724208Y1408401
X0699728Y1408495
X0703128Y1360099
X0764328Y1384297
X0752088Y1360099
X0752088Y1348187
X0736448Y1372385
X0703128Y1396583
X0724208Y1348187
X0675248Y1348187
X0760928Y1372385
X0678648Y1396583
X0703128Y1348187
X0748688Y1348187
X0699728Y1396583
X0675248Y1396583
X0678648Y1348187
X0699728Y1348187
X0711968Y1372385
X0727608Y1396489
X0739848Y1372385
X0687488Y1372385
X0724208Y1396489
X0727608Y1348187
X0715368Y1372385
X0764328Y1372385
X0690888Y1372385
X0711968Y1360099
X0699728Y1384297
X0736448Y1408401
X0711968Y1408495
X0703128Y1384297
X0736448Y1348187
X0727608Y1372385
X0739848Y1360099
X0752088Y1384297
X0764328Y1348187
X0727608Y1384297
X0687488Y1348187
X0760928Y1348187
X0687488Y1396583
X0711968Y1396583
X0715368Y1360099
X0690888Y1396583
X0760928Y1360099
X0699728Y1372385
X0764328Y1360099
X0715368Y1396583
X0739848Y1408401
X0715368Y1408495
X0724208Y1384297
X0675248Y1372385
X0703128Y1372385
X0736448Y1360099
X0736448Y1396489
X0739848Y1348187
X0748688Y1384297
X0690888Y1348187
X0739848Y1396489
X0711968Y1348187
X0724208Y1372385
X0748688Y1372385
X0678648Y1372385
X0752088Y1372385
X0715368Y1348187
X0690888Y1360099
X0690888Y1408495
X0678648Y1384297
X0687488Y1408495
X0687488Y1360099
X0675248Y1384297
X0674470Y1350683
X0679426Y1345691
X0674470Y1345691
X0679426Y1362595
X0679426Y1357603
X0674470Y1362595
X0674470Y1357603
X0679426Y1350683
X0686710Y1386793
X0686710Y1381801
X0691666Y1362595
X0691666Y1357603
X0686710Y1362595
X0686710Y1357603
X0686710Y1369889
X0691666Y1345691
X0686710Y1345691
X0686710Y1374881
X0691666Y1350683
X0686710Y1350683
X0698950Y1357603
X0703906Y1362595
X0703906Y1357603
X0691666Y1386793
X0698950Y1362595
X0691666Y1381801
X0691666Y1374881
X0703906Y1345597
X0691666Y1369889
X0698950Y1345597
X0703906Y1350683
X0698950Y1350683
X0679426Y1386793
X0674470Y1386793
X0674470Y1369889
X0679426Y1369889
X0679426Y1381801
X0674470Y1381801
X0674470Y1374881
X0679426Y1374881
X0723430Y1405905
X0723430Y1393993
X0711190Y1345691
X0716146Y1345691
X0723430Y1398985
X0711190Y1350683
X0716146Y1350683
X0703906Y1374881
X0698950Y1369889
X0698950Y1381801
X0698950Y1374881
X0703906Y1369889
X0703906Y1381801
X0716146Y1362595
X0711190Y1362595
X0711190Y1357603
X0716146Y1357603
X0723430Y1410897
X0698950Y1386793
X0703906Y1386793
X0728386Y1405905
X0723430Y1362595
X0723430Y1357603
X0728386Y1362595
X0728386Y1357603
X0728386Y1410897
X0728386Y1350683
X0728386Y1393993
X0723430Y1345691
X0728386Y1345691
X0728386Y1398985
X0723430Y1350683
X0711190Y1386793
X0679426Y1410991
X0674470Y1410991
X0711190Y1381801
X0711190Y1374881
X0674470Y1399079
X0679426Y1394087
X0674470Y1394087
X0679426Y1405999
X0679426Y1399079
X0674470Y1405999
X0711190Y1369889
X0735670Y1374881
X0735670Y1369889
X0740626Y1345691
X0735670Y1345691
X0740626Y1350683
X0735670Y1350683
X0691666Y1399079
X0691666Y1405999
X0691666Y1394087
X0716146Y1369889
X0716146Y1381801
X0716146Y1374881
X0686710Y1399079
X0686710Y1405999
X0686710Y1394087
X0735670Y1381801
X0735670Y1386793
X0740626Y1362595
X0740626Y1357603
X0735670Y1362595
X0735670Y1357603
X0691666Y1410991
X0716146Y1386793
X0686710Y1410991
X0752866Y1350683
X0752866Y1345691
X0740626Y1374881
X0747910Y1350683
X0740626Y1369889
X0747910Y1345691
X0698950Y1410991
X0723430Y1386793
X0728386Y1386793
X0698950Y1394087
X0698950Y1405999
X0698950Y1399079
X0723430Y1374881
X0723430Y1381801
X0723430Y1369889
X0728386Y1369889
X0728386Y1374881
X0728386Y1381801
X0747910Y1362595
X0747910Y1357603
X0752866Y1362595
X0752866Y1357603
X0740626Y1386793
X0740626Y1381801
X0752866Y1369889
X0752866Y1381801
X0752866Y1374881
X0740626Y1410897
X0740626Y1405905
X0735670Y1410897
X0735670Y1405905
X0760150Y1362595
X0760150Y1357603
X0735670Y1398985
X0740626Y1398985
X0740626Y1393993
X0735670Y1393993
X0760150Y1350683
X0760150Y1345597
X0703906Y1410991
X0747910Y1386793
X0752866Y1386793
X0747910Y1369889
X0703906Y1405999
X0703906Y1399079
X0747910Y1381801
X0747910Y1374881
X0703906Y1394087
X0765106Y1357603
X0765106Y1345597
X0765106Y1350683
X0711190Y1410991
X0716146Y1410991
X0760150Y1386793
X0711190Y1393993
X0716146Y1393993
X0711190Y1405999
X0711190Y1399079
X0716146Y1405999
X0716146Y1399079
X0760150Y1369889
X0760150Y1381801
X0760150Y1374881
X0765106Y1362595
X0765106Y1386793
X0765106Y1369889
X0765106Y1381801
X0765106Y1374881
X0722789Y0927095
X0732306Y0942682
X0720271Y0931730
X0725194Y0942073
X0727116Y0959326
X0733798Y0950186
X0743062Y1004460
X0742407Y0988452
X0728846Y0948331
X0722400Y0942500
X0724547Y0958287
X0720373Y0940310
X0745673Y1007009
X0738707Y0987952
X0732713Y0853890
X0724707Y0893143
X0733680Y0828977
X0730880Y0828924
X0728692Y0886653
X0736452Y0890548
X0728503Y0891692
X0722600Y0869600
X0719661Y0904900
X0736000Y0864266
X0735576Y0861780
X0725318Y0890354
X0690449Y0814406
X0713222Y0790812
X0713222Y0793312
X0723177Y0728219
X0712901Y0821600
X0691991Y0759581
X0692356Y0764614
X0692221Y0773449
X0692155Y0778974
X0692478Y0730641
X0733000Y0816000
X0725667Y0732161
X0710275Y0786131
X0702677Y0775159
X0702677Y0780659
X0702691Y0756971
X0702691Y0762971
X0741993Y0775909
X0742000Y0768137
X0743428Y0772418
X0741992Y0763480
X0717434Y0782500
X0721163Y0738981
X0741000Y0771100
X0744069Y0746617
X0720271Y0782481
X0713425Y0786029
X0702677Y0784659
X0702677Y0771159
X0702691Y0753471
X0702691Y0766471
X0704446Y0760611
X0721218Y0742131
X0710196Y0707562
X0722473Y0693718
X0705390Y0655789
X0703680Y0697094
X0703600Y0702212
X0715802Y0706446
X0711328Y0653821
X0705776Y0678519
X0702086Y0678462
X0699188Y0656321
X0720985Y0711658
X0723656Y0705858
X0716623Y0702463
X0713200Y0699676
X0703604Y0699653
X0716350Y0699477
X0698936Y0678462
X0700164Y0636842
X0703669Y0665140
X0716656Y0646429
X0706070Y0638125
X0734819Y0646429
X0682586Y0530000
X0704364Y0618288
X0681190Y0562800
X0681126Y0558800
X0702448Y0542712
X0681286Y0549800
X0681086Y0547075
X0713791Y0614517
X0721091Y0589857
X0721091Y0604030
X0713791Y0600344
X0721091Y0607430
X0721091Y0564910
X0713791Y0586171
X0721091Y0575684
X0713791Y0568597
X0721091Y0579084
X0713791Y0596944
X0713791Y0532731
X0713791Y0582771
X0713791Y0536131
X0721091Y0593257
X0713791Y0571997
X0713791Y0611117
X0721091Y0529044
X0721091Y0561510
X0721091Y0525644
X0670066Y0531088
X0670066Y0527688
X0711463Y0546712
X0682086Y0540500
X0669546Y0560500
X0681011Y0543925
X0681586Y0555000
X0672466Y0532933
X0672466Y0525846
X0711391Y0616359
X0716191Y0616359
X0718691Y0609272
X0716191Y0609272
X0711391Y0609272
X0716191Y0595099
X0711391Y0595099
X0718691Y0595099
X0718691Y0602185
X0711391Y0602186
X0716191Y0602186
X0711391Y0580926
X0716191Y0580926
X0718691Y0580926
X0716191Y0588013
X0718691Y0588012
X0711391Y0588013
X0716191Y0573839
X0718691Y0573839
X0711391Y0573839
X0716191Y0566752
X0718691Y0566752
X0718691Y0559665
X0711391Y0566752
X0711391Y0537973
X0711391Y0530886
X0716191Y0537973
X0716191Y0530886
X0718691Y0530886
X0711391Y0523800
X0718691Y0523800
X0716191Y0523800
X0723491Y0602185
X0731319Y0574338
X0723491Y0580926
X0723491Y0588012
X0723491Y0573839
X0731672Y0565574
X0731291Y0559665
X0723491Y0559665
X0723491Y0566752
X0732388Y0535677
X0732549Y0529136
X0723491Y0537973
X0723491Y0530886
X0723491Y0523799
X0731418Y0616358
X0723491Y0616358
X0723491Y0609272
X0723491Y0595099
X0740463Y0532756
X0740542Y0525483
X0738062Y0537973
X0749402Y0530886
X0749402Y0537973
X0749402Y0523799
X0741666Y0608117
X0749402Y0616358
X0749402Y0609272
X0749402Y0595099
X0749402Y0602185
X0741602Y0573839
X0741452Y0579978
X0749402Y0580925
X0749402Y0588012
X0749402Y0573839
X0741602Y0566752
X0741602Y0559665
X0749402Y0566752
X0749402Y0559665
X0680586Y0568000
X0702448Y0546712
X0711598Y0438323
X0724362Y0504731
X0722097Y0446595
X0720996Y0442856
X0731952Y0446606
X0711764Y0445873
X0732035Y0442606
X0750393Y0454177
X0750393Y0451677
X0752893Y0454177
X0752893Y0451677
X0752097Y0463618
X0752097Y0460218
X0733430Y0467367
X0752339Y0440869
X0752339Y0435669
X0752339Y0430469
X0752339Y0433069
X0752339Y0438269
X0749539Y0433069
X0749539Y0430469
X0749539Y0435669
X0749539Y0440869
X0749539Y0438269
X0732959Y0463479
X0675237Y0465611
X0710643Y0456335
X0713791Y0477824
X0721091Y0511471
X0713791Y0521958
X0721091Y0467337
X0721091Y0514871
X0713791Y0518558
X0713791Y0491997
X0721091Y0481510
X0713791Y0488597
X0713791Y0474424
X0721091Y0470737
X0721091Y0484910
X0670066Y0486954
X0670066Y0436915
X0670066Y0472781
X0670066Y0513515
X0670066Y0483554
X0670066Y0469381
X0670066Y0433515
X0670066Y0516915
X0670066Y0422741
X0739316Y0458572
X0719612Y0451108
X0719051Y0458455
X0722097Y0453881
X0735599Y0449961
X0709781Y0442956
X0678461Y0455981
X0718691Y0509626
X0749402Y0472579
X0741602Y0472579
X0749402Y0486752
X0749402Y0479665
X0741602Y0486752
X0741072Y0478958
X0731433Y0475262
X0723491Y0472579
X0723491Y0486752
X0723491Y0479665
X0731433Y0482666
X0711391Y0472579
X0716191Y0472579
X0718691Y0472579
X0718691Y0486752
X0716191Y0486752
X0711391Y0486752
X0711391Y0479666
X0718691Y0479666
X0716191Y0479666
X0672466Y0474626
X0672466Y0481712
X0672466Y0467539
X0672466Y0431673
X0672466Y0438760
X0672466Y0424586
X0718691Y0465492
X0711764Y0449873
X0713162Y0434493
X0723491Y0451319
X0723491Y0458406
X0723031Y0430098
X0723031Y0432598
X0723031Y0435098
X0723031Y0437598
X0723031Y0440098
X0723315Y0462264
X0731291Y0466027
X0723491Y0465492
X0741218Y0437072
X0741402Y0433570
X0741381Y0430760
X0741259Y0439963
X0749402Y0465492
X0739333Y0470136
X0741568Y0460250
X0741602Y0465492
X0749402Y0458406
X0741465Y0452018
X0741523Y0454744
X0741503Y0443180
X0755593Y0445908
X0759543Y0445787
X0672466Y0511673
X0672466Y0518760
X0672466Y0488799
X0718691Y0516713
X0711391Y0516713
X0716191Y0516713
X0716191Y0493839
X0711391Y0493839
X0731291Y0509626
X0731906Y0522134
X0731984Y0514608
X0723491Y0509626
X0723491Y0516713
X0731249Y0495088
X0723491Y0493839
X0731433Y0489435
X0741602Y0516713
X0741602Y0509626
X0749402Y0509626
X0749402Y0516713
X0741602Y0493839
X0749402Y0493839
X0706211Y0465874
X0712692Y0356779
X0689486Y0339583
X0682857Y0339477
X0766344Y0397912
X0685353Y0396718
X0766344Y0381912
X0766344Y0377912
X0731511Y0381113
X0734661Y0393633
X0759624Y0353961
X0759029Y0328867
X0670066Y0394395
X0670066Y0419341
X0670066Y0408568
X0670066Y0405168
X0670066Y0390995
X0754805Y0339559
X0723440Y0391496
X0717420Y0404334
X0751086Y0398583
X0723404Y0379657
X0756086Y0386500
X0753086Y0403500
X0717105Y0410964
X0755086Y0409000
X0721900Y0384500
X0723440Y0398583
X0752785Y0382047
X0749606Y0384410
X0755086Y0391496
X0756086Y0377912
X0749444Y0393858
X0756174Y0397912
X0672466Y0403326
X0672466Y0396240
X0685353Y0404718
X0685353Y0400718
X0685353Y0408718
X0672466Y0410413
X0672466Y0389153
X0685353Y0392718
X0686012Y0339795
X0685353Y0412718
X0672466Y0417499
X0722097Y0403307
X0722097Y0410394
X0734606Y0379562
X0731511Y0390500
X0749586Y0403307
X0749586Y0410394
X0741161Y0381500
X0760407Y0324494
X0758381Y0395391
X0756800Y0403824
X0752341Y0407148
X0766344Y0401924
X0766344Y0405924
X0766344Y0409924
X0758038Y0381143
X0766344Y0385912
X0766344Y0389912
X0766344Y0393924
X0759029Y0332017
X0763898Y0342319
X0687055Y0376456
X0742336Y0265896
X0747352Y0266114
X0738884Y0281716
X0737249Y0265701
X0744825Y0281982
X0690504Y0253198
X0680017Y0244571
X0677397Y0249108
X0718338Y0305272
X0684410Y0228646
X0693406Y0227824
X0763653Y0224536
X0742577Y0256303
X0719798Y0258880
X0695713Y0244297
X0689151Y0230556
X0697996Y0230117
X0728767Y0270026
X0731567Y0270026
X0734067Y0270026
X0734067Y0267526
X0728767Y0267526
X0731567Y0267526
X0719873Y0264180
X0722373Y0264180
X0683367Y0232971
X0693493Y0246874
X0741051Y0316389
X0688136Y0242078
X0681449Y0226320
X0694012Y0238714
X0750598Y0270695
X0750598Y0268195
X0750401Y0248765
X0750460Y0236189
X0748209Y0224421
X0749909Y0231021
X0749909Y0228221
X0762058Y0265897
X0759558Y0265897
X0755898Y0270695
X0753098Y0270695
X0755898Y0268195
X0753098Y0268195
X0752901Y0248765
X0755401Y0248765
X0755460Y0236189
X0752960Y0236189
X0683260Y0253198
X0683341Y0236121
X0680375Y0238589
X0690551Y0247292
X0689777Y0238689
X0698012Y0238714
X0716544Y0223726
X0716544Y0226226
X0716544Y0231226
X0716544Y0228726
X0733404Y0288190
X0730604Y0288190
X0728104Y0285690
X0730604Y0285690
X0728104Y0288190
X0722590Y0293796
X0720090Y0293796
X0733404Y0285690
X0730652Y0248891
X0733152Y0248891
X0734969Y0231786
X0730950Y0236611
X0733450Y0236611
X0727000Y0231461
X0734969Y0229286
X0727000Y0223661
X0733507Y0226141
X0727000Y0226461
X0730707Y0226141
X0727000Y0228961
X0745630Y0290755
X0737630Y0290755
X0741630Y0290755
X0751711Y0281307
X0747607Y0279208
X0746577Y0256535
X0738577Y0256535
X0735652Y0248891
X0735950Y0236611
X0738662Y0224712
X0767099Y0316731
X0756201Y0293645
X0753701Y0293645
X0753701Y0290845
X0753701Y0288345
X0756201Y0290845
X0756201Y0288345
X0672313Y0124879
X0677335Y0124663
X0756622Y0152373
X0741852Y0148277
X0744472Y0143740
X0750667Y0192300
X0760574Y0178560
X0678679Y0138838
X0757522Y0143518
X0682316Y0125107
X0765267Y0157370
X0684830Y0148717
X0760777Y0207037
X0690930Y0143762
X0753182Y0198671
X0760843Y0212455
X0760754Y0200864
X0753035Y0141247
X0742313Y0177616
X0742894Y0172190
X0745567Y0168697
X0742333Y0215632
X0727000Y0215713
X0742333Y0213132
X0738630Y0211359
X0738630Y0213859
X0727000Y0210713
X0731072Y0211695
X0733572Y0211695
X0731072Y0208695
X0733872Y0208695
X0727000Y0208213
X0727000Y0213213
X0716544Y0212978
X0716544Y0207978
X0716544Y0210478
X0716544Y0215478
X0737211Y0184012
X0734594Y0184221
X0737597Y0181366
X0740392Y0181009
X0734386Y0181426
X0760464Y0183834
X0760637Y0172665
X0759984Y0190185
X0754709Y0192490
X0759772Y0152562
X0765024Y0219379
X0672070Y0218085
X0681383Y0221970
X0678670Y0216385
X0681383Y0216970
X0681383Y0219470
X0674870Y0218085
X0761450Y0186629
X0746655Y0191941
X0768016Y0161306
X0737005Y0141247
X0683789Y0142862
X0733233Y0147540
X0691732Y0206806
X0694396Y0202048
X0689959Y0210509
X0687459Y0210509
X0689232Y0206806
X0691396Y0201748
X0692378Y0195176
X0694878Y0195176
X0694396Y0199248
X0689878Y0195176
X0687378Y0195176
X0691396Y0199248
X0735389Y0167993
X0735389Y0170493
X0735389Y0162793
X0735389Y0165393
X0725689Y0162368
X0728289Y0162368
X0697499Y0128828
X0697499Y0125428
X0690199Y0135915
X0690199Y0132515
X0737816Y0125396
X0748218Y0132509
X0737816Y0128796
X0748794Y0221708
X0751294Y0221708
X0748664Y0206767
X0751164Y0206767
X0758144Y0221642
X0753794Y0221708
X0753664Y0206767
X0669056Y0133298
X0680879Y0206838
X0678379Y0206838
X0674691Y0203393
X0676950Y0201683
X0672191Y0203393
X0680131Y0195176
X0676950Y0198883
X0677331Y0195176
X0674831Y0195176
X0672331Y0195176
X0685695Y0141228
X0683789Y0146012
X0671203Y0134579
X0677056Y0133298
X0696331Y0213539
X0688583Y0150847
X0699799Y0137756
X0692599Y0137757
X0687799Y0137757
X0699799Y0130670
X0699799Y0123583
X0695099Y0130670
X0692599Y0130670
X0687799Y0130670
X0692599Y0123584
X0695099Y0123583
X0687799Y0123584
X0709271Y0137756
X0714500Y0137756
X0709276Y0130670
X0717909Y0123583
X0717909Y0130670
X0708223Y0124576
X0736750Y0188727
X0733233Y0151540
X0725909Y0137756
X0725909Y0123583
X0725909Y0130670
X0748813Y0146461
X0745722Y0136687
X0750714Y0136687
X0750714Y0122513
X0750714Y0131731
X0735320Y0129574
X0735320Y0124618
X0740312Y0124618
X0740312Y0129574
X0745722Y0122513
X0745722Y0131731
X0738662Y0222212
X0745363Y0206760
X0736883Y0191941
X0743383Y0184619
X0749415Y0185165
X0749415Y0180572
X0747715Y0152367
X0754053Y0185121
X0757821Y0192421
X0754098Y0180527
X0748218Y0135909
X0672756Y0110784
X0677756Y0110784
X0745475Y0097475
X0707799Y0095236
X0761118Y0103621
X0752456Y0100625
X0692649Y0095111
X0728667Y0107649
X0728667Y0104249
X0756829Y0112083
X0717682Y0099961
X0697018Y0106561
X0717732Y0095236
X0768979Y0086046
X0765425Y0085731
X0713361Y0090615
X0751017Y0072615
X0708049Y0090650
X0751017Y0076587
X0768157Y0060438
X0765297Y0060513
X0765982Y0094351
X0671476Y0086012
X0684055Y0102495
X0763065Y0088801
X0671476Y0094374
X0738471Y0103783
X0745406Y0106186
X0678782Y0116594
X0678782Y0119594
X0734921Y0098551
X0688399Y0097667
X0758935Y0080581
X0758922Y0068581
X0762697Y0055513
X0697253Y0097667
X0726640Y0092874
X0696859Y0103411
X0726596Y0082593
X0726596Y0085193
X0726596Y0079993
X0726596Y0077393
X0726596Y0074793
X0690199Y0118342
X0690199Y0121742
X0697499Y0111255
X0697499Y0114655
X0737816Y0111223
X0748218Y0121735
X0669462Y0110784
X0684055Y0106495
X0685048Y0109172
X0682048Y0109172
X0679031Y0102249
X0697387Y0053619
X0690073Y0044662
X0699799Y0102323
X0699799Y0109410
X0699799Y0116496
X0695099Y0116497
X0692599Y0116497
X0687799Y0116497
X0695099Y0109410
X0717909Y0109410
X0717909Y0116496
X0708051Y0116496
X0708051Y0109410
X0707799Y0102323
X0717775Y0103037
X0708261Y0085584
X0710815Y0092849
X0708261Y0075184
X0708261Y0077784
X0708261Y0080384
X0708261Y0082984
X0717387Y0053619
X0725909Y0109410
X0725909Y0116496
X0734921Y0101701
X0731192Y0094017
X0735192Y0094017
X0725909Y0102323
X0742471Y0103783
X0735320Y0115401
X0735320Y0110445
X0740312Y0110445
X0740312Y0115401
X0745722Y0117557
X0750714Y0117557
X0739192Y0094017
X0743201Y0094017
X0748269Y0080140
X0748269Y0076140
X0748269Y0084140
X0735555Y0044773
X0735555Y0024773
X0753638Y0103621
X0762065Y0117040
X0763040Y0091951
X0765847Y0055513
X0767929Y0096890
X0748218Y0118335
X0737816Y0114623
X0718488Y-0036010
X0721741Y-0036024
X0724781Y-0037219
X0724781Y-0026433
X0721756Y-0025113
X0718503Y-0025127
X0721741Y-0027628
X0718488Y-0027642
X0718500Y-0030420
X0718500Y-0033320
X0718503Y-0038525
X0721756Y-0038539
X0841756Y-0077719
X0838503Y-0077705
X0736242Y0005374
X0755145Y0003000
X0838488Y-0066822
X0841741Y-0066808
X0838503Y-0064307
X0841756Y-0064293
X0844781Y-0065613
X0838500Y-0069600
X0844781Y-0076399
X0841741Y-0075204
X0838488Y-0075190
X0838500Y-0072500
X0775145Y0003000
X0791129Y0004469
X0838606Y0005374
X0850145Y0003000
X0780118Y0110784
X0775118Y0110784
X0847837Y0097475
X0810161Y0095236
X0854818Y0100625
X0863480Y0103621
X0795011Y0095111
X0831029Y0107649
X0831029Y0104249
X0799380Y0106561
X0820044Y0099961
X0859191Y0112083
X0820094Y0095236
X0867787Y0085731
X0815723Y0090615
X0853379Y0072615
X0810411Y0090650
X0853379Y0076587
X0868344Y0094351
X0867659Y0060513
X0773838Y0086012
X0769931Y0094279
X0786417Y0102495
X0769175Y0119594
X0769175Y0116594
X0865427Y0088801
X0773838Y0094374
X0847768Y0106186
X0840833Y0103783
X0781144Y0116594
X0781144Y0119594
X0837283Y0098551
X0790761Y0097667
X0861297Y0080581
X0861284Y0068581
X0865059Y0055513
X0829002Y0092874
X0799615Y0097667
X0799221Y0103411
X0828958Y0082593
X0828958Y0085193
X0828958Y0074793
X0828958Y0077393
X0828958Y0079993
X0792561Y0121742
X0792561Y0118342
X0799861Y0111255
X0799861Y0114655
X0850580Y0121735
X0840178Y0111223
X0771011Y0060922
X0797461Y0109410
X0786417Y0106495
X0790161Y0116497
X0797461Y0116497
X0794961Y0116497
X0799811Y0053597
X0792490Y0044773
X0792490Y0024773
X0810623Y0075184
X0810623Y0080384
X0810623Y0082984
X0802161Y0102323
X0802161Y0109410
X0802161Y0116496
X0810413Y0116496
X0810413Y0109410
X0810161Y0102323
X0810623Y0085584
X0813177Y0092849
X0810623Y0077784
X0828271Y0102323
X0828271Y0109410
X0828271Y0116496
X0820271Y0109410
X0820271Y0116496
X0820137Y0103037
X0819811Y0053597
X0844833Y0103783
X0842674Y0110445
X0842674Y0115401
X0848084Y0117557
X0837682Y0115401
X0837682Y0110445
X0837283Y0101701
X0833554Y0094017
X0845563Y0094017
X0837554Y0094017
X0841554Y0094017
X0837919Y0044773
X0837919Y0024773
X0850631Y0076140
X0850631Y0080140
X0850631Y0084140
X0856000Y0103621
X0853076Y0117557
X0864006Y0117261
X0865402Y0091951
X0868209Y0055513
X0787410Y0109172
X0769175Y0113394
X0773393Y0102249
X0777393Y0102249
X0781393Y0102249
X0771824Y0110784
X0784410Y0109172
X0850580Y0118335
X0840178Y0114623
X0774675Y0124879
X0779697Y0124663
X0769609Y0124283
X0853029Y0192300
X0862936Y0178560
X0781041Y0138838
X0769464Y0186778
X0784678Y0125107
X0787192Y0148717
X0863139Y0207037
X0793292Y0143762
X0769351Y0192665
X0863116Y0200864
X0863205Y0212455
X0769383Y0208864
X0862346Y0190185
X0862999Y0172665
X0845256Y0172190
X0862826Y0183834
X0844675Y0177616
X0847929Y0168697
X0844695Y0215632
X0829362Y0215713
X0844695Y0213132
X0833434Y0211695
X0840992Y0211359
X0840992Y0213859
X0835934Y0211695
X0833434Y0208695
X0836234Y0208695
X0829362Y0210713
X0829362Y0208213
X0818906Y0210478
X0818906Y0215478
X0818906Y0212978
X0818906Y0207978
X0829362Y0213213
X0836956Y0184221
X0839573Y0184012
X0836748Y0181426
X0839959Y0181366
X0842754Y0181009
X0857071Y0192490
X0867386Y0219379
X0783745Y0219470
X0783745Y0221970
X0781032Y0216385
X0783745Y0216970
X0777232Y0218085
X0774432Y0218085
X0769383Y0204864
X0863812Y0186629
X0849017Y0191941
X0769351Y0168665
X0769351Y0176665
X0786151Y0142862
X0796758Y0202048
X0793758Y0201748
X0792321Y0210509
X0789821Y0210509
X0791594Y0206806
X0794094Y0206806
X0793758Y0199248
X0792240Y0195176
X0789740Y0195176
X0794740Y0195176
X0797240Y0195176
X0796758Y0199248
X0837751Y0167993
X0837751Y0170493
X0837751Y0162793
X0837751Y0165393
X0828051Y0162368
X0830651Y0162368
X0799861Y0125428
X0799861Y0128828
X0792561Y0132515
X0792561Y0135915
X0840178Y0125396
X0840178Y0128796
X0850580Y0135909
X0851156Y0221708
X0856156Y0221708
X0853656Y0221708
X0860506Y0221642
X0851026Y0206767
X0856026Y0206767
X0853526Y0206767
X0793221Y0140296
X0769351Y0180665
X0769351Y0172665
X0773565Y0134579
X0769383Y0216864
X0769383Y0221864
X0769383Y0212864
X0769383Y0200864
X0774553Y0203393
X0779312Y0201683
X0777053Y0203393
X0783241Y0206838
X0780741Y0206838
X0774693Y0195176
X0782493Y0195176
X0777193Y0195176
X0779312Y0198883
X0779693Y0195176
X0798693Y0213539
X0790945Y0150847
X0786151Y0146012
X0788057Y0141228
X0790161Y0137757
X0794961Y0137757
X0790161Y0130670
X0797461Y0130670
X0794961Y0130670
X0790161Y0123584
X0794961Y0123584
X0797461Y0123583
X0802161Y0137756
X0811633Y0137756
X0802161Y0123583
X0802161Y0130670
X0811638Y0130670
X0810585Y0124576
X0828271Y0137756
X0816637Y0137756
X0828271Y0123583
X0828271Y0130670
X0820271Y0123583
X0820271Y0130670
X0847725Y0206760
X0845745Y0184619
X0839245Y0191941
X0839112Y0188727
X0848084Y0136687
X0848084Y0122513
X0848084Y0131731
X0837682Y0129574
X0837682Y0124618
X0842674Y0124618
X0842674Y0129574
X0841024Y0222212
X0856415Y0185121
X0851777Y0185165
X0860183Y0192421
X0856460Y0180527
X0851777Y0180572
X0853076Y0136687
X0853076Y0122513
X0853076Y0131731
X0771960Y0130898
X0779418Y0133298
X0850580Y0132509
X0847187Y0281982
X0849714Y0266114
X0789722Y0256394
X0839611Y0265701
X0779759Y0249108
X0841246Y0281716
X0844698Y0265896
X0782379Y0244571
X0863430Y0316970
X0863430Y0309368
X0809466Y0310604
X0809490Y0321368
X0809489Y0313830
X0809490Y0317368
X0809490Y0305368
X0817456Y0313368
X0817456Y0305368
X0817100Y0319600
X0822477Y0309368
X0786772Y0228646
X0791513Y0230556
X0866015Y0224536
X0844939Y0256303
X0795768Y0227824
X0790280Y0287421
X0798075Y0244297
X0786461Y0293028
X0822160Y0258880
X0771941Y0311740
X0784118Y0303962
X0800358Y0230117
X0836429Y0270026
X0833929Y0270026
X0833929Y0267526
X0836429Y0267526
X0831129Y0270026
X0831129Y0267526
X0824735Y0264180
X0822235Y0264180
X0771140Y0248371
X0795855Y0246874
X0785729Y0232971
X0805952Y0301675
X0790498Y0242078
X0783811Y0226320
X0796374Y0238714
X0855460Y0268195
X0861920Y0265897
X0858260Y0270695
X0858260Y0268195
X0864420Y0265897
X0855460Y0270695
X0852960Y0270695
X0852960Y0268195
X0857763Y0248765
X0855263Y0248765
X0852763Y0248765
X0857822Y0236189
X0855322Y0236189
X0852822Y0236189
X0850571Y0224421
X0852271Y0231021
X0852271Y0228221
X0776943Y0321649
X0780968Y0303839
X0771140Y0252371
X0782737Y0238589
X0788522Y0290304
X0785622Y0253198
X0785703Y0236121
X0792139Y0238689
X0792913Y0247292
X0800374Y0238714
X0825792Y0305225
X0830466Y0288190
X0830466Y0285690
X0822452Y0293796
X0824952Y0293796
X0818906Y0223726
X0818906Y0226226
X0818906Y0231226
X0818906Y0228726
X0829362Y0223661
X0829362Y0226461
X0829362Y0228961
X0829362Y0231461
X0847992Y0290755
X0839992Y0290755
X0843992Y0290755
X0835766Y0285690
X0835766Y0288190
X0832966Y0285690
X0832966Y0288190
X0835514Y0248891
X0838014Y0248891
X0840939Y0256535
X0848939Y0256535
X0833014Y0248891
X0837331Y0231786
X0833312Y0236611
X0838312Y0236611
X0835812Y0236611
X0835869Y0226141
X0833069Y0226141
X0841024Y0224712
X0837331Y0229286
X0856063Y0288345
X0858563Y0288345
X0856063Y0290845
X0856063Y0293645
X0858563Y0290845
X0858563Y0293645
X0854073Y0281307
X0849969Y0279208
X0772165Y0314890
X0842240Y0324854
X0795445Y0356950
X0829485Y0345101
X0863040Y0330140
X0863114Y0324505
X0864086Y0384000
X0809490Y0325368
X0809490Y0333368
X0809457Y0330459
X0845435Y0356172
X0822626Y0348066
X0772162Y0332584
X0868586Y0398500
X0793893Y0409502
X0825971Y0345101
X0789581Y0405011
X0848879Y0360849
X0856069Y0356426
X0852569Y0356712
X0868086Y0373750
X0867586Y0385000
X0854086Y0392999
X0867586Y0393000
X0861235Y0394000
X0860586Y0383000
X0849591Y0411388
X0855017Y0411969
X0846098Y0408715
X0861622Y0419688
X0858767Y0416685
X0858410Y0413890
X0858827Y0419896
X0861413Y0417071
X0863086Y0374500
X0858586Y0374500
X0854086Y0374500
X0797141Y0350368
X0774419Y0353470
X0861770Y0343006
X0800029Y0333368
X0800155Y0337368
X0801097Y0325858
X0769349Y0324518
X0772859Y0347937
X0778502Y0348015
X0777569Y0353506
X0772990Y0336324
X0784586Y0416000
X0784586Y0413500
X0784586Y0418500
X0784586Y0421000
X0792564Y0406410
X0799937Y0347340
X0829381Y0348036
X0839573Y0325327
X0857928Y0400184
X0862566Y0404867
X0862522Y0400229
X0857973Y0404867
X0858586Y0385000
X0854086Y0385000
X0854622Y0359004
X0864920Y0343168
X0862020Y0410899
X0866128Y0417532
X0810406Y0448214
X0824650Y0450034
X0810453Y0453330
X0810749Y0443045
X0824650Y0455034
X0833269Y0506683
X0802136Y0448334
X0842476Y0482382
X0842916Y0467009
X0820810Y0473743
X0823544Y0472561
X0823544Y0475061
X0810756Y0473571
X0810756Y0476071
X0861468Y0487303
X0814828Y0472053
X0817380Y0468806
X0814580Y0468806
X0810756Y0468571
X0810756Y0471071
X0820810Y0471243
X0817328Y0472053
X0850748Y0465382
X0818840Y0456060
X0815840Y0456060
X0842515Y0461382
X0842779Y0473076
X0850732Y0469382
X0854882Y0461791
X0862882Y0461791
X0854882Y0458991
X0862882Y0458991
X0858169Y0495032
X0831378Y0430486
X0831378Y0435686
X0831378Y0433086
X0825103Y0432958
X0825103Y0435558
X0825103Y0430358
X0784804Y0425371
X0784902Y0428653
X0844227Y0479882
X0861468Y0483303
X0834215Y0484138
X0833918Y0480580
X0831057Y0484036
X0831418Y0480580
X0828918Y0480580
X0833293Y0487836
X0833293Y0490636
X0794173Y0450510
X0813456Y0441474
X0816177Y0441442
X0815840Y0444091
X0818840Y0444091
X0778079Y0484879
X0778079Y0470706
X0778079Y0511439
X0778079Y0514839
X0788481Y0521952
X0788481Y0518552
X0778079Y0481479
X0788481Y0474418
X0788481Y0491991
X0788481Y0488591
X0778079Y0467306
X0788481Y0477818
X0850909Y0482382
X0822418Y0482570
X0822418Y0485070
X0813864Y0486870
X0810756Y0486118
X0816364Y0486870
X0810756Y0483618
X0790977Y0473640
X0785985Y0473640
X0790977Y0478596
X0785985Y0478596
X0780575Y0485657
X0775583Y0485657
X0775583Y0480701
X0780575Y0480701
X0850832Y0473382
X0850738Y0477382
X0775583Y0471484
X0780575Y0466528
X0775584Y0466528
X0780575Y0471484
X0779029Y0450510
X0778881Y0446510
X0778985Y0442498
X0823529Y0467189
X0826262Y0459326
X0826262Y0462326
X0850733Y0461382
X0854882Y0468791
X0854882Y0465991
X0862882Y0465991
X0862882Y0468791
X0775583Y0510661
X0780575Y0515617
X0775583Y0515617
X0780575Y0510661
X0785985Y0517774
X0790977Y0517774
X0790977Y0492769
X0785985Y0492769
X0790977Y0487813
X0785985Y0487813
X0810756Y0488618
X0810756Y0491118
X0818973Y0488758
X0818973Y0491258
X0861468Y0491303
X0822040Y0444091
X0804536Y0441486
X0824650Y0446740
X0833185Y0448309
X0833185Y0452309
X0833185Y0456309
X0802136Y0452334
X0781429Y0545017
X0827291Y0533100
X0828272Y0535462
X0834282Y0536085
X0833953Y0530621
X0867093Y0574703
X0867093Y0586828
X0866938Y0549771
X0867093Y0554703
X0777708Y0553287
X0775746Y0539315
X0788481Y0611111
X0778079Y0564879
X0788481Y0582765
X0778079Y0561479
X0778079Y0603999
X0788481Y0586165
X0788481Y0568591
X0778079Y0579052
X0778079Y0525613
X0788481Y0596938
X0788481Y0600338
X0778079Y0607399
X0788481Y0571991
X0778079Y0593225
X0778079Y0589825
X0788481Y0614511
X0778079Y0529013
X0788481Y0536125
X0788481Y0532725
X0778079Y0575652
X0775583Y0565657
X0775583Y0560701
X0780575Y0565657
X0780575Y0560701
X0775583Y0529791
X0775583Y0524835
X0780575Y0529791
X0780575Y0524835
X0780575Y0608177
X0775583Y0608177
X0780575Y0603221
X0775583Y0603221
X0775583Y0594003
X0780575Y0594003
X0780575Y0589047
X0775583Y0589047
X0780575Y0574874
X0775583Y0574874
X0780575Y0579830
X0775583Y0579830
X0785985Y0567813
X0790977Y0572769
X0785985Y0572769
X0790977Y0536903
X0790977Y0531947
X0785985Y0536903
X0785985Y0531947
X0785985Y0522730
X0790977Y0522730
X0785985Y0610333
X0785985Y0615289
X0790977Y0610333
X0790977Y0615289
X0790977Y0596160
X0785985Y0596160
X0785985Y0601116
X0790977Y0601116
X0785985Y0586943
X0785985Y0581987
X0790977Y0586943
X0790977Y0581987
X0790977Y0567813
X0784665Y0564843
X0835236Y0533174
X0867093Y0582828
X0867093Y0570703
X0867093Y0578703
X0867093Y0566703
X0867093Y0562703
X0867093Y0558703
X0796000Y0553101
X0823670Y0710542
X0859441Y0678015
X0823890Y0703415
X0838152Y0700215
X0864029Y0688970
X0829496Y0676793
X0858002Y0707244
X0867455Y0710611
X0853989Y0632953
X0853989Y0630453
X0855300Y0646819
X0861663Y0646653
X0842640Y0662814
X0842352Y0659243
X0839636Y0666533
X0837272Y0663910
X0848444Y0657756
X0853982Y0657506
X0855646Y0692710
X0835987Y0713745
X0836078Y0709619
X0845784Y0708089
X0845850Y0710969
X0845784Y0716589
X0845784Y0705489
X0829784Y0705489
X0829784Y0716589
X0868919Y0700894
X0858186Y0701170
X0849680Y0694789
X0778205Y0622912
X0836503Y0667845
X0830318Y0674164
X0845729Y0661263
X0851111Y0656635
X0858202Y0646330
X0853900Y0627700
X0829784Y0713939
X0823790Y0713375
X0845784Y0713939
X0855646Y0685230
X0856145Y0677887
X0867227Y0722060
X0858186Y0713170
X0778860Y0626912
X0813548Y0814000
X0859000Y0760000
X0859000Y0764000
X0859000Y0778000
X0859000Y0781000
X0859000Y0796000
X0859000Y0800000
X0859000Y0814000
X0859000Y0818000
X0857986Y0722670
X0836713Y0738751
X0830484Y0738750
X0813635Y0762000
X0854484Y0738633
X0846484Y0738750
X0813000Y0805000
X0819788Y0739634
X0817365Y0756827
X0859199Y0744517
X0827500Y0750000
X0846000Y0772079
X0842661Y0769521
X0817584Y0764219
X0824500Y0800500
X0824500Y0782500
X0824500Y0756000
X0818500Y0810135
X0824500Y0774000
X0817845Y0817879
X0824342Y0792315
X0849500Y0817500
X0849500Y0812500
X0859000Y0810000
X0867000Y0774000
X0861425Y0788500
X0867000Y0792000
X0861425Y0806500
X0863443Y0753254
X0861425Y0770500
X0867000Y0810000
X0813653Y0746856
X0813678Y0740979
X0813902Y0730738
X0849500Y0763500
X0849500Y0758500
X0859000Y0756000
X0849500Y0781500
X0849500Y0776500
X0821582Y0727140
X0859000Y0774000
X0849500Y0799500
X0849500Y0794500
X0818307Y0724144
X0859000Y0792000
X0824387Y0726246
X0822151Y0752283
X0857632Y0789385
X0853282Y0789887
X0824500Y0814500
X0830075Y0805000
X0824500Y0796500
X0830075Y0787000
X0818000Y0797000
X0824500Y0778500
X0830075Y0769000
X0824500Y0760500
X0813009Y0819734
X0854484Y0746701
X0838484Y0746701
X0826484Y0747127
X0817500Y0760000
X0820500Y0777500
X0820500Y0792000
X0826925Y0769000
X0826925Y0787000
X0849500Y0797000
X0849500Y0779000
X0849500Y0761000
X0864575Y0770500
X0841500Y0758161
X0864575Y0788500
X0841500Y0776161
X0864575Y0806500
X0841500Y0794161
X0826925Y0805000
X0819890Y0736924
X0815492Y0732917
X0813566Y0744187
X0820432Y0800529
X0820547Y0780314
X0819993Y0754109
X0830484Y0746701
X0832284Y0731216
X0823843Y0732109
X0818500Y0814000
X0812661Y0810032
X0849500Y0815000
X0841500Y0812161
X0846484Y0746701
X0848284Y0731181
X0814080Y0864464
X0834465Y0884538
X0812575Y0880834
X0812219Y0883586
X0849600Y0918028
X0858988Y0898307
X0822608Y0848526
X0851184Y0879459
X0850800Y0883500
X0848384Y0875459
X0848384Y0871459
X0848739Y0847459
X0824804Y0898395
X0833327Y0855560
X0848224Y0823502
X0838194Y0836962
X0812440Y0862306
X0848384Y0835459
X0829946Y0829788
X0848384Y0839459
X0822938Y0863298
X0823900Y0882083
X0816037Y0845578
X0819918Y0889365
X0829757Y0842672
X0815863Y0830097
X0831583Y0853454
X0851184Y0843459
X0836894Y0824401
X0831654Y0864494
X0830014Y0833046
X0818031Y0907747
X0848384Y0879459
X0848200Y0883400
X0835553Y0835119
X0837434Y0851459
X0836909Y0914018
X0836909Y0916618
X0851239Y0847459
X0837276Y0883459
X0859461Y0859459
X0843574Y0859423
X0848384Y0851459
X0850900Y0888359
X0859614Y0887846
X0845964Y0887490
X0859614Y0883800
X0845633Y0883492
X0859165Y0848728
X0846239Y0847490
X0859603Y0863570
X0845820Y0863413
X0847098Y0891213
X0848384Y0843459
X0846336Y0855459
X0848384Y0863459
X0836066Y0894955
X0830063Y0898500
X0817139Y0890330
X0859463Y0866125
X0845820Y0867413
X0848792Y0896472
X0851184Y0851459
X0862114Y0859479
X0839530Y0859408
X0848384Y0867459
X0859234Y0879600
X0845876Y0879459
X0851184Y0835459
X0847138Y0859459
X0813887Y0835146
X0814299Y0840877
X0836839Y0831301
X0851184Y0875459
X0851184Y0871459
X0861425Y0824500
X0848322Y0888421
X0849267Y0892567
X0843315Y0916612
X0841274Y0914060
X0831057Y0916745
X0829848Y0914211
X0825336Y0916774
X0815500Y0824000
X0817884Y0915425
X0855524Y0898505
X0851184Y0867459
X0851184Y0863459
X0827992Y0874107
X0833194Y0873561
X0835346Y0891346
X0835215Y0847719
X0823540Y0857956
X0822916Y0852576
X0851184Y0839459
X0836999Y0867413
X0838189Y0847490
X0840234Y0851459
X0837183Y0855459
X0830075Y0823000
X0850496Y0831469
X0840136Y0830903
X0817152Y0896380
X0826070Y0893014
X0823234Y0870830
X0826209Y0866052
X0825721Y0839816
X0838189Y0843459
X0835626Y0843629
X0842827Y0895443
X0837290Y0887490
X0840234Y0875459
X0837396Y0871459
X0837383Y0879530
X0856628Y0918042
X0864253Y0918042
X0851782Y0823720
X0829000Y0852000
X0812980Y0824166
X0812811Y0908162
X0814731Y0889365
X0813182Y0852800
X0816016Y0838036
X0825508Y0913869
X0822462Y0915095
X0825774Y0895553
X0826797Y0883756
X0823234Y0867680
X0825686Y0869496
X0819134Y0863607
X0826165Y0863000
X0825721Y0836666
X0826925Y0823000
X0838685Y0832987
X0829791Y0839020
X0839381Y0915839
X0849600Y0915266
X0833870Y0881860
X0845654Y0895437
X0864253Y0915242
X0856628Y0915242
X0851161Y0855205
X0864575Y0824500
X0864464Y0828503
X0865004Y0831273
X0816519Y0931147
X0849205Y0924129
X0834751Y0922368
X0824414Y0939655
X0829617Y0939583
X0848070Y1022190
X0848045Y1019310
X0853030Y0934690
X0858601Y0934505
X0842856Y0949146
X0835431Y0977775
X0828964Y0977780
X0863334Y1009393
X0851925Y0951350
X0865830Y0961600
X0844058Y1011738
X0836243Y0939579
X0833683Y0939579
X0853449Y1007048
X0850686Y1006923
X0836243Y0949105
X0867096Y0935963
X0833683Y0949105
X0788600Y1006923
X0823552Y0930700
X0841329Y0926602
X0824168Y0949538
X0832423Y0964669
X0865973Y0978187
X0866906Y1018751
X0863956Y1020763
X0861047Y1018909
X0840935Y1011499
X0836423Y0964669
X0825670Y0964671
X0848520Y1016855
X0832711Y0993268
X0832432Y0977982
X0828423Y0964731
X0828193Y0949324
X0818347Y0939610
X0843734Y1008778
X0839122Y0939655
X0852247Y1009529
X0849088Y0951081
X0855867Y0935540
X0867199Y0949372
X0868908Y0933640
X0827856Y1116251
X0830356Y1116251
X0867476Y1110175
X0867475Y1107647
X0789050Y1026150
X0795631Y1025440
X0803673Y1025440
X0867457Y1089104
X0867457Y1091604
X0868624Y1074104
X0868624Y1071604
X0863689Y1024974
X0866887Y1026762
X0866887Y1023208
X0860887Y1026762
X0860887Y1023208
X0799631Y1025440
X0849996Y1091073
X0850023Y1095179
X0791686Y1025440
X0828385Y1120599
X0860842Y1120636
X0858142Y1120636
X0855542Y1120636
X0863342Y1120636
X0792382Y1191664
X0804458Y1193112
X0798542Y1188345
X0798353Y1172011
X0793842Y1143384
X0823489Y1200969
X0819026Y1128137
X0819449Y1134534
X0811507Y1157544
X0817964Y1157404
X0823516Y1185238
X0805519Y1187215
X0794533Y1195766
X0804452Y1199814
X0815037Y1167768
X0810018Y1167768
X0823309Y1180235
X0805212Y1180175
X0818879Y1187310
X0814170Y1185205
X0797160Y1146609
X0799020Y1175975
X0792277Y1173065
X0809632Y1142666
X0819489Y1201039
X0807020Y1217900
X0806835Y1134729
X0814835Y1134729
X0807489Y1201043
X0811485Y1201043
X0809027Y1219895
X0815455Y1201043
X0796338Y1138130
X0868022Y1148080
X0868664Y1139336
X0823608Y1208993
X0814160Y1178240
X0823220Y1170767
X0787887Y1174500
X0803453Y1134729
X0825335Y1137129
X0825744Y1150087
X0806787Y1148000
X0794716Y1186071
X0863619Y1148080
X0861119Y1148080
X0809393Y1187252
X0817446Y1210089
X0811487Y1193019
X0815487Y1193019
X0807487Y1193019
X0809623Y1160168
X0815034Y1159455
X0809682Y1133284
X0821816Y1214458
X0819522Y1212164
X0826612Y1219254
X0819487Y1193019
X0823487Y1193019
X0823220Y1162817
X0825744Y1146937
X0822006Y1130208
X0817006Y1133027
X0863442Y1139336
X0860942Y1139336
X0860942Y1130336
X0855642Y1130336
X0858242Y1130336
X0863442Y1130336
X0815149Y1226016
X0817360Y1228226
X0812302Y1223170
X0819419Y1230265
X0780162Y1412848
X0793548Y1397690
X0778685Y1416198
X0810204Y1401661
X0806148Y1375208
X0806148Y1383715
X0783694Y1410977
X0804654Y1404769
X0792848Y1414718
X0795296Y1416995
X0788648Y1422044
X0776568Y1360099
X0773168Y1360099
X0773168Y1348187
X0776568Y1348187
X0810148Y1374884
X0816648Y1380758
X0794983Y1331230
X0794983Y1334030
X0800627Y1392748
X0789383Y1331230
X0789383Y1334030
X0792183Y1331230
X0792183Y1334030
X0816648Y1377608
X0806318Y1401661
X0772390Y1345691
X0777346Y1345691
X0777346Y1350683
X0772390Y1350683
X0777346Y1362595
X0777346Y1357603
X0772390Y1362595
X0772390Y1357603
X0794506Y1411307
X0805569Y1441519
X0804919Y1489247
X0812104Y1426483
X0797318Y1471242
X0802684Y1465549
X0790989Y1455695
X0850644Y1457359
X0826341Y1451236
X0834475Y1460059
X0799057Y1449158
X0801057Y1447158
X0803057Y1449158
X0786591Y1452803
X0845306Y1438269
X0793994Y1441499
X0787038Y1460533
X0790754Y1441399
X0850544Y1447559
X0783620Y1460108
X0853514Y1457510
X0826204Y1440689
X0826204Y1444689
X0790361Y1447895
X0826219Y1455244
X0836744Y1444849
X0777260Y1446237
X0790296Y1463459
X0839744Y1461959
X0798601Y1431673
X0800607Y1440760
X0846044Y1451459
X0836704Y1440849
X0835474Y1457397
X0777725Y1450193
X0826365Y1458974
X0807576Y1469584
X0836704Y1448849
X0794005Y1464178
X0787694Y1442749
X0785820Y1425993
X0789647Y1427518
X0793459Y1429165
X0786787Y1433800
X0783469Y1424655
X0801354Y1478681
X0839744Y1457959
X0837685Y1453196
X0846844Y1454334
X0778428Y1455156
X0839744Y1448959
X0839744Y1440859
X0839744Y1444959
X0793744Y1437159
X0801057Y1458016
X0799057Y1456016
X0803057Y1456016
X0793288Y1450918
X0777749Y1439432
X0777749Y1435432
X0777749Y1431432
X0867644Y1476759
X0861644Y1476759
X0864644Y1476759
X0858644Y1476759
X0855644Y1476759
X0867644Y1473759
X0861644Y1473759
X0864644Y1473759
X0858644Y1473759
X0855644Y1473759
X0858644Y1464759
X0855644Y1464759
X0855644Y1467759
X0861644Y1470759
X0861644Y1467759
X0867644Y1470759
X0864644Y1470759
X0867644Y1467759
X0864644Y1467759
X0861644Y1464759
X0867644Y1464759
X0864644Y1464759
X0858644Y1470759
X0855644Y1470759
X0858644Y1467759
X0815096Y1470387
X0815096Y1476587
X0815096Y1479587
X0815096Y1473387
X0812096Y1476587
X0812096Y1479587
X0824096Y1470387
X0824096Y1467387
X0821096Y1467387
X0821096Y1470387
X0818096Y1470387
X0815096Y1467387
X0818096Y1467387
X0812009Y1470432
X0824096Y1476587
X0821096Y1476587
X0818096Y1476587
X0812009Y1473432
X0824096Y1479587
X0821096Y1479587
X0818096Y1479587
X0824096Y1473387
X0821096Y1473387
X0818096Y1473387
X0821096Y1464387
X0815096Y1464387
X0818096Y1464387
X0864671Y1457719
X0859071Y1457719
X0859071Y1452589
X0864671Y1447459
X0859071Y1447459
X0812474Y1457717
X0817974Y1457717
X0806874Y1457717
X0812474Y1447457
X0817974Y1452587
X0817974Y1447457
X0806874Y1452587
X0806874Y1447457
X0797083Y1467883
X0799314Y1475693
X0771557Y1446818
X0810059Y1432778
X0815901Y1432804
X0812901Y1432804
X0821986Y1438785
X0810001Y1435504
X0815901Y1435504
X0812901Y1435504
X0815986Y1441485
X0812986Y1441485
X0809986Y1441485
X0815986Y1438785
X0818986Y1438785
X0812986Y1438785
X0818986Y1441485
X0821986Y1441485
X0809986Y1438785
X0818901Y1432804
X0821901Y1432804
X0818901Y1435504
X0821901Y1435504
X0827901Y1435504
X0824901Y1435504
X0830901Y1432804
X0827901Y1432804
X0824901Y1432804
X0824901Y1430104
X0827901Y1430104
X0830901Y1430104
X0821901Y1430104
X0818901Y1430104
X0821901Y1427404
X0827901Y1427404
X0824901Y1427404
X0857944Y1432359
X0866944Y1426359
X0866944Y1429359
X0866944Y1432359
X0863944Y1426359
X0857944Y1426359
X0860944Y1426359
X0860944Y1429359
X0857944Y1429359
X0860944Y1432359
X0863944Y1429359
X0863944Y1432359
X0860944Y1438359
X0857944Y1438359
X0857944Y1441359
X0860944Y1435359
X0857944Y1435359
X0866944Y1438359
X0866944Y1441359
X0860944Y1441359
X0863944Y1438359
X0863944Y1441359
X0866944Y1435359
X0863944Y1435359
X0793723Y1468071
X0832084Y1461072
X0800703Y1426779
X0777114Y1442270
X0784046Y1600438
X0777059Y1608982
X0781110Y1595254
X0781124Y1583553
X0771383Y1616917
X0778045Y1619395
X0782289Y1620109
X0791610Y1593708
X0774658Y1601012
X0781545Y1602835
X0777033Y1595215
X0787447Y1593586
X0778358Y1627418
X0773822Y1627418
X0778045Y1622545
X0772000Y1644980
X0793564Y1642682
X0811457Y1639797
X0831457Y1639797
X0851457Y1639797
X0871457Y1639797
X0891457Y1639797
X0911457Y1639797
X0931457Y1639797
X0951457Y1639797
X0947094Y1542353
X0947094Y1545353
X0944094Y1545353
X0941094Y1545353
X0944094Y1542353
X0941094Y1542353
X0929094Y1545353
X0929094Y1542353
X0950035Y1542333
X0953035Y1542333
X0956035Y1542333
X0959035Y1542333
X0926044Y1542370
X0938094Y1545353
X0938094Y1542353
X0932094Y1545353
X0935094Y1545353
X0932094Y1542353
X0935094Y1542353
X0950035Y1545333
X0926041Y1560503
X0926041Y1557503
X0953035Y1545333
X0926041Y1548503
X0926041Y1551503
X0926041Y1554503
X0926044Y1545370
X0959035Y1545333
X0956035Y1545333
X0937671Y1488139
X0930441Y1461039
X0930441Y1464039
X0930441Y1467039
X0930441Y1458039
X0930441Y1455039
X0952676Y1467039
X0952676Y1455039
X0952676Y1458039
X0952676Y1464039
X0952676Y1461039
X0937671Y1492139
X0956238Y1469902
X0956238Y1467139
X0956238Y1464139
X0956238Y1461139
X0956238Y1458139
X0956238Y1455139
X0952695Y1444139
X0893919Y1462132
X0919285Y1456226
X0889244Y1468859
X0925435Y1478114
X0892244Y1440859
X0889336Y1452554
X0892244Y1449636
X0895244Y1457510
X0889244Y1444859
X0921498Y1446692
X0878244Y1451605
X0920244Y1451605
X0875744Y1453573
X0881244Y1476859
X0881244Y1456859
X0917744Y1453573
X0924803Y1474743
X0889244Y1472859
X0925697Y1460109
X0889244Y1460859
X0889944Y1457959
X0881244Y1453059
X0881244Y1464859
X0881244Y1440859
X0881244Y1448859
X0968540Y1514693
X0914370Y1470583
X0911370Y1470583
X0914370Y1467583
X0911370Y1467583
X0911370Y1473583
X0914370Y1473583
X0911370Y1476583
X0914370Y1476583
X0914370Y1464583
X0911370Y1464583
X0899370Y1467583
X0905370Y1470583
X0905370Y1467583
X0908370Y1470583
X0908370Y1467583
X0902370Y1470583
X0899370Y1470583
X0902370Y1467583
X0899370Y1473583
X0902370Y1473583
X0908370Y1473583
X0905370Y1473583
X0899370Y1476583
X0902370Y1476583
X0908370Y1476583
X0905370Y1476583
X0902370Y1464583
X0899370Y1464583
X0905370Y1464583
X0908370Y1464583
X0870644Y1476759
X0870644Y1473759
X0901071Y1447459
X0906671Y1447459
X0912171Y1447459
X0901071Y1452589
X0901071Y1457719
X0906671Y1457719
X0912171Y1452589
X0912171Y1457719
X0870644Y1470759
X0870644Y1467759
X0870644Y1464759
X0870171Y1457719
X0870171Y1452589
X0870171Y1447459
X0942770Y1507928
X0945370Y1507928
X0946470Y1505328
X0943870Y1505328
X0943870Y1510528
X0946470Y1510528
X0940170Y1507928
X0938670Y1505328
X0941270Y1505328
X0941270Y1510528
X0938670Y1510528
X0966883Y1439997
X0966883Y1436997
X0960883Y1439997
X0963883Y1439997
X0960883Y1436997
X0963883Y1436997
X0966883Y1433997
X0960883Y1433997
X0963883Y1433997
X0960883Y1430997
X0966883Y1427997
X0966883Y1430997
X0960883Y1427997
X0963883Y1427997
X0963883Y1430997
X0937725Y1430744
X0937725Y1427744
X0934725Y1427744
X0940725Y1430744
X0940725Y1427744
X0937725Y1436744
X0934725Y1436744
X0937725Y1439744
X0934725Y1439744
X0934725Y1430744
X0937725Y1433744
X0934725Y1433744
X0940725Y1436744
X0940725Y1439744
X0940725Y1433744
X0943725Y1427744
X0949725Y1436744
X0946725Y1436744
X0943725Y1436744
X0949725Y1439744
X0946725Y1439744
X0943725Y1439744
X0949725Y1433744
X0949725Y1427744
X0949725Y1430744
X0946725Y1430744
X0946725Y1427744
X0943725Y1430744
X0946725Y1433744
X0943725Y1433744
X0905944Y1435359
X0905944Y1432359
X0905944Y1429359
X0902944Y1432359
X0899944Y1429359
X0902944Y1429359
X0902944Y1426359
X0899944Y1426359
X0905944Y1426359
X0911944Y1435359
X0914944Y1435359
X0911944Y1432359
X0914944Y1432359
X0911944Y1429359
X0914944Y1429359
X0914944Y1426359
X0911944Y1426359
X0908944Y1435359
X0908944Y1432359
X0908944Y1429359
X0908944Y1426359
X0905944Y1441359
X0905944Y1438359
X0902944Y1441359
X0911944Y1441359
X0914944Y1441359
X0911944Y1438359
X0914944Y1438359
X0908944Y1441359
X0908944Y1438359
X0899944Y1435359
X0902944Y1435359
X0899944Y1432359
X0899944Y1441359
X0899944Y1438359
X0902944Y1438359
X0869944Y1426359
X0869944Y1429359
X0869944Y1432359
X0869944Y1438359
X0869944Y1441359
X0869944Y1435359
X0872944Y1426359
X0872944Y1429359
X0872944Y1432359
X0872944Y1438359
X0872944Y1441359
X0872944Y1435359
X0904177Y1359955
X0952385Y1375591
X0949385Y1375591
X0931159Y1383227
X0931159Y1406027
X0931159Y1390827
X0931159Y1398427
X0949469Y1379528
X0952417Y1379528
X0944235Y1406262
X0952561Y1383465
X0939559Y1402227
X0931199Y1371951
X0931159Y1387027
X0931159Y1394627
X0948235Y1406262
X0952716Y1387402
X0939559Y1398427
X0931137Y1375878
X0920255Y1383264
X0952395Y1395276
X0920360Y1387039
X0952514Y1391339
X0931159Y1379427
X0931159Y1402227
X0911135Y1345560
X0914033Y1345613
X0947308Y1325035
X0927193Y1361547
X0924650Y1324419
X0924650Y1327819
X0950239Y1409555
X0952180Y1407087
X0951832Y1371654
X0948832Y1371654
X0949070Y1367717
X0952070Y1367717
X0927146Y1323641
X0927146Y1328597
X0872600Y1298333
X0872600Y1300833
X0944207Y1320739
X0899699Y1283872
X0908700Y1316300
X0930754Y1310564
X0909077Y1232724
X0889729Y1295516
X0887342Y1314990
X0902908Y1299828
X0906506Y1299188
X0943891Y1306608
X0905740Y1309264
X0902875Y1309301
X0911117Y1314130
X0948259Y1295965
X0886926Y1298712
X0910788Y1299456
X0961146Y1225259
X0906309Y1226647
X0897169Y1225259
X0910633Y1222799
X0891107Y1314305
X0891888Y1260558
X0886888Y1260558
X0889388Y1260558
X0891888Y1263058
X0889388Y1263058
X0886888Y1263058
X0955865Y1260558
X0950865Y1260558
X0953365Y1260558
X0955865Y1263058
X0953365Y1263058
X0950865Y1263058
X0875700Y1299700
X0949970Y1321749
X0883142Y1259935
X0872440Y1250783
X0872440Y1248283
X0872440Y1241383
X0872440Y1243883
X0878004Y1224406
X0872440Y1236983
X0872440Y1234483
X0874624Y1224514
X0871624Y1224514
X0872440Y1227583
X0872440Y1230083
X0890738Y1311132
X0891003Y1292765
X0894887Y1227209
X0904703Y1297398
X0901940Y1239299
X0901940Y1243699
X0901940Y1246199
X0901940Y1232399
X0901940Y1229899
X0901940Y1236799
X0940848Y1310181
X0933254Y1308273
X0947119Y1259935
X0936417Y1250783
X0936417Y1248283
X0936417Y1241383
X0936417Y1243883
X0941981Y1224406
X0938601Y1224514
X0935601Y1224514
X0936417Y1227583
X0936417Y1230083
X0936417Y1236983
X0936417Y1234483
X0958864Y1227209
X0965917Y1239299
X0965917Y1243699
X0965917Y1246199
X0965917Y1232399
X0965917Y1229899
X0965917Y1236799
X0959524Y1145169
X0935341Y1139336
X0932000Y1147708
X0934500Y1147708
X0962024Y1145169
X0962255Y1136426
X0959252Y1132870
X0956552Y1132870
X0935341Y1130336
X0932641Y1139336
X0943241Y1130336
X0940541Y1130336
X0937941Y1130336
X0958226Y1123803
X0955526Y1123803
X0952926Y1123803
X0950326Y1123803
X0913784Y1221057
X0870522Y1148080
X0898047Y1145169
X0895547Y1145169
X0898278Y1136426
X0892575Y1132870
X0895275Y1132870
X0871364Y1130336
X0873964Y1130336
X0876564Y1130336
X0879264Y1130336
X0871364Y1139336
X0894249Y1123803
X0891549Y1123803
X0888949Y1123803
X0886349Y1123803
X0956509Y1220112
X0962855Y1214182
X0967936Y1207823
X0963263Y1219469
X0958690Y1210419
X0939298Y1207654
X0903959Y1207823
X0906784Y1216607
X0875321Y1207654
X0914637Y1214838
X0892532Y1220112
X0899286Y1219469
X0898878Y1214182
X0894713Y1210419
X0966374Y1145169
X0968874Y1145169
X0927597Y1147708
X0925097Y1147708
X0902397Y1145169
X0904897Y1145169
X0874624Y1216114
X0874624Y1218914
X0874624Y1221714
X0871624Y1216114
X0871624Y1218914
X0871624Y1221714
X0874624Y1213314
X0871624Y1213314
X0893328Y1212887
X0893190Y1208069
X0888650Y1199622
X0904063Y1135946
X0903908Y1132870
X0901428Y1136426
X0911641Y1126328
X0909041Y1126328
X0911699Y1129488
X0908371Y1123803
X0903171Y1123803
X0905771Y1123803
X0911071Y1123803
X0914637Y1210568
X0927419Y1139336
X0924919Y1139336
X0927619Y1130336
X0924919Y1130336
X0914241Y1126328
X0914299Y1129488
X0914661Y1132612
X0938601Y1213314
X0938601Y1216114
X0938601Y1218914
X0938601Y1221714
X0935601Y1213314
X0935601Y1216114
X0935601Y1218914
X0935601Y1221714
X0952627Y1199622
X0957167Y1208069
X0957305Y1212887
X0967885Y1132870
X0965405Y1136426
X0967148Y1123803
X0916749Y1092664
X0916749Y1104659
X0916875Y1098643
X0908422Y1023103
X0908278Y1083484
X0966330Y1104333
X0902353Y1104333
X0951839Y1088067
X0957981Y1081231
X0908799Y1100659
X0894004Y1081231
X0908799Y1088659
X0908799Y1093659
X0887862Y1088067
X0966366Y1081764
X0952926Y1114103
X0958226Y1114103
X0955526Y1114103
X0950326Y1114103
X0935341Y1120636
X0937941Y1120636
X0940541Y1120636
X0943241Y1120636
X0902389Y1081764
X0886349Y1114103
X0888949Y1114103
X0891549Y1114103
X0894249Y1114103
X0870076Y1110175
X0872676Y1110175
X0875376Y1110175
X0879264Y1120636
X0876564Y1120636
X0873964Y1120636
X0871364Y1120636
X0870075Y1107647
X0872675Y1107647
X0875375Y1107647
X0946756Y1074104
X0946756Y1071604
X0951956Y1074104
X0949356Y1074104
X0954556Y1074104
X0954556Y1071604
X0949356Y1071604
X0951956Y1071604
X0946592Y1084666
X0937489Y1071682
X0934889Y1071682
X0940089Y1071682
X0940089Y1074182
X0934889Y1074182
X0937489Y1074182
X0932289Y1071682
X0932289Y1074182
X0936828Y1088909
X0934228Y1088909
X0939428Y1088909
X0939428Y1091409
X0934228Y1091409
X0936828Y1091409
X0931628Y1088909
X0931628Y1091409
X0944092Y1084666
X0927861Y1024768
X0924864Y1023208
X0924864Y1026762
X0930864Y1023208
X0939864Y1023208
X0942864Y1026762
X0936864Y1026762
X0930864Y1026762
X0945864Y1023208
X0934911Y1023579
X0959371Y1026985
X0957864Y1023208
X0951864Y1023208
X0954864Y1026762
X0948864Y1026762
X0963864Y1023208
X0963864Y1026762
X0882615Y1084666
X0872657Y1091604
X0880115Y1084666
X0872657Y1089104
X0870057Y1089104
X0875257Y1089104
X0875257Y1091604
X0870057Y1091604
X0887979Y1071604
X0885379Y1071604
X0890579Y1071604
X0890579Y1074104
X0885379Y1074104
X0887979Y1074104
X0882779Y1071604
X0882779Y1074104
X0873824Y1074104
X0871224Y1074104
X0876424Y1074104
X0876424Y1071604
X0871224Y1071604
X0873824Y1071604
X0899887Y1026762
X0899887Y1023208
X0884887Y1026762
X0890887Y1026762
X0887887Y1023208
X0893887Y1023208
X0895394Y1026985
X0869741Y1025895
X0881887Y1023208
X0872887Y1026762
X0878887Y1026762
X0875887Y1023208
X0878927Y1022387
X0871069Y1023114
X0956833Y1102760
X0908799Y1096659
X0892856Y1102760
X0916992Y1076659
X0916749Y1084659
X0901366Y1078069
X0897815Y1078042
X0884890Y1098724
X0884906Y1102760
X0897056Y1095984
X0891055Y1095407
X0897056Y1091391
X0905671Y1114103
X0903071Y1114103
X0908271Y1114103
X0910971Y1114103
X0901694Y1095940
X0901739Y1091346
X0924898Y1120636
X0917110Y1101902
X0916749Y1088659
X0916749Y1080659
X0927598Y1120636
X0961033Y1095984
X0955032Y1095407
X0948867Y1098724
X0948883Y1102760
X0961033Y1091391
X0967048Y1114103
X0965671Y1095940
X0965716Y1091346
X0891367Y0941126
X0962329Y0936229
X0957235Y0936398
X0929741Y0967006
X0945671Y0982191
X0870209Y0949384
X0900983Y0940895
X0949671Y0977921
X0965671Y0982191
X0953671Y0982191
X0957671Y0977921
X0951863Y0936168
X0878976Y0994020
X0891343Y0994378
X0909166Y0994188
X0921364Y0951251
X0949671Y0991564
X0897825Y0994413
X0912690Y0994350
X0872183Y0993980
X0926796Y0966297
X0928227Y0951125
X0923289Y0965780
X0909811Y0962400
X0935255Y0962725
X0882763Y0933472
X0913005Y0969605
X0874066Y0977928
X0918265Y0969745
X0914193Y0945318
X0946363Y0951179
X0940716Y0951733
X0958567Y0927654
X0964280Y0927777
X0894660Y0994330
X0888400Y0994579
X0875391Y0993796
X0936371Y0951484
X0908856Y1017677
X0872126Y0934766
X0924956Y0994321
X0916932Y0994405
X0925024Y1018909
X0948975Y1021325
X0943093Y1021769
X0942760Y1018751
X0936822Y1018988
X0930883Y1018751
X0960636Y1021917
X0961208Y1018592
X0957678Y1018555
X0940015Y1020176
X0954937Y1021998
X0893147Y1020025
X0897717Y1019915
X0888743Y1019931
X0872845Y1018988
X0878783Y1018751
X0885099Y1021685
X0953671Y0991564
X0961671Y0991564
X0965671Y0991564
X0903759Y0951358
X0954567Y0927654
X0968507Y0937615
X0909300Y1014639
X0882609Y0994245
X0869390Y0978003
X0876481Y0941126
X0906909Y0951494
X0906710Y0962433
X0911355Y0944909
X0912628Y0928101
X0909296Y1020224
X0915490Y0969886
X0918648Y0964717
X0924487Y0951244
X0924628Y0928101
X0916628Y0928101
X0928628Y0928101
X0920628Y0928101
X0933810Y0972433
X0940497Y0928101
X0936628Y0928101
X0932628Y0928101
X0944628Y0928101
X0946642Y0991361
X0957671Y0991564
X0961479Y0927643
X0950567Y0927654
X0959545Y0918306
X0925462Y0867338
X0919163Y0867338
X0922313Y0867338
X0925462Y0864189
X0919163Y0864189
X0881370Y0870488
X0884519Y0870488
X0928612Y0864189
X0881370Y0886236
X0937200Y0841000
X0925462Y0845293
X0942194Y0891216
X0938729Y0874396
X0929181Y0895029
X0925462Y0857891
X0871600Y0898584
X0884519Y0879937
X0890818Y0876787
X0900266Y0835844
X0890818Y0848442
X0881370Y0848442
X0919163Y0842143
X0919163Y0838994
X0919163Y0835844
X0916014Y0845293
X0906565Y0845293
X0909714Y0851592
X0885126Y0889742
X0887669Y0842143
X0881370Y0851592
X0884519Y0842143
X0956239Y0829577
X0878220Y0835844
X0881370Y0845293
X0878220Y0845293
X0878220Y0848442
X0893967Y0851591
X0890818Y0851592
X0888628Y0918042
X0922313Y0842143
X0932628Y0918042
X0932300Y0890200
X0887669Y0857891
X0884519Y0845293
X0908628Y0915242
X0893968Y0848442
X0941592Y0900908
X0904838Y0918042
X0890818Y0845293
X0887669Y0845293
X0884519Y0857891
X0893968Y0835846
X0955712Y0833988
X0884585Y0886354
X0893968Y0879937
X0888628Y0915242
X0892628Y0915242
X0896553Y0918042
X0912628Y0918042
X0900628Y0915242
X0890818Y0842143
X0908628Y0918042
X0893968Y0838994
X0893968Y0876787
X0897118Y0845293
X0928612Y0883086
X0919163Y0876787
X0957900Y0856300
X0961175Y0838525
X0919163Y0845293
X0900267Y0842143
X0886093Y0835318
X0900267Y0845293
X0922313Y0857891
X0922313Y0864189
X0906565Y0842143
X0916014Y0842143
X0955850Y0862902
X0909714Y0848442
X0912864Y0876787
X0922313Y0870488
X0906565Y0879937
X0887669Y0848442
X0909714Y0879937
X0919163Y0870488
X0919163Y0873638
X0925462Y0851592
X0937551Y0860801
X0936450Y0858327
X0884519Y0851592
X0932319Y0871626
X0934928Y0871727
X0916014Y0867338
X0916014Y0864189
X0925462Y0883086
X0893968Y0842143
X0929790Y0828603
X0916628Y0915242
X0928628Y0915242
X0920628Y0915242
X0924628Y0915242
X0916014Y0851592
X0932418Y0825135
X0935262Y0825135
X0933054Y0843804
X0933021Y0840893
X0916014Y0848442
X0928628Y0918042
X0895050Y0828548
X0897118Y0842143
X0925462Y0879937
X0919163Y0879937
X0922313Y0879937
X0916014Y0879937
X0928612Y0879937
X0890326Y0828548
X0919163Y0848442
X0949382Y0886737
X0912628Y0915242
X0919163Y0851592
X0945982Y0886737
X0953240Y0876834
X0955343Y0866850
X0936628Y0918042
X0890818Y0873638
X0884519Y0867338
X0924628Y0918042
X0900267Y0838992
X0916628Y0918042
X0932628Y0915242
X0940628Y0915242
X0920628Y0918042
X0876628Y0918042
X0928612Y0876787
X0967337Y0828901
X0887669Y0879937
X0930800Y0904840
X0928612Y0886236
X0881370Y0876787
X0947029Y0915242
X0877800Y0876500
X0880628Y0918042
X0890818Y0879937
X0919163Y0883086
X0881370Y0883086
X0925462Y0876787
X0928612Y0873638
X0884519Y0876787
X0925462Y0886236
X0889178Y0905619
X0884628Y0918042
X0884519Y0854742
X0908920Y0905630
X0922313Y0886236
X0922313Y0883086
X0921451Y0903800
X0912864Y0879937
X0887669Y0873638
X0916014Y0876787
X0887669Y0864189
X0884519Y0873638
X0922313Y0873638
X0916014Y0873638
X0925462Y0870488
X0928612Y0870488
X0922313Y0876787
X0925462Y0873638
X0884519Y0848442
X0967510Y0868971
X0897118Y0879937
X0878220Y0851592
X0893968Y0845293
X0967842Y0864801
X0881370Y0835844
X0936628Y0915242
X0881370Y0867338
X0940100Y0830700
X0922313Y0845293
X0966813Y0904556
X0954700Y0837700
X0907884Y0829866
X0950300Y0877800
X0912864Y0873638
X0906565Y0876787
X0900267Y0876787
X0890818Y0867338
X0916014Y0854742
X0916014Y0857891
X0906565Y0851592
X0900267Y0851592
X0890818Y0857891
X0890818Y0864189
X0897118Y0851592
X0944297Y0839975
X0940716Y0840074
X0935124Y0831382
X0906565Y0838994
X0922313Y0854742
X0954760Y0826734
X0957379Y0826586
X0900267Y0879937
X0876628Y0915242
X0872628Y0918042
X0876475Y0830372
X0877818Y0824214
X0877407Y0828017
X0884628Y0915242
X0900628Y0918042
X0935765Y0878317
X0932770Y0878233
X0960100Y0846665
X0897118Y0848442
X0900267Y0848442
X0906565Y0848442
X0916014Y0870488
X0919163Y0857891
X0919163Y0854742
X0897118Y0876787
X0909714Y0876787
X0887669Y0870488
X0890818Y0870488
X0887669Y0867338
X0887669Y0854742
X0890818Y0854742
X0887669Y0851592
X0887669Y0876787
X0899693Y0895207
X0929611Y0858669
X0933700Y0887508
X0938188Y0900853
X0944839Y0902400
X0953587Y0902814
X0942634Y0886520
X0952738Y0886624
X0953145Y0874240
X0880628Y0915242
X0872628Y0915242
X0893968Y0867338
X0893968Y0873638
X0893968Y0870488
X0893968Y0854742
X0893968Y0857891
X0893968Y0864189
X0904833Y0915340
X0912864Y0867338
X0912864Y0870488
X0912864Y0854742
X0912864Y0857891
X0912864Y0864189
X0912864Y0851592
X0909714Y0838994
X0928612Y0835844
X0946700Y0849200
X0932000Y0831000
X0950291Y0866240
X0950291Y0870240
X0950251Y0874268
X0955967Y0860376
X0953217Y0861440
X0953091Y0857440
X0947735Y0854935
X0954700Y0842700
X0948935Y0835800
X0947735Y0824921
X0968319Y0826191
X0897118Y0854742
X0900267Y0854742
X0900267Y0857891
X0906565Y0854742
X0909714Y0842143
X0909714Y0845293
X0912864Y0842143
X0912864Y0845293
X0912864Y0848442
X0909714Y0867338
X0909714Y0864189
X0906565Y0864189
X0909714Y0857891
X0906565Y0857891
X0909714Y0854742
X0922313Y0851592
X0897118Y0867338
X0897118Y0870488
X0897118Y0873638
X0900267Y0864189
X0900267Y0867338
X0900267Y0870488
X0900267Y0873638
X0906565Y0867338
X0906565Y0870488
X0906565Y0873638
X0909714Y0870488
X0909714Y0873638
X0897118Y0864189
X0897118Y0857891
X0966127Y0776382
X0957500Y0780800
X0956017Y0770300
X0957487Y0798553
X0950699Y0779711
X0946970Y0786366
X0923872Y0798271
X0959950Y0734178
X0883916Y0800815
X0925228Y0816934
X0927916Y0800909
X0926961Y0723797
X0927916Y0817015
X0884002Y0797616
X0963950Y0734178
X0938357Y0808856
X0949609Y0796051
X0891916Y0799605
X0911028Y0796598
X0907866Y0795572
X0957763Y0725336
X0955950Y0734178
X0902641Y0800748
X0895829Y0800660
X0878670Y0742841
X0899916Y0808965
X0914202Y0797460
X0963869Y0725057
X0957579Y0744168
X0951151Y0730111
X0875473Y0742056
X0887916Y0808965
X0883916Y0808965
X0879916Y0808965
X0895916Y0808965
X0933201Y0798297
X0876402Y0797415
X0881637Y0744154
X0884463Y0744757
X0884976Y0740891
X0882098Y0741565
X0879887Y0784719
X0870000Y0780000
X0892040Y0784511
X0873728Y0752692
X0870017Y0757313
X0879875Y0753612
X0955225Y0788984
X0968094Y0799792
X0965983Y0763567
X0967562Y0802982
X0968589Y0722434
X0870035Y0801032
X0874142Y0748914
X0889516Y0792851
X0917803Y0811365
X0880040Y0792851
X0913716Y0811954
X0898737Y0792289
X0889763Y0788159
X0953837Y0763025
X0883413Y0759855
X0883126Y0766124
X0869325Y0761259
X0951791Y0808121
X0951461Y0812223
X0951708Y0818894
X0903916Y0810809
X0945736Y0819397
X0942858Y0819430
X0931916Y0817015
X0909785Y0810778
X0922352Y0800809
X0887916Y0800815
X0874925Y0800746
X0950475Y0789361
X0955076Y0784861
X0942676Y0789286
X0881157Y0749148
X0936026Y0727450
X0883686Y0729778
X0944916Y0808965
X0873318Y0744597
X0878610Y0747171
X0877616Y0749484
X0872700Y0816615
X0875916Y0808965
X0873250Y0798750
X0871294Y0771809
X0891916Y0808965
X0888514Y0797602
X0888545Y0785528
X0889083Y0780371
X0886836Y0729778
X0911053Y0800510
X0899916Y0800815
X0913716Y0800815
X0921790Y0810965
X0916590Y0800636
X0945626Y0789761
X0936026Y0730600
X0941916Y0808965
X0957474Y0764426
X0956323Y0748412
X0952681Y0735256
X0951195Y0727165
X0954023Y0725336
X0956051Y0793937
X0955086Y0779798
X0964036Y0818961
X0964070Y0813006
X0964070Y0807686
X0918300Y0629700
X0915800Y0629700
X0968365Y0633473
X0956345Y0633716
X0950748Y0627713
X0950865Y0633724
X0961352Y0633736
X0889525Y0722060
X0963365Y0628078
X0902841Y0703665
X0954526Y0666671
X0928704Y0680261
X0893241Y0704656
X0879135Y0632552
X0909265Y0677795
X0912462Y0683770
X0884911Y0690279
X0902236Y0694332
X0956023Y0706907
X0920090Y0666714
X0922626Y0633772
X0876286Y0698970
X0913247Y0714204
X0902236Y0689332
X0884903Y0696678
X0928353Y0686342
X0965042Y0722234
X0878881Y0667156
X0913858Y0721289
X0872862Y0666859
X0886304Y0666650
X0892461Y0666671
X0908699Y0709387
X0883309Y0666608
X0900753Y0656925
X0966797Y0667653
X0941859Y0625311
X0929690Y0666593
X0933974Y0719371
X0945434Y0634325
X0943181Y0632536
X0946128Y0666522
X0949137Y0666660
X0910836Y0721570
X0965774Y0706907
X0921061Y0715386
X0886836Y0715970
X0947556Y0699550
X0906886Y0702285
X0912462Y0687770
X0876286Y0694970
X0935281Y0680945
X0941859Y0629311
X0876286Y0690970
X0870137Y0669461
X0963187Y0667620
X0915194Y0666671
X0950865Y0641817
X0956365Y0641817
X0967302Y0627948
X0873021Y0715729
X0880501Y0710611
X0876286Y0686970
X0872069Y0700894
X0869313Y0688486
X0889436Y0715970
X0884903Y0694119
X0905050Y0720268
X0910753Y0715864
X0905313Y0709259
X0910036Y0702285
X0912462Y0695770
X0924932Y0701051
X0917286Y0679625
X0928043Y0677795
X0931244Y0720471
X0939314Y0707847
X0935281Y0677795
X0957551Y0698251
X0899530Y0530753
X0885931Y0534093
X0950667Y0616905
X0954535Y0610548
X0950479Y0622285
X0874649Y0545296
X0908846Y0560124
X0878382Y0554942
X0899407Y0560019
X0887417Y0566713
X0885556Y0543664
X0882195Y0539204
X0923642Y0561578
X0923453Y0569578
X0895933Y0609696
X0913998Y0597103
X0921217Y0589216
X0939992Y0527726
X0923599Y0581578
X0917811Y0544325
X0875290Y0578703
X0913728Y0550495
X0876949Y0571419
X0914296Y0558143
X0886549Y0553963
X0898207Y0599891
X0891673Y0600049
X0881131Y0577349
X0881476Y0588202
X0919038Y0579378
X0921507Y0578791
X0910789Y0598726
X0919080Y0587640
X0933725Y0585936
X0933725Y0589336
X0933741Y0594687
X0933741Y0598087
X0912908Y0621616
X0909508Y0621616
X0904076Y0621536
X0900676Y0621536
X0968145Y0607762
X0965345Y0610562
X0965345Y0607762
X0968145Y0610562
X0962545Y0610562
X0959745Y0610562
X0959745Y0607762
X0962545Y0607762
X0965173Y0591215
X0962373Y0591215
X0959573Y0591215
X0965173Y0581222
X0962373Y0581222
X0959573Y0581222
X0958016Y0571194
X0960816Y0571194
X0960816Y0563194
X0958016Y0563194
X0967042Y0540458
X0960816Y0555194
X0958016Y0555194
X0967042Y0537658
X0948532Y0541135
X0948905Y0534909
X0948621Y0552726
X0948598Y0546553
X0939992Y0544726
X0925949Y0608863
X0925949Y0612363
X0891933Y0618143
X0876351Y0605023
X0876351Y0608523
X0931627Y0573578
X0931627Y0577578
X0931627Y0581578
X0931627Y0569578
X0931627Y0557641
X0893949Y0547363
X0891449Y0547363
X0899931Y0534093
X0892931Y0534093
X0944351Y0534211
X0936653Y0526836
X0941859Y0621311
X0939992Y0548726
X0944296Y0611071
X0960581Y0531882
X0952531Y0531948
X0961166Y0529169
X0955581Y0531882
X0958081Y0531882
X0959466Y0525369
X0959466Y0522569
X0931578Y0590669
X0931620Y0584417
X0931647Y0593271
X0931594Y0599420
X0902459Y0530755
X0894449Y0606363
X0887949Y0608863
X0895933Y0618143
X0894015Y0588253
X0890956Y0588325
X0890959Y0579788
X0882949Y0557363
X0892023Y0570176
X0893949Y0550363
X0896449Y0550863
X0882891Y0536122
X0906996Y0530707
X0896431Y0534093
X0903431Y0534093
X0904854Y0619040
X0899898Y0619040
X0913686Y0619120
X0908730Y0619120
X0909024Y0574394
X0906999Y0588274
X0902635Y0588305
X0909024Y0586768
X0898232Y0588320
X0909024Y0578394
X0898815Y0570176
X0908517Y0570176
X0904393Y0570176
X0913853Y0561487
X0898156Y0554812
X0909362Y0555614
X0910578Y0550186
X0911630Y0543998
X0915949Y0563363
X0920961Y0550075
X0924600Y0533706
X0915712Y0613792
X0943825Y0591215
X0943825Y0581222
X0931627Y0565578
X0931627Y0561578
X0939992Y0552726
X0939992Y0540726
X0939992Y0536726
X0939827Y0531104
X0948427Y0611091
X0946625Y0591215
X0949425Y0591215
X0949425Y0581222
X0946625Y0581222
X0951016Y0563194
X0953816Y0563194
X0951016Y0571194
X0953816Y0571194
X0951016Y0555194
X0953816Y0555194
X0964012Y0546830
X0968462Y0429368
X0966694Y0427599
X0963816Y0464419
X0962769Y0451419
X0882954Y0486256
X0869954Y0487303
X0955816Y0464919
X0869454Y0479303
X0916593Y0469140
X0933412Y0468942
X0933161Y0451442
X0933404Y0463462
X0933424Y0458455
X0927401Y0469059
X0910236Y0465272
X0921973Y0469328
X0927596Y0447453
X0927766Y0456442
X0958736Y0482165
X0941872Y0440942
X0957977Y0500202
X0958124Y0492354
X0949823Y0495982
X0963816Y0472905
X0959600Y0496486
X0955816Y0473419
X0949823Y0491982
X0907450Y0460062
X0910250Y0460062
X0890903Y0460234
X0870882Y0461791
X0880910Y0460234
X0907450Y0451662
X0910250Y0451662
X0907450Y0457262
X0907450Y0454462
X0910250Y0454462
X0910250Y0457262
X0890903Y0457434
X0890903Y0454634
X0880910Y0457434
X0880910Y0454634
X0870882Y0458991
X0876271Y0426952
X0873771Y0426952
X0878536Y0437408
X0881036Y0437408
X0876036Y0437408
X0873536Y0437408
X0878771Y0426952
X0881271Y0426952
X0877253Y0422880
X0874253Y0422880
X0924999Y0477948
X0954182Y0481467
X0891454Y0486303
X0962816Y0442919
X0967912Y0485138
X0965412Y0485138
X0962563Y0485128
X0920999Y0477948
X0928999Y0477948
X0959816Y0472905
X0968340Y0459839
X0968340Y0462339
X0968340Y0457339
X0953915Y0517401
X0956415Y0517401
X0958915Y0517401
X0953974Y0504825
X0956474Y0504825
X0958974Y0504825
X0910759Y0475511
X0921963Y0424445
X0924763Y0424445
X0927563Y0424445
X0917541Y0441280
X0924480Y0436716
X0921680Y0436716
X0927280Y0436716
X0917541Y0443780
X0967816Y0472905
X0949823Y0483982
X0949876Y0478486
X0882907Y0480350
X0875907Y0486256
X0870882Y0468791
X0870882Y0465991
X0880910Y0466382
X0880910Y0469182
X0880910Y0471982
X0897019Y0426952
X0892019Y0426952
X0887096Y0437264
X0896388Y0437614
X0889596Y0437264
X0894519Y0426952
X0891699Y0423245
X0889219Y0426952
X0890903Y0466382
X0890903Y0471982
X0890903Y0469182
X0910779Y0471380
X0907173Y0443081
X0898888Y0437614
X0907173Y0440581
X0907712Y0436734
X0902712Y0436734
X0905212Y0436734
X0907594Y0424581
X0902594Y0424581
X0905094Y0424581
X0929050Y0450316
X0927636Y0452505
X0941505Y0463442
X0950315Y0464851
X0956863Y0451466
X0962769Y0458466
X0963577Y0426391
X0949823Y0499982
X0949823Y0487982
X0939331Y0324044
X0942731Y0324044
X0968348Y0402369
X0869924Y0328722
X0877977Y0329368
X0877977Y0333368
X0877977Y0325368
X0929947Y0376821
X0872158Y0359962
X0869924Y0333722
X0870413Y0342791
X0874005Y0344917
X0906344Y0372524
X0898869Y0351114
X0897736Y0383125
X0883552Y0357276
X0888812Y0357372
X0916330Y0377748
X0910646Y0376084
X0905000Y0362158
X0905483Y0355262
X0960376Y0392807
X0936175Y0364823
X0944238Y0360828
X0934047Y0369160
X0913288Y0372752
X0934464Y0358618
X0923311Y0349959
X0908625Y0359317
X0908521Y0356708
X0898533Y0334498
X0906161Y0367191
X0934128Y0355168
X0924564Y0344041
X0940997Y0335312
X0927964Y0344041
X0940997Y0331912
X0919629Y0336333
X0917882Y0324816
X0919354Y0344150
X0939300Y0346363
X0916229Y0336333
X0917882Y0328216
X0915954Y0344150
X0942700Y0346363
X0921343Y0376888
X0874253Y0420080
X0878690Y0411619
X0881190Y0411619
X0879417Y0415322
X0876917Y0415322
X0877253Y0420380
X0890553Y0392038
X0872736Y0391754
X0882925Y0391099
X0880736Y0383125
X0877909Y0391731
X0891251Y0387484
X0869342Y0407627
X0931072Y0386992
X0915072Y0386992
X0911072Y0386992
X0876736Y0383125
X0929943Y0372600
X0896592Y0374369
X0896592Y0354369
X0896592Y0358369
X0885953Y0333368
X0885953Y0329368
X0885953Y0325368
X0914323Y0401051
X0914323Y0403551
X0914323Y0398551
X0901747Y0400992
X0901747Y0403492
X0901747Y0398492
X0889979Y0405743
X0893779Y0404043
X0896579Y0404043
X0887266Y0402658
X0887266Y0405158
X0887266Y0400158
X0940600Y0370600
X0938499Y0362202
X0945120Y0326441
X0936608Y0326058
X0923902Y0332411
X0912085Y0332335
X0917858Y0331453
X0932622Y0336817
X0949813Y0336817
X0940972Y0338238
X0940924Y0328959
X0945599Y0345383
X0936453Y0345336
X0930398Y0342050
X0922198Y0342051
X0949579Y0330517
X0932388Y0330517
X0909417Y0323302
X0926801Y0323302
X0913206Y0336489
X0922629Y0336609
X0921847Y0346622
X0912278Y0343881
X0944694Y0352192
X0869342Y0417399
X0872318Y0408589
X0872736Y0383125
X0871382Y0373971
X0873733Y0357844
X0873885Y0340892
X0897344Y0418983
X0890270Y0415290
X0891699Y0420445
X0887770Y0415290
X0894844Y0418983
X0888736Y0383125
X0893736Y0383125
X0884736Y0383125
X0896592Y0370369
X0896592Y0366369
X0896592Y0362369
X0886026Y0346584
X0910040Y0353532
X0902169Y0415502
X0902169Y0418002
X0902169Y0413002
X0914202Y0415502
X0914202Y0413002
X0914202Y0418002
X0923072Y0386992
X0919072Y0386992
X0927072Y0386992
X0915395Y0369210
X0921468Y0369210
X0927309Y0369210
X0927309Y0363239
X0915395Y0363212
X0915395Y0357267
X0921389Y0357267
X0927309Y0357267
X0944900Y0363700
X0948400Y0370045
X0943663Y0355674
X0954888Y0369513
X0952170Y0356131
X0958823Y0362802
X0956348Y0356371
X0937000Y0315684
X0937000Y0312284
X0887148Y0249670
X0944248Y0239844
X0936962Y0249807
X0948785Y0242464
X0869924Y0321368
X0869924Y0313368
X0877977Y0321368
X0877977Y0309368
X0877977Y0305368
X0877977Y0317368
X0885918Y0289500
X0896034Y0243307
X0886059Y0284644
X0891383Y0243203
X0877977Y0313368
X0879112Y0302369
X0869924Y0305368
X0895140Y0265236
X0892484Y0260860
X0895064Y0250186
X0950953Y0317947
X0886496Y0268968
X0876622Y0293721
X0949974Y0291554
X0948741Y0229468
X0943183Y0281652
X0873262Y0300030
X0872050Y0302644
X0923732Y0304585
X0893284Y0236739
X0905898Y0302347
X0893284Y0233339
X0909298Y0302347
X0899352Y0311960
X0899352Y0308560
X0915653Y0307438
X0883118Y0262687
X0897004Y0257480
X0885884Y0255118
X0945018Y0276051
X0933403Y0245507
X0919577Y0264567
X0919616Y0268462
X0919577Y0271654
X0910977Y0262205
X0896953Y0272012
X0910977Y0248032
X0910977Y0243307
X0919577Y0250394
X0919577Y0240945
X0946482Y0255940
X0947733Y0319680
X0885953Y0321368
X0885989Y0313368
X0885989Y0317368
X0930727Y0302571
X0913057Y0311046
X0885989Y0305368
X0885989Y0309368
X0898048Y0269387
X0951278Y0250583
X0947040Y0223885
X0917906Y0321670
X0939606Y0310521
X0939653Y0317474
X0941845Y0278968
X0876246Y0302754
X0885741Y0261150
X0886261Y0252090
X0895780Y0232634
X0895780Y0237517
X0905120Y0304843
X0910076Y0304843
X0901848Y0312738
X0901848Y0307782
X0898851Y0266929
X0910977Y0266929
X0898851Y0274016
X0910977Y0257480
X0910977Y0252756
X0898576Y0253056
X0898851Y0259843
X0910977Y0238583
X0898851Y0245669
X0898851Y0238583
X0898851Y0231496
X0919729Y0274580
X0919577Y0255118
X0919577Y0259843
X0919682Y0236921
X0919577Y0233858
X0919577Y0245669
X0919606Y0231000
X0920142Y0308501
X0912786Y0306697
X0946064Y0252998
X0940158Y0245707
X0942805Y0223860
X0938125Y0230891
X0968906Y0226226
X0968906Y0231226
X0968906Y0228726
X0968906Y0223726
X0951040Y0223885
X0891852Y0148277
X0919609Y0124283
X0929697Y0124663
X0924675Y0124879
X0906622Y0152373
X0894472Y0143740
X0934678Y0125107
X0907522Y0143518
X0931041Y0138838
X0916453Y0167975
X0871826Y0186778
X0899573Y0158195
X0915267Y0157370
X0937438Y0213817
X0937192Y0148717
X0942179Y0215727
X0946234Y0213390
X0903035Y0141247
X0871713Y0192665
X0871713Y0196665
X0943292Y0143762
X0871745Y0208864
X0950177Y0215730
X0968906Y0210478
X0968906Y0215478
X0968906Y0212978
X0968906Y0207978
X0909772Y0152562
X0936395Y0218142
X0925098Y0203256
X0927898Y0203256
X0934411Y0204641
X0934477Y0211491
X0934411Y0207141
X0931698Y0201556
X0934411Y0202141
X0871745Y0204864
X0871713Y0176665
X0871713Y0168665
X0918016Y0161306
X0936151Y0142862
X0887005Y0141247
X0942561Y0135915
X0949861Y0128828
X0949861Y0125428
X0942561Y0132515
X0947424Y0187219
X0944424Y0184419
X0942987Y0195680
X0940487Y0195680
X0942260Y0191977
X0944760Y0191977
X0944424Y0186919
X0947906Y0180347
X0947424Y0184419
X0942906Y0180347
X0940406Y0180347
X0945406Y0180347
X0883233Y0147540
X0871745Y0221864
X0871745Y0216864
X0871745Y0212864
X0871745Y0200864
X0871713Y0180665
X0871713Y0172665
X0886011Y0154100
X0897715Y0152367
X0898813Y0146461
X0929978Y0184054
X0927719Y0188564
X0929978Y0186854
X0925219Y0188564
X0927859Y0180347
X0925359Y0180347
X0923565Y0134579
X0929418Y0133298
X0921418Y0133298
X0944961Y0130670
X0940161Y0130670
X0944961Y0123584
X0940161Y0123584
X0936369Y0221292
X0933907Y0192009
X0931407Y0192009
X0933159Y0180347
X0930359Y0180347
X0940945Y0150847
X0938057Y0141228
X0936151Y0146012
X0944961Y0137757
X0940161Y0137757
X0966347Y0137756
X0949443Y0208206
X0949359Y0198710
X0952161Y0137756
X0961633Y0137756
X0947461Y0123583
X0952161Y0123583
X0952161Y0130670
X0947461Y0130670
X0961638Y0130670
X0925118Y0110784
X0930118Y0110784
X0945011Y0095111
X0960161Y0095236
X0949380Y0106561
X0871341Y0086046
X0876200Y0086012
X0872293Y0094279
X0870519Y0060438
X0960411Y0090650
X0965723Y0090615
X0936417Y0102495
X0919175Y0119594
X0919175Y0116594
X0876200Y0094374
X0942561Y0121742
X0949861Y0114655
X0942561Y0118342
X0949861Y0111255
X0949615Y0097667
X0949221Y0103411
X0931144Y0116594
X0931144Y0119594
X0940761Y0097667
X0870395Y0096738
X0873373Y0060922
X0927393Y0102249
X0923393Y0102249
X0921824Y0110784
X0919175Y0113394
X0931393Y0102249
X0940161Y0116497
X0937410Y0109172
X0936417Y0106495
X0934410Y0109172
X0944961Y0116497
X0942490Y0044773
X0942490Y0024773
X0947461Y0109410
X0952161Y0102323
X0952161Y0109410
X0952161Y0116496
X0947461Y0116497
X0960413Y0116496
X0960413Y0109410
X0960161Y0102323
X0960623Y0085584
X0960623Y0075184
X0960623Y0080384
X0960623Y0077784
X0960623Y0082984
X0949811Y0053597
X0963360Y0121459
X0963177Y0092849
X0956460Y-0027614
X0953207Y-0027600
X0950167Y-0026405
X0950167Y-0037191
X0953192Y-0038511
X0956445Y-0038497
X0953207Y-0035996
X0956460Y-0035982
X0956448Y-0033204
X0956448Y-0030304
X0956445Y-0025099
X0953192Y-0025085
X0978036Y-0077691
X0981289Y-0077677
X0930145Y0003000
X0941129Y0004469
X1011187Y-0040126
X1011187Y-0043526
X1011187Y-0030126
X1011187Y-0033526
X1013683Y-0034304
X1013683Y-0029348
X1013683Y-0039348
X1013683Y-0044304
X1008281Y-0026433
X1008281Y-0036919
X1008281Y-0047219
X1002000Y-0030120
X1001988Y-0027542
X1005241Y-0027628
X1002003Y-0025027
X1005256Y-0025113
X1001988Y-0035710
X1002000Y-0032720
X1005241Y-0035724
X1001988Y-0046024
X1005241Y-0046024
X1002000Y-0043334
X1002003Y-0048539
X1005256Y-0048539
X1002003Y-0038225
X1005256Y-0038239
X1002000Y-0040834
X0981304Y-0066794
X0978051Y-0066780
X0975011Y-0065585
X0975011Y-0076371
X0978051Y-0075176
X0981304Y-0075162
X0981292Y-0072384
X0981292Y-0069484
X0981289Y-0064279
X0978036Y-0064265
X0988606Y0005374
X1007508Y0003000
X1027508Y0003000
X1043492Y0004469
X1032480Y0110784
X1027480Y0110784
X1047373Y0095111
X1013480Y0103621
X0997837Y0097475
X1004818Y0100625
X1062523Y0095236
X0970044Y0099961
X1009191Y0112083
X0970094Y0095236
X1051742Y0106561
X0981029Y0107649
X0981029Y0104249
X1021341Y0086046
X1017787Y0085731
X1026200Y0086012
X1017659Y0060513
X1018344Y0094351
X1020519Y0060438
X1022293Y0094279
X1003379Y0076587
X1068085Y0090615
X1003379Y0072615
X1062773Y0090650
X1038779Y0102495
X1021537Y0119594
X1021537Y0116594
X1015427Y0088801
X1026200Y0094374
X0978958Y0079993
X0978958Y0074793
X0978958Y0077393
X0978958Y0082593
X0978958Y0085193
X1052223Y0114655
X1044923Y0121742
X1052223Y0111255
X1044923Y0118342
X1051977Y0097667
X0979002Y0092874
X1051583Y0103411
X0997768Y0106186
X0990833Y0103783
X0987283Y0098551
X1011297Y0080581
X1011284Y0068581
X1015059Y0055513
X1033506Y0119594
X1033506Y0116594
X1043123Y0097667
X0978271Y0116496
X0970271Y0109410
X0970271Y0116496
X0970137Y0103037
X0978271Y0102323
X0978271Y0109410
X0969811Y0053597
X0994833Y0103783
X0987682Y0110445
X0992674Y0110445
X0992674Y0115401
X0987682Y0115401
X0987283Y0101701
X0991554Y0094017
X0987554Y0094017
X0983554Y0094017
X0987919Y0044773
X0987919Y0024773
X1000631Y0080140
X1000631Y0076140
X1000631Y0084140
X0998084Y0117557
X1003076Y0117557
X1006000Y0103621
X0995563Y0094017
X1024186Y0110784
X1025755Y0102249
X1021537Y0113394
X1014006Y0117261
X1015402Y0091951
X1020254Y0097068
X1018209Y0055513
X1023373Y0060922
X1042523Y0116497
X1029755Y0102249
X1038779Y0106495
X1039772Y0109172
X1036772Y0109172
X1033755Y0102249
X1047323Y0116497
X1049823Y0116497
X1054523Y0102323
X1054523Y0109410
X1054523Y0116496
X1049823Y0109410
X1052174Y0053597
X1044853Y0044773
X1044853Y0024773
X1062775Y0116496
X1062775Y0109410
X1062523Y0102323
X1062985Y0085584
X1065539Y0092849
X1062985Y0080384
X1062985Y0077784
X1062985Y0075184
X1062985Y0082984
X1000580Y0118335
X0990178Y0111223
X0990178Y0114623
X1000580Y0121735
X0994214Y0148277
X1027037Y0124879
X1032059Y0124663
X1008984Y0152373
X1021971Y0124283
X0996834Y0143740
X1012999Y0172665
X1021713Y0192665
X1037040Y0125107
X1009884Y0143518
X1033403Y0138838
X1021826Y0186778
X1017629Y0157370
X1039554Y0148717
X1005397Y0141247
X1045654Y0143762
X1021745Y0208864
X1013205Y0212455
X1013116Y0200864
X1013139Y0207037
X1021713Y0196665
X1010291Y0199582
X1012826Y0183834
X0997929Y0168697
X0994695Y0215632
X0979362Y0215713
X0983434Y0211695
X0990992Y0211359
X0990992Y0213859
X0985934Y0211695
X0983434Y0208695
X0986234Y0208695
X0979362Y0213213
X0979362Y0210713
X0979362Y0208213
X0994695Y0213132
X0989573Y0184012
X0986956Y0184221
X0992754Y0181009
X0986748Y0181426
X0989959Y0181366
X1007071Y0192490
X1012346Y0190185
X1003029Y0192300
X0994675Y0177616
X1012936Y0178560
X0995256Y0172190
X1012134Y0152562
X1017386Y0219379
X1026794Y0218085
X1033394Y0216385
X1036107Y0216970
X1036107Y0219470
X1036107Y0221970
X1029594Y0218085
X1021745Y0204864
X1013812Y0186629
X0999017Y0191941
X1021713Y0168665
X1021713Y0176665
X1020378Y0161306
X1038513Y0142862
X0989367Y0141247
X0987751Y0170493
X0987751Y0167993
X0987751Y0165393
X0987751Y0162793
X0980651Y0162368
X0978051Y0162368
X1044923Y0132515
X1052223Y0128828
X1052223Y0125428
X1044923Y0135915
X1043956Y0206806
X1046456Y0206806
X1044683Y0210509
X1049120Y0202048
X1046120Y0201748
X1042183Y0210509
X1049602Y0195176
X1049120Y0199248
X1044602Y0195176
X1046120Y0199248
X1047102Y0195176
X1042102Y0195176
X0985595Y0147540
X1001156Y0221708
X1006156Y0221708
X1003656Y0221708
X1010506Y0221642
X1001026Y0206767
X1006026Y0206767
X1003526Y0206767
X0978271Y0137756
X0978271Y0123583
X0978271Y0130670
X0970271Y0123583
X0970271Y0130670
X0985595Y0151540
X0992674Y0129574
X0987682Y0129574
X0987682Y0124618
X0992674Y0124618
X0991024Y0222212
X0989112Y0188727
X0989245Y0191941
X0997725Y0206760
X0995745Y0184619
X1006415Y0185121
X1001777Y0185165
X1010183Y0192421
X1006460Y0180527
X1001777Y0180572
X1000077Y0152367
X0998084Y0136687
X1003076Y0136687
X1001175Y0146461
X0998084Y0131731
X0998084Y0122513
X1003076Y0131731
X1003076Y0122513
X1021745Y0216864
X1021745Y0221864
X1021745Y0200864
X1021745Y0212864
X1026915Y0203393
X1027055Y0195176
X1021713Y0172665
X1021713Y0180665
X1025927Y0134579
X1024289Y0130898
X1031674Y0201683
X1029415Y0203393
X1035603Y0206838
X1033103Y0206838
X1034855Y0195176
X1029555Y0195176
X1031674Y0198883
X1032055Y0195176
X1043307Y0150847
X1042523Y0137757
X1040419Y0141228
X1038513Y0146012
X1042523Y0123584
X1042523Y0130670
X1031780Y0133298
X1051055Y0213539
X1047323Y0137757
X1054523Y0137756
X1054523Y0123583
X1054523Y0130670
X1049823Y0123583
X1047323Y0123584
X1047323Y0130670
X1049823Y0130670
X1063995Y0137756
X1064000Y0130670
X1062947Y0124576
X1000580Y0132509
X0990178Y0125396
X1000580Y0135909
X0990178Y0128796
X0994698Y0265896
X1032121Y0249108
X1042084Y0256394
X0997187Y0281982
X0999714Y0266114
X0989611Y0265701
X0991246Y0281716
X1034741Y0244571
X1018014Y0228631
X0994939Y0256303
X1010499Y0309062
X1039134Y0228646
X1048130Y0227824
X1043875Y0230556
X1050437Y0244297
X1022604Y0290262
X0987517Y0314092
X0972160Y0258880
X0993552Y0318175
X1001105Y0318006
X1023502Y0248371
X1051796Y0279965
X1045364Y0279895
X1033890Y0296293
X1037290Y0296293
X1002580Y0309619
X1021848Y0310396
X1022435Y0312865
X1030220Y0313554
X1041783Y0321114
X1027216Y0289440
X1052720Y0230117
X0973365Y0264068
X0970865Y0264068
X0981129Y0267526
X0986429Y0267526
X0983929Y0267526
X0981129Y0270026
X0983929Y0270026
X0986429Y0270026
X1000698Y0300276
X1020635Y0300276
X1025749Y0300276
X1012635Y0300276
X1016635Y0300276
X1029639Y0300141
X1045650Y0300093
X1050076Y0305512
X1050164Y0302748
X1038091Y0232971
X1048217Y0246874
X1042860Y0242078
X1036173Y0226320
X1048736Y0238714
X1005460Y0270695
X1002960Y0270695
X1008260Y0270695
X1002960Y0268195
X1005460Y0268195
X1008260Y0268195
X1007763Y0248765
X1005263Y0248765
X1002763Y0248765
X1007822Y0236189
X1005322Y0236189
X1002822Y0236189
X1000571Y0224421
X1002271Y0231021
X1002271Y0228221
X1011920Y0265897
X1014420Y0265897
X1030184Y0288709
X0976763Y0307303
X0972452Y0293796
X0974952Y0293796
X0979362Y0223661
X0987055Y0320273
X0993243Y0321325
X0993132Y0310942
X0989992Y0290755
X0993992Y0290755
X0980466Y0285690
X0980466Y0288190
X0982966Y0285690
X0985766Y0285690
X0982966Y0288190
X0985766Y0288190
X0990939Y0256535
X0985514Y0248891
X0988014Y0248891
X0983014Y0248891
X0983312Y0236611
X0988312Y0236611
X0985812Y0236611
X0987331Y0231786
X0979362Y0226461
X0979362Y0228961
X0979362Y0231461
X0985869Y0226141
X0983069Y0226141
X0991024Y0224712
X0987331Y0229286
X1008635Y0300276
X1004635Y0300276
X0997992Y0290755
X1008563Y0288345
X1008563Y0290845
X1006063Y0288345
X1006063Y0290845
X1006063Y0293645
X1008563Y0293645
X1004061Y0280808
X0999826Y0278734
X0998939Y0256535
X1023502Y0252371
X1004933Y0314535
X1004544Y0318050
X0998667Y0322239
X1041496Y0300276
X1033112Y0298789
X1038068Y0298789
X1037984Y0253198
X1035099Y0238589
X1038065Y0236121
X1048695Y0280161
X1052736Y0238714
X1045275Y0247292
X1044501Y0238689
X0975631Y0343112
X0975631Y0346612
X0971721Y0407762
X0991392Y0409230
X0983956Y0346652
X0983717Y0341665
X0996024Y0352132
X0989630Y0343862
X0988631Y0349496
X0986373Y0370467
X1003076Y0332496
X0997020Y0345354
X1031259Y0350427
X1020406Y0350772
X1043106Y0340230
X1042948Y0333696
X1009770Y0344486
X1000420Y0353954
X1003181Y0323057
X0981719Y0352217
X0993026Y0353813
X0977150Y0338972
X0977150Y0331972
X0980045Y0366559
X0990420Y0337954
X0990420Y0340454
X1061387Y0343509
X1060679Y0356151
X1060679Y0368276
X1062234Y0382600
X1062865Y0419347
X1054863Y0398113
X1062865Y0394401
X1062865Y0405174
X1054863Y0401513
X1062865Y0408574
X1062234Y0378600
X1062865Y0391001
X1052463Y0415687
X1052463Y0412287
X0977150Y0328472
X0972147Y0323681
X0969623Y0405614
X0977150Y0335472
X0973338Y0345018
X0988045Y0366559
X0984045Y0366559
X0992045Y0366559
X0993420Y0337954
X0993920Y0335454
X1000420Y0348954
X0997921Y0333654
X1031354Y0322905
X1013313Y0339909
X1022845Y0340944
X1013318Y0333190
X1013327Y0327453
X1026032Y0322906
X1021451Y0322879
X1013354Y0323362
X1046674Y0340031
X1031362Y0329268
X1031377Y0333671
X1031310Y0337888
X1031382Y0340947
X1031354Y0325901
X1054959Y0416465
X1049967Y0411509
X1049967Y0416465
X1054959Y0411509
X1057359Y0397335
X1052367Y0397335
X1057359Y0402291
X1052367Y0402291
X1045966Y0346808
X1065361Y0418569
X1060369Y0418569
X1065361Y0409352
X1065361Y0404396
X1065361Y0395179
X1060369Y0409352
X1060369Y0404396
X1060369Y0395179
X1065361Y0390223
X1060369Y0390223
X1060679Y0364276
X1060679Y0360151
X1061325Y0339509
X0977327Y0462371
X0981843Y0464818
X0979910Y0445603
X0972030Y0446071
X0972397Y0465004
X0971826Y0430187
X0976397Y0473045
X1063113Y0455921
X1059549Y0458711
X0987803Y0459652
X0987803Y0462152
X0987803Y0464652
X0985303Y0459652
X0985303Y0462152
X0985303Y0464652
X0992206Y0496133
X0992206Y0493633
X0988134Y0498151
X0980576Y0495487
X0985334Y0498151
X0980576Y0492987
X0985634Y0495151
X0988134Y0495151
X0992206Y0498633
X0976873Y0493714
X0992206Y0491133
X0976873Y0491214
X1012188Y0443421
X0970412Y0485138
X0970997Y0482425
X0969297Y0475825
X0969297Y0478625
X1061693Y0463600
X1064876Y0453682
X0970840Y0462339
X0970840Y0459839
X0970840Y0457339
X1052463Y0429860
X1052463Y0483560
X1062865Y0490673
X1052463Y0444033
X1052463Y0516921
X1062865Y0494073
X1062865Y0422747
X1062865Y0479899
X1052463Y0472787
X1052463Y0440633
X1062865Y0433521
X1052463Y0426460
X1062865Y0476499
X1052463Y0486960
X1062349Y0458711
X1062865Y0436921
X1052463Y0469387
X1062865Y0520633
X1052463Y0513521
X1065361Y0475721
X1065361Y0480677
X1060369Y0475721
X1060369Y0480677
X1054959Y0473565
X1049967Y0473565
X1054959Y0482782
X1049967Y0482782
X0980397Y0473045
X0983989Y0478446
X0983989Y0475946
X0988499Y0480705
X0992206Y0476086
X0980544Y0484634
X0980544Y0482134
X0985699Y0480705
X0992206Y0483886
X0992206Y0481086
X0992206Y0478586
X0972397Y0472954
X0969109Y0449352
X0973695Y0448874
X0971932Y0437508
X0975932Y0437508
X0982670Y0450201
X0982792Y0447269
X0979932Y0437508
X1015195Y0428305
X1054959Y0468609
X1049967Y0468609
X1054959Y0444811
X1050777Y0450750
X1049967Y0444811
X1054959Y0439855
X1049967Y0430638
X1054959Y0430638
X1049967Y0439855
X1049967Y0425682
X1054959Y0425682
X1065361Y0437699
X1065361Y0432743
X1060369Y0437699
X1060369Y0432743
X1065361Y0423525
X1060369Y0423525
X0975925Y0516979
X0974406Y0521804
X0973425Y0516979
X0978425Y0516979
X0973723Y0504699
X0976223Y0504699
X0978723Y0504699
X0973843Y0500086
X0984936Y0519531
X0982436Y0519531
X0987436Y0519531
X0989936Y0519531
X0982375Y0522129
X1054959Y0487738
X1049967Y0487738
X1049967Y0517699
X1054959Y0512743
X1049967Y0512743
X1054959Y0517699
X1065361Y0519855
X1060369Y0519855
X1065361Y0494851
X1060369Y0494851
X1060369Y0489895
X1065361Y0489895
X0981857Y0605637
X1062098Y0619600
X1062098Y0603600
X1061496Y0612786
X1061342Y0610269
X0973857Y0605443
X0977857Y0605443
X0986688Y0596089
X0977857Y0597130
X0998332Y0578986
X0997857Y0596729
X0991907Y0596782
X0992906Y0578405
X0978032Y0590801
X0986510Y0573303
X0989156Y0573689
X0989513Y0576484
X1001825Y0581659
X0989096Y0570478
X0986301Y0570686
X0982375Y0540377
X0982375Y0545377
X0982375Y0542877
X0984888Y0548366
X0982388Y0548366
X0987388Y0548366
X0978303Y0544895
X0975503Y0544895
X0975803Y0541895
X0978303Y0541895
X0970745Y0542231
X0982375Y0537877
X0989888Y0548366
X0970745Y0539731
X0992306Y0558497
X0992306Y0566797
X0992306Y0563697
X0992306Y0561097
X0992306Y0553297
X0992306Y0555897
X1001857Y0605443
X0993857Y0605443
X0981857Y0597232
X0978581Y0582747
X1055885Y0554555
X1052463Y0527694
X1062865Y0538206
X1062865Y0524033
X1062865Y0534806
X0976027Y0617853
X0976027Y0620653
X0983843Y0613913
X0983843Y0616713
X0983843Y0619513
X0995913Y0614158
X0995913Y0616958
X0995913Y0619758
X1052463Y0531094
X0986268Y0532949
X0989068Y0532949
X0976962Y0608311
X0978581Y0572975
X0975868Y0527449
X0970713Y0528878
X0970713Y0531378
X0974406Y0524304
X0978668Y0527449
X0989857Y0605443
X0989995Y0590190
X0985401Y0590145
X0989950Y0585507
X0985357Y0585507
X0985903Y0579475
X0981795Y0572842
X0982375Y0529929
X0982375Y0524629
X0982375Y0527129
X0997857Y0605443
X1062098Y0615600
X1059782Y0594668
X1059843Y0597580
X1054876Y0536382
X1054959Y0526916
X1049967Y0531872
X1054959Y0531872
X1049967Y0526916
X1065361Y0534028
X1065361Y0538984
X1060369Y0534028
X1060369Y0538984
X1060369Y0524811
X1065361Y0524811
X1062066Y0607588
X1062069Y0596095
X1061267Y0592354
X1061328Y0589556
X1062066Y0599588
X0972354Y0627908
X1002883Y0622521
X1022937Y0691421
X1029885Y0711762
X1005800Y0637600
X0978865Y0642184
X1021885Y0698974
X1001676Y0678015
X1001605Y0627605
X1003900Y0628700
X1062098Y0623600
X1066931Y0645389
X1063642Y0634190
X0986600Y0717641
X1015659Y0683054
X1015659Y0679654
X0970197Y0667653
X1026916Y0719769
X0973712Y0722064
X0980703Y0625013
X0973138Y0667621
X0969491Y0629362
X0980683Y0628242
X0983843Y0636005
X0983843Y0633205
X0983843Y0638805
X0995913Y0639050
X0995913Y0636250
X0995913Y0633450
X1066559Y0634946
X1024932Y0717856
X1025116Y0698332
X1018155Y0684132
X1018238Y0678647
X0983712Y0722064
X1013486Y0750773
X1007027Y0792973
X1013319Y0785929
X0996385Y0816141
X0987990Y0774005
X0999990Y0774671
X1010699Y0803454
X0990699Y0778630
X1013151Y0756726
X1024684Y0756485
X0994051Y0810871
X1006054Y0810969
X0997051Y0778833
X0978978Y0817618
X0999990Y0764566
X0984357Y0777555
X0998376Y0810970
X1012695Y0776728
X1038344Y0756476
X1035619Y0755809
X1038678Y0776750
X0983786Y0765647
X1018015Y0751565
X1017664Y0779101
X1018071Y0798490
X1017955Y0812097
X0982300Y0821200
X0988371Y0764143
X1043016Y0782161
X0985921Y0805135
X0978352Y0730766
X0971081Y0722637
X0976186Y0789819
X1002751Y0757169
X1014781Y0810319
X0987394Y0787490
X1013821Y0813520
X1007990Y0765899
X0970839Y0729923
X1042414Y0801443
X1046930Y0796557
X1046068Y0792742
X1014064Y0793660
X1033200Y0731700
X0978214Y0821224
X1012851Y0722417
X1014641Y0724436
X1009562Y0722438
X1011185Y0724519
X0981876Y0745179
X0973450Y0747280
X0987461Y0745796
X1039251Y0812340
X0987501Y0812573
X1002699Y0819475
X1021895Y0818974
X1003990Y0765899
X0977218Y0802178
X0976764Y0786563
X0978059Y0747438
X0987903Y0818645
X0979313Y0814316
X0984963Y0785387
X0991990Y0773974
X0988329Y0781445
X0985030Y0781204
X0984307Y0748432
X1018044Y0793592
X1019375Y0783056
X1021895Y0771974
X1015804Y0760454
X0999825Y0819488
X1006053Y0787745
X1002834Y0777394
X1003539Y0762632
X1008342Y0761735
X1025859Y0802275
X1014587Y0802788
X1015800Y0807535
X1030753Y0732213
X1044112Y0778835
X1042880Y0794924
X1026090Y0770943
X1038796Y0763272
X1048328Y0808166
X1045744Y0800835
X1037685Y0862789
X1035185Y0862793
X0987702Y0829159
X0987703Y0837159
X0973510Y0834991
X0981700Y0856300
X1024913Y0884000
X1038010Y0902565
X0973988Y0910038
X0990300Y0897500
X1004713Y0871389
X0989311Y0920364
X0988054Y0888283
X0998313Y0888295
X1050295Y0891100
X1012842Y0910685
X0983269Y0853883
X0990457Y0852043
X1001187Y0850084
X0979498Y0907500
X1044390Y0861210
X1053909Y0855472
X1052500Y0841200
X1049087Y0856033
X1040822Y0841339
X1050358Y0837793
X1046045Y0841217
X1012703Y0837659
X1054900Y0879321
X1058155Y0887635
X0970299Y0853773
X0994094Y0829000
X0974437Y0849140
X1004577Y0853679
X1031813Y0850273
X1037527Y0836486
X1041100Y0838500
X1051550Y0823146
X1053392Y0832788
X1043626Y0836563
X1053913Y0837718
X1048314Y0833102
X0969309Y0839334
X1018419Y0917575
X1029570Y0917718
X1022346Y0917669
X0970040Y0842903
X1055700Y0840900
X1043425Y0830800
X1045300Y0872352
X1038363Y0875288
X1021408Y0895008
X0992441Y0870398
X1005413Y0905295
X1017800Y0867065
X0978880Y0869552
X0982783Y0909995
X1037709Y0886209
X0979592Y0902849
X1016798Y0890299
X1016574Y0874537
X1016973Y0877196
X0987200Y0848940
X0989800Y0843900
X0979203Y0833159
X0987319Y0843589
X0987202Y0846395
X0989700Y0846500
X1013918Y0851306
X0979891Y0876589
X1020703Y0837659
X1010977Y0841737
X1011144Y0844340
X0979203Y0829159
X0976902Y0847135
X1025239Y0845070
X1025219Y0842155
X1021221Y0848712
X1020703Y0833659
X1000369Y0834342
X1002887Y0834342
X0979203Y0837159
X0974282Y0838011
X0976800Y0838011
X0976635Y0835018
X0971144Y0908972
X0978201Y0897500
X0975925Y0854783
X0971808Y0851242
X0982787Y0899757
X0995133Y0888503
X0987790Y0896596
X0984892Y0868720
X0988231Y0878203
X0980529Y0879097
X0988820Y0858903
X0993061Y0833135
X1002930Y0906785
X1005607Y0877859
X1005607Y0874859
X1026340Y0917761
X1016320Y0828481
X1043252Y0902501
X1030300Y0881400
X1028155Y0879413
X1008935Y0924007
X1004953Y0923995
X1033370Y0953994
X1027719Y0958822
X1012219Y0954222
X1011782Y1016591
X1050744Y1021954
X1034790Y1016827
X1028943Y1016827
X1015198Y1009655
X1017998Y1009655
X0971443Y0938828
X1030819Y0938422
X1027319Y0938322
X1033019Y0935822
X1033019Y0933022
X1050744Y1009354
X1056199Y1012354
X1050699Y1012354
X1066878Y0931909
X0983227Y0968565
X1008571Y1006648
X1001805Y1007522
X1005938Y1018307
X1060698Y0931619
X1002180Y1013678
X1022009Y0988813
X1034009Y0988813
X1065823Y0988773
X1042009Y0988813
X1058009Y0988813
X1062009Y0988813
X1030009Y0988813
X1050009Y0988813
X1009564Y0988874
X1046009Y0988813
X1054009Y0988813
X1026009Y0988813
X1038009Y0988813
X1021924Y0980456
X1018009Y0988813
X1014009Y0988813
X0988240Y1016923
X0988240Y1020015
X1066009Y0980330
X1018009Y0980356
X1014009Y0980356
X0999879Y0998507
X1014719Y0938322
X1004719Y0948822
X1011019Y0948822
X1007919Y0948822
X1004994Y0955372
X1006222Y0980337
X1006619Y0933822
X1010119Y0933822
X1017619Y0932122
X1023319Y0937922
X1019519Y0937922
X1018919Y0951522
X1023519Y0951522
X1031219Y0949922
X0969806Y0993033
X1059689Y1012354
X1058009Y0997860
X1062009Y0997860
X1066009Y0997860
X1057961Y0931919
X0972278Y0934429
X0988461Y1013841
X0999700Y1018400
X1005301Y1006560
X1010009Y0998100
X1025448Y1011762
X1014009Y0997860
X1025448Y1008262
X1026009Y0997860
X1018009Y0997860
X1022009Y0997860
X1038252Y1021954
X1034752Y1021954
X1038009Y0997860
X1042009Y0997860
X1028943Y1009354
X1034752Y1009354
X1038252Y1009354
X1034009Y0997860
X1030009Y0997860
X1050009Y0997860
X1054009Y0997860
X1046009Y0997860
X0989513Y1097683
X0986645Y1108465
X1060768Y1053457
X1067866Y1051037
X1057212Y1040356
X1065079Y1036920
X0988240Y1023968
X0980726Y1092664
X1039098Y1102091
X1024570Y1024003
X1017297Y1122164
X1023144Y1122164
X1023144Y1109564
X1017297Y1109564
X1034790Y1029427
X1028943Y1029427
X1025143Y1030672
X1039098Y1114691
X1044553Y1117691
X1039053Y1117691
X1044553Y1105091
X1039053Y1105091
X1050699Y1024954
X1056199Y1024954
X1046485Y1034538
X0972776Y1100659
X1002652Y1023731
X0980726Y1104659
X0980852Y1098643
X0972776Y1088659
X0972255Y1083484
X0972776Y1093659
X1039499Y1098758
X1016143Y1030672
X1019143Y1030672
X1022143Y1030672
X0972776Y1096659
X0980726Y1084659
X0980969Y1076659
X0983751Y1078675
X0984909Y1081071
X1008759Y1023900
X1060172Y1050481
X1066933Y1040567
X1059689Y1024954
X0974948Y1114103
X0972248Y1114103
X0969648Y1114103
X0981087Y1101902
X0980726Y1088659
X0980726Y1080659
X1026606Y1114691
X1023106Y1114691
X1017297Y1114691
X1023106Y1102091
X1026606Y1102591
X1017297Y1102091
X1022594Y1035114
X1014767Y1035088
X1043553Y1035384
X1048043Y1117691
X1048043Y1105091
X1039098Y1165091
X1039098Y1177691
X1017297Y1185164
X1023139Y1184856
X1017297Y1172564
X1023162Y1174445
X1017297Y1159964
X1023144Y1159964
X1017297Y1147364
X1023144Y1147364
X1017297Y1134764
X1023144Y1134764
X1039098Y1127291
X1039098Y1152491
X1021976Y1218169
X1039098Y1139891
X1044553Y1155491
X1039053Y1155491
X1039053Y1168091
X1044553Y1168091
X1044553Y1142891
X1039053Y1142891
X1044553Y1130291
X1039053Y1130291
X1039053Y1180691
X1044553Y1180691
X1032831Y1207950
X1026221Y1214372
X1049930Y1221407
X0978169Y1221268
X1029797Y1220921
X0978614Y1214838
X0987804Y1131619
X0984558Y1134774
X0984558Y1128774
X0988112Y1137774
X0984558Y1140774
X0991763Y1134378
X0991763Y1128378
X0991763Y1140378
X0995009Y1131223
X0995317Y1137378
X0970761Y1216607
X0970485Y1132870
X0975048Y1123803
X0972348Y1123803
X0969748Y1123803
X1023106Y1152491
X1017297Y1152491
X1017297Y1127291
X1026606Y1139891
X1023106Y1139891
X1017297Y1139891
X1026606Y1127291
X1023106Y1127291
X1022420Y1203204
X1020434Y1205579
X1026606Y1177691
X1023106Y1177691
X1017297Y1177691
X1026606Y1165091
X1023106Y1165091
X1017297Y1165091
X1026606Y1152491
X1035384Y1215195
X1040600Y1210600
X1048043Y1180691
X1048043Y1168091
X1048043Y1142891
X1048043Y1155491
X1048043Y1130291
X0978614Y1210568
X0990501Y1320756
X1050002Y1293283
X1052660Y1293257
X0979001Y1288925
X0984817Y1303297
X0974985Y1290950
X1049720Y1234921
X1049770Y1229402
X1050605Y1224472
X1043588Y1227300
X1040606Y1230407
X1051249Y1290288
X1025434Y1320606
X0978727Y1284908
X0988389Y1302558
X1026968Y1223749
X0980139Y1393308
X1007850Y1368835
X0980092Y1389370
X0999283Y1377400
X0980203Y1377559
X0985448Y1398271
X0980047Y1397245
X0980166Y1373622
X0997401Y1381200
X0980139Y1381496
X0979996Y1386100
X1009333Y1343293
X1009333Y1346693
X1019391Y1377061
X0998600Y1373400
X0998643Y1398271
X0988784Y1361974
X0998600Y1369200
X1049493Y1350694
X1046075Y1350650
X1049670Y1347462
X1054713Y1348187
X1058113Y1348187
X1066953Y1372385
X1066953Y1384297
X1054713Y1360099
X1058113Y1360099
X0987136Y1401636
X0984136Y1401636
X1008387Y1380797
X1013991Y1360842
X0993413Y1327048
X0993413Y1324248
X0990613Y1327048
X0990613Y1324248
X0996213Y1327048
X0996213Y1324248
X1023358Y1363921
X1058113Y1384297
X1054713Y1384297
X1066953Y1408495
X1066953Y1360099
X1054713Y1372385
X1066953Y1396583
X1058113Y1372385
X1066953Y1348187
X1049204Y1337377
X1005338Y1418386
X1005338Y1412786
X1005338Y1415586
X1008138Y1418386
X1008138Y1412786
X1008138Y1415586
X1005338Y1409986
X1005338Y1407186
X1008138Y1409986
X1008138Y1407186
X1053935Y1357603
X1058891Y1357603
X1053935Y1350683
X1053935Y1345691
X1058891Y1350683
X1058891Y1345691
X1053935Y1386793
X1058891Y1386793
X1053935Y1369889
X1053935Y1374881
X1053935Y1381801
X1058891Y1369889
X1058891Y1374881
X1058891Y1381801
X1053935Y1362595
X1058891Y1362595
X1066175Y1410991
X1066175Y1405999
X1066175Y1386793
X1066175Y1399079
X1066175Y1393993
X1066175Y1374881
X1066175Y1369795
X1066175Y1381801
X1066175Y1362595
X1066175Y1357603
X1066175Y1345691
X1066175Y1350683
X1034513Y1333665
X1052221Y1336984
X0981857Y1360945
X0983501Y1369685
X0981944Y1413859
X0980501Y1369685
X1008312Y1363533
X1008483Y1372734
X1008452Y1376752
X1021623Y1373216
X1042586Y1345824
X1015286Y1344924
X0978857Y1360945
X0978944Y1413859
X1030338Y1388597
X1030338Y1391597
X1024338Y1388597
X1024338Y1391597
X1027338Y1391597
X1027338Y1388597
X1018338Y1388597
X1018338Y1391597
X1021338Y1391597
X1021338Y1388597
X1015338Y1388597
X1015338Y1391597
X1012338Y1391597
X1012338Y1388597
X1009338Y1388597
X1009338Y1391597
X1006211Y1397662
X1011829Y1342515
X1011829Y1347471
X1048403Y1444608
X1016769Y1489832
X1020023Y1489637
X0982241Y1489637
X1025138Y1469602
X1002538Y1469702
X0979538Y1469802
X1025138Y1454839
X1025138Y1457839
X1025138Y1460839
X1025138Y1463839
X1025138Y1466839
X1002538Y1454939
X1002538Y1457939
X1002538Y1460939
X1002538Y1463939
X1002538Y1466939
X0979538Y1455039
X0979538Y1458039
X0979538Y1461039
X0979538Y1464039
X0979538Y1467039
X0978987Y1489832
X1068861Y1451311
X0978934Y1444392
X1025615Y1444492
X1002194Y1444392
X1026422Y1514993
X1016022Y1514993
X1018622Y1514993
X1021222Y1514993
X1023822Y1514993
X1013422Y1514993
X1010822Y1514993
X1005622Y1514993
X1008222Y1514993
X0989340Y1514693
X0986740Y1514693
X0978940Y1514693
X0981540Y1514693
X0984140Y1514693
X0976340Y1514693
X0973740Y1514693
X0971140Y1514693
X1007049Y1512415
X1017449Y1512415
X1020049Y1512415
X1027849Y1512415
X1022649Y1512415
X1025249Y1512415
X1014849Y1512415
X1012249Y1512415
X1009649Y1512415
X1027849Y1507215
X1026749Y1509815
X1029349Y1509815
X1009649Y1507215
X1012249Y1507215
X1014849Y1507215
X1020049Y1507215
X1017449Y1507215
X1025249Y1507215
X1022649Y1507215
X1024149Y1509815
X1018949Y1509815
X1021549Y1509815
X1016349Y1509815
X1013749Y1509815
X1011149Y1509815
X1007049Y1507215
X0988167Y1506915
X0990767Y1506915
X0990767Y1512115
X0988167Y1512115
X0987067Y1509515
X0992267Y1509515
X0989667Y1509515
X1008549Y1509815
X0980367Y1512115
X0982967Y1512115
X0977767Y1512115
X0975167Y1512115
X0972567Y1506915
X0969967Y1506915
X0975167Y1506915
X0977767Y1506915
X0982967Y1506915
X0980367Y1506915
X0985567Y1506915
X0985567Y1512115
X0981867Y1509515
X0984467Y1509515
X0979267Y1509515
X0976667Y1509515
X0969967Y1512115
X0972567Y1512115
X0974067Y1509515
X0971467Y1509515
X1041867Y1440213
X1044867Y1440213
X1041867Y1437213
X1044867Y1437213
X1041867Y1434213
X1041867Y1428213
X1041867Y1431213
X1044867Y1431213
X1044867Y1428213
X1044867Y1434213
X1038867Y1440213
X1038867Y1437213
X1035867Y1440213
X1035867Y1437213
X1029867Y1440213
X1032867Y1440213
X1029867Y1437213
X1032867Y1437213
X1038867Y1434213
X1038867Y1431213
X1038867Y1428213
X1035867Y1434213
X1029867Y1434213
X1032867Y1434213
X1029867Y1431213
X1035867Y1428213
X1035867Y1431213
X1029867Y1428213
X1032867Y1428213
X1032867Y1431213
X1018981Y1440097
X1021981Y1440097
X1018981Y1437097
X1021981Y1437097
X1018981Y1434097
X1018981Y1428097
X1018981Y1431097
X1021981Y1431097
X1021981Y1428097
X1021981Y1434097
X1015981Y1440097
X1015981Y1437097
X1012981Y1440097
X1012981Y1437097
X1006981Y1440097
X1009981Y1440097
X1006981Y1437097
X1009981Y1437097
X1015981Y1434097
X1015981Y1431097
X1015981Y1428097
X1012981Y1434097
X1006981Y1434097
X1009981Y1434097
X1006981Y1431097
X1012981Y1428097
X1012981Y1431097
X1006981Y1428097
X1009981Y1428097
X1009981Y1431097
X0995949Y1439997
X0998949Y1439997
X0995949Y1436997
X0998949Y1436997
X0995949Y1433997
X0995949Y1427997
X0995949Y1430997
X0998949Y1430997
X0998949Y1427997
X0998949Y1433997
X0992949Y1439997
X0992949Y1436997
X0989949Y1439997
X0989949Y1436997
X0983949Y1439997
X0986949Y1439997
X0983949Y1436997
X0986949Y1436997
X0992949Y1433997
X0992949Y1430997
X0992949Y1427997
X0989949Y1433997
X0983949Y1433997
X0986949Y1433997
X0983949Y1430997
X0989949Y1427997
X0989949Y1430997
X0983949Y1427997
X0986949Y1427997
X0986949Y1430997
X0972883Y1439997
X0975883Y1439997
X0972883Y1436997
X0975883Y1436997
X0972883Y1433997
X0972883Y1427997
X0972883Y1430997
X0975883Y1430997
X0975883Y1427997
X0975883Y1433997
X0969883Y1439997
X0969883Y1436997
X0969883Y1433997
X0969883Y1430997
X0969883Y1427997
X0980773Y1546081
X0983773Y1546081
X0986773Y1546081
X0971547Y1546081
X0974547Y1546081
X0977547Y1546081
X1004611Y1552247
X1004611Y1555247
X1004611Y1558247
X1004611Y1561247
X1007611Y1552247
X1007611Y1555247
X1007611Y1558247
X1007611Y1561247
X1019653Y1571669
X1016653Y1571669
X1013653Y1571669
X1019606Y1547824
X1016606Y1547824
X1013606Y1547824
X1010653Y1571669
X1010606Y1547824
X1019659Y1565771
X1016659Y1565771
X1013659Y1565771
X1010659Y1565771
X1019659Y1568771
X1016659Y1568771
X1013659Y1568771
X1010659Y1568771
X1051457Y1639797
X1031457Y1639797
X1011457Y1639797
X0971457Y1639797
X0991457Y1639797
X1090093Y1628297
X1105474Y1629450
X1097474Y1637753
X1096941Y1627905
X1089474Y1638213
X1105474Y1638426
X1085474Y1629028
X1093474Y1638213
X1101474Y1637820
X1112000Y1644980
X1092000Y1644980
X1132000Y1644980
X1152000Y1644980
X1071457Y1639797
X1101402Y1531702
X1096780Y1535400
X1098617Y1546183
X1091525Y1546300
X1096780Y1526700
X1091529Y1528718
X1084000Y1529600
X1086904Y1599004
X1083900Y1593206
X1093778Y1599574
X1102904Y1566668
X1088021Y1606949
X1098904Y1602138
X1101946Y1614709
X1091569Y1561300
X1100233Y1588000
X1100476Y1579318
X1090469Y1588435
X1092527Y1579422
X1099371Y1561153
X1095250Y1531600
X1083283Y1526583
X1090904Y1599047
X1104233Y1587983
X1098498Y1590435
X1093682Y1582433
X1086469Y1588435
X1107620Y1603602
X1082176Y1600598
X1090876Y1554183
X1100876Y1554183
X1083483Y1523433
X1107620Y1606752
X1099900Y1535700
X1093713Y1585583
X1096264Y1562285
X1090747Y1617415
X1138298Y1587960
X1138298Y1593853
X1138298Y1583229
X1129637Y1589522
X1129637Y1594253
X1129637Y1583629
X1138298Y1578498
X1138298Y1567875
X1129637Y1574167
X1129637Y1578898
X1129637Y1568275
X1138298Y1572606
X1138298Y1563144
X1129637Y1558813
X1129637Y1563544
X1138298Y1618669
X1138298Y1613938
X1129637Y1614338
X1138298Y1609207
X1129637Y1604876
X1129637Y1598984
X1129637Y1609607
X1138298Y1603315
X1138298Y1598584
X1155621Y1618669
X1155621Y1613938
X1146960Y1614338
X1155621Y1603315
X1155621Y1598584
X1155621Y1609207
X1146960Y1598984
X1146960Y1604876
X1146960Y1609607
X1146960Y1589522
X1155621Y1583229
X1146960Y1583629
X1155621Y1587960
X1155621Y1593853
X1146960Y1594253
X1155621Y1578498
X1146960Y1578898
X1146960Y1574167
X1155621Y1567875
X1146960Y1568275
X1155621Y1572606
X1146960Y1558813
X1155621Y1563144
X1146960Y1563544
X1164283Y1594253
X1164283Y1589522
X1164283Y1583629
X1164283Y1568275
X1164283Y1578898
X1164283Y1574167
X1164283Y1563544
X1164283Y1558813
X1164283Y1614338
X1164283Y1598984
X1164283Y1604876
X1164283Y1609607
X1069642Y1445541
X1095080Y1513398
X1129637Y1487159
X1129637Y1491890
X1138298Y1496221
X1138298Y1485598
X1138298Y1491490
X1129637Y1496621
X1129637Y1471805
X1138298Y1480867
X1138298Y1470244
X1138298Y1476136
X1129637Y1481267
X1129637Y1476536
X1138298Y1460782
X1138298Y1465513
X1129637Y1456451
X1129637Y1461182
X1129637Y1465913
X1138298Y1516307
X1138298Y1506845
X1129637Y1511976
X1129637Y1502514
X1129637Y1507245
X1138298Y1511576
X1138298Y1500952
X1146960Y1496621
X1146960Y1491890
X1146960Y1487159
X1155621Y1496221
X1155621Y1485598
X1155621Y1491490
X1155621Y1470244
X1155621Y1476136
X1146960Y1481267
X1146960Y1476536
X1146960Y1471805
X1155621Y1480867
X1146960Y1456451
X1155621Y1460782
X1155621Y1465513
X1146960Y1461182
X1146960Y1465913
X1155621Y1516307
X1146960Y1511976
X1155621Y1511576
X1155621Y1500952
X1155621Y1506845
X1146960Y1502514
X1146960Y1507245
X1164283Y1496621
X1164283Y1491890
X1164283Y1487159
X1164283Y1481267
X1164283Y1476536
X1164283Y1471805
X1164283Y1461182
X1164283Y1456451
X1164283Y1465913
X1164283Y1511976
X1164283Y1502514
X1164283Y1507245
X1115913Y1384297
X1079193Y1408495
X1128153Y1360099
X1156033Y1360099
X1131553Y1408495
X1107073Y1360099
X1079193Y1360099
X1156033Y1408495
X1143793Y1384297
X1152633Y1360099
X1070353Y1384297
X1082593Y1408495
X1070353Y1372385
X1152633Y1396583
X1152633Y1348187
X1164873Y1372385
X1128153Y1348187
X1156033Y1348187
X1094833Y1372385
X1140393Y1372385
X1103673Y1348187
X1128153Y1396583
X1079193Y1348187
X1079193Y1396583
X1082593Y1396583
X1119313Y1372385
X1168273Y1372385
X1107073Y1348187
X1103673Y1396583
X1156033Y1396583
X1107073Y1396583
X1131553Y1396583
X1082593Y1348187
X1091433Y1372385
X1143793Y1372385
X1131553Y1348187
X1115913Y1372385
X1164873Y1384297
X1128153Y1408495
X1091433Y1384297
X1082593Y1360099
X1103673Y1408495
X1107073Y1408495
X1131553Y1360099
X1152633Y1408495
X1119313Y1384297
X1094833Y1384297
X1140393Y1384297
X1103673Y1360099
X1168273Y1384297
X1070353Y1408495
X1070353Y1360099
X1079193Y1384297
X1094833Y1360099
X1094833Y1408495
X1103673Y1384297
X1091433Y1408495
X1119313Y1360099
X1082593Y1384297
X1115913Y1360099
X1091433Y1360099
X1107073Y1384297
X1131553Y1372385
X1119313Y1348187
X1070353Y1348187
X1094833Y1396583
X1152633Y1372385
X1119313Y1396583
X1115913Y1348187
X1168273Y1396583
X1115913Y1396583
X1164873Y1348187
X1164873Y1396583
X1082593Y1372385
X1168273Y1348187
X1103673Y1372385
X1091433Y1348187
X1107073Y1372385
X1079193Y1372385
X1143793Y1348187
X1140393Y1396583
X1140393Y1348187
X1091433Y1396583
X1094833Y1348187
X1143793Y1396583
X1070353Y1396583
X1128153Y1372385
X1156033Y1372385
X1119313Y1408495
X1140393Y1408495
X1168273Y1360099
X1164873Y1408495
X1164095Y1410991
X1164095Y1405999
X1164095Y1386793
X1164095Y1399079
X1164095Y1393993
X1164095Y1374881
X1164095Y1381801
X1164095Y1369889
X1164095Y1362595
X1164095Y1357603
X1164095Y1345597
X1164095Y1350683
X1144571Y1410991
X1144571Y1405999
X1151855Y1410991
X1151855Y1405999
X1156811Y1410991
X1156811Y1405999
X1144571Y1386793
X1144571Y1399079
X1144571Y1394087
X1151855Y1394087
X1151855Y1399079
X1151855Y1386793
X1156811Y1394087
X1156811Y1399079
X1156811Y1386793
X1144571Y1374881
X1144571Y1381801
X1144571Y1369889
X1151855Y1381801
X1151855Y1369889
X1151855Y1374881
X1156811Y1381801
X1156811Y1369889
X1156811Y1374881
X1144571Y1362595
X1144571Y1357603
X1151855Y1357603
X1151855Y1362595
X1156811Y1362595
X1156811Y1357603
X1144571Y1345691
X1144571Y1350683
X1151855Y1350683
X1151855Y1345691
X1156811Y1345691
X1156811Y1350683
X1127375Y1410991
X1127375Y1405999
X1132331Y1410991
X1132331Y1405999
X1139615Y1410991
X1139615Y1405999
X1127375Y1399079
X1127375Y1394087
X1127375Y1386793
X1132331Y1399079
X1132331Y1394087
X1132331Y1386793
X1139615Y1386793
X1139615Y1399079
X1139615Y1394087
X1127375Y1374881
X1127375Y1381801
X1127375Y1369889
X1132331Y1374881
X1132331Y1381801
X1132331Y1369889
X1139615Y1381801
X1139615Y1369889
X1139615Y1374881
X1127375Y1362595
X1127375Y1357603
X1132331Y1357603
X1132331Y1362595
X1139615Y1362595
X1139615Y1357603
X1127375Y1345691
X1127375Y1350683
X1132331Y1350683
X1132331Y1345691
X1139615Y1345691
X1139615Y1350683
X1120091Y1410991
X1120091Y1405999
X1115135Y1410991
X1115135Y1405999
X1120091Y1386793
X1120091Y1394087
X1120091Y1399079
X1115135Y1386793
X1115135Y1399079
X1115135Y1394087
X1120091Y1381801
X1120091Y1374881
X1120091Y1369889
X1115135Y1369889
X1115135Y1381801
X1115135Y1374881
X1120091Y1362595
X1120091Y1357603
X1115135Y1362595
X1115135Y1357603
X1120091Y1350683
X1120091Y1345691
X1115135Y1350683
X1115135Y1345691
X1095611Y1410991
X1095611Y1405999
X1102895Y1410991
X1102895Y1405999
X1107851Y1410991
X1107851Y1405999
X1095611Y1386793
X1095611Y1394087
X1095611Y1399079
X1102895Y1399079
X1102895Y1394087
X1102895Y1386793
X1107851Y1399079
X1107851Y1394087
X1107851Y1386793
X1095611Y1369889
X1095611Y1374881
X1095611Y1381801
X1102895Y1381801
X1102895Y1369889
X1102895Y1374881
X1107851Y1381801
X1107851Y1374881
X1107851Y1369889
X1095611Y1362595
X1095611Y1357603
X1107851Y1362595
X1102895Y1357603
X1102895Y1362595
X1107851Y1357603
X1095611Y1345691
X1095611Y1350683
X1107851Y1350683
X1102895Y1345691
X1102895Y1350683
X1107851Y1345691
X1078415Y1410991
X1078415Y1405999
X1083371Y1410991
X1083371Y1405999
X1090655Y1410991
X1090655Y1405999
X1078415Y1399079
X1078415Y1394087
X1078415Y1386793
X1083371Y1394087
X1083371Y1399079
X1083371Y1386793
X1090655Y1386793
X1090655Y1399079
X1090655Y1394087
X1078415Y1381801
X1078415Y1374881
X1078415Y1369889
X1083371Y1381801
X1083371Y1374881
X1083371Y1369889
X1090655Y1369889
X1090655Y1374881
X1090655Y1381801
X1078415Y1357603
X1078415Y1362595
X1083371Y1362595
X1083371Y1357603
X1090655Y1362595
X1090655Y1357603
X1078415Y1350683
X1078415Y1345691
X1083371Y1350683
X1083371Y1345691
X1090655Y1345691
X1090655Y1350683
X1071131Y1410991
X1071131Y1405999
X1071131Y1386793
X1071131Y1393993
X1071131Y1399079
X1071131Y1374881
X1071131Y1369795
X1071131Y1381801
X1071131Y1362595
X1071131Y1357603
X1071131Y1345691
X1071131Y1350683
X1152633Y1384297
X1168273Y1408495
X1143793Y1360099
X1131553Y1384297
X1115913Y1408495
X1164873Y1360099
X1140393Y1360099
X1156033Y1384297
X1128153Y1384297
X1143793Y1408495
X1079822Y1159350
X1083562Y1155610
X1079822Y1151870
X1079178Y1037884
X1076577Y1041332
X1074232Y1055836
X1078755Y1031518
X1076110Y1029535
X1079910Y1045264
X1074650Y1070006
X1076868Y1047293
X1079809Y1034386
X1071348Y1050503
X1071641Y1058029
X1070009Y0997860
X1069685Y0933391
X1073525Y1012428
X1076800Y1012900
X1074009Y0988813
X1092769Y0936975
X1069607Y0980131
X1070009Y0988813
X1074009Y0997860
X1070778Y1012252
X1159887Y0869106
X1090375Y0899047
X1078920Y0856700
X1161535Y0844167
X1153229Y0848581
X1163579Y0850774
X1152510Y0844642
X1152512Y0728543
X1164732Y0802269
X1154985Y0802897
X1153485Y0813142
X1129471Y0732571
X1147468Y0766093
X1148962Y0747253
X1152485Y0764552
X1164925Y0791607
X1145910Y0803642
X1154652Y0791056
X1146985Y0812642
X1149627Y0813323
X1151277Y0790996
X1145910Y0794217
X1149345Y0771517
X1152316Y0746625
X1149437Y0728541
X1160516Y0800900
X1161291Y0791662
X1157985Y0791142
X1168577Y0733812
X1166115Y0718469
X1163774Y0713347
X1164275Y0656321
X1160275Y0656321
X1111785Y0686971
X1160146Y0699491
X1162646Y0699491
X1157646Y0699491
X1155146Y0699491
X1159173Y0678462
X1162863Y0678519
X1156275Y0656321
X1116296Y0691851
X1118105Y0707592
X1115054Y0662981
X1108045Y0668153
X1115320Y0646449
X1115151Y0650119
X1160756Y0665140
X1112839Y0668885
X1104448Y0653161
X1118863Y0662981
X1157251Y0636842
X1163157Y0638125
X1108045Y0677843
X1118855Y0705043
X1113244Y0691851
X1156023Y0678462
X1163751Y0719498
X1167900Y0553300
X1165400Y0553300
X1139673Y0530000
X1157451Y0618288
X1118847Y0558917
X1118847Y0561420
X1161451Y0618288
X1089096Y0545263
X1089096Y0541863
X1105298Y0610400
X1138277Y0562800
X1138213Y0558800
X1087288Y0553407
X1089788Y0553407
X1087288Y0550907
X1089788Y0550907
X1114668Y0577937
X1122705Y0591015
X1122705Y0588515
X1085512Y0572070
X1086859Y0569928
X1089206Y0570962
X1088949Y0568475
X1091272Y0569426
X1091558Y0566929
X1159535Y0542712
X1138173Y0547075
X1138373Y0549800
X1127153Y0531088
X1127153Y0527688
X1119853Y0534775
X1119853Y0524002
X1119853Y0538175
X1118847Y0551683
X1117914Y0612592
X1099501Y0545528
X1117633Y0618400
X1122173Y0604567
X1122673Y0595500
X1117673Y0606929
X1123267Y0616317
X1123331Y0610072
X1108236Y0577716
X1139173Y0540500
X1137673Y0568000
X1159535Y0546712
X1071548Y0555234
X1071263Y0562003
X1091287Y0595108
X1090823Y0602197
X1091542Y0547106
X1091542Y0540020
X1091542Y0532933
X1091542Y0525847
X1105298Y0606400
X1105298Y0614400
X1105298Y0594400
X1105298Y0602400
X1105298Y0598400
X1099813Y0574102
X1101040Y0560675
X1099272Y0562443
X1101581Y0572334
X1099827Y0552872
X1099949Y0550123
X1099342Y0525847
X1121022Y0607750
X1120512Y0617332
X1121191Y0612555
X1122718Y0598857
X1117453Y0595118
X1117453Y0602205
X1117913Y0575414
X1117913Y0572914
X1117913Y0570414
X1117913Y0567914
X1117913Y0565414
X1117453Y0547106
X1117453Y0554193
X1117453Y0540020
X1117453Y0532933
X1117453Y0525847
X1124753Y0525846
X1122253Y0525846
X1122253Y0540020
X1122253Y0532933
X1124753Y0532933
X1125287Y0592897
X1126633Y0560500
X1138673Y0555000
X1138098Y0543925
X1138166Y0534759
X1129553Y0525846
X1129553Y0532933
X1168478Y0595099
X1168478Y0602186
X1168478Y0573839
X1168478Y0588013
X1168478Y0580926
X1168478Y0566752
X1161274Y0550462
X1168478Y0530886
X1168478Y0537973
X1168478Y0523800
X1168478Y0616359
X1168478Y0609272
X1168685Y0438323
X1168851Y0445873
X1126622Y0506256
X1134629Y0465551
X1168398Y0456309
X1127153Y0483554
X1119853Y0520602
X1119853Y0479868
X1119853Y0429828
X1127153Y0486954
X1127153Y0433515
X1127153Y0436915
X1127153Y0513515
X1127153Y0469381
X1119853Y0426428
X1119853Y0444002
X1127153Y0422741
X1119853Y0494041
X1119853Y0476468
X1127153Y0516915
X1127153Y0472781
X1119853Y0440602
X1119853Y0490641
X1135548Y0455804
X1163298Y0465874
X1129553Y0474626
X1129553Y0481712
X1117453Y0474626
X1124753Y0474626
X1122253Y0474626
X1117453Y0481713
X1122253Y0481712
X1124753Y0481712
X1109242Y0479104
X1108395Y0472772
X1099342Y0474626
X1099603Y0480828
X1091542Y0474626
X1091542Y0481713
X1168478Y0472579
X1168478Y0486752
X1168478Y0479666
X1091542Y0467539
X1091542Y0445847
X1091542Y0438760
X1091542Y0431673
X1091542Y0424587
X1099342Y0467539
X1101073Y0445847
X1108451Y0436447
X1108846Y0429832
X1100762Y0426299
X1108776Y0422864
X1117453Y0467539
X1124753Y0467539
X1109653Y0467539
X1117453Y0445847
X1122253Y0445847
X1110486Y0447953
X1122253Y0431673
X1117453Y0438760
X1117453Y0431673
X1124753Y0431673
X1124753Y0438760
X1122253Y0438760
X1117453Y0424586
X1124753Y0424586
X1122253Y0424586
X1125178Y0459792
X1129553Y0467539
X1130355Y0453483
X1126931Y0453564
X1129553Y0438760
X1129553Y0431673
X1129553Y0424586
X1168851Y0449873
X1167931Y0435029
X1168902Y0431029
X1091542Y0518760
X1091542Y0511673
X1091542Y0495886
X1091542Y0488799
X1099342Y0511673
X1099342Y0518760
X1108253Y0510565
X1105002Y0516841
X1101553Y0498834
X1117453Y0518760
X1117453Y0511673
X1124753Y0511673
X1122253Y0518760
X1124753Y0518760
X1109653Y0495886
X1117453Y0495886
X1122253Y0495886
X1109129Y0487711
X1117453Y0488799
X1124753Y0488799
X1122253Y0488799
X1129553Y0511673
X1129553Y0518760
X1129553Y0488799
X1168478Y0516713
X1168478Y0493839
X1166868Y0442956
X1098845Y0353404
X1105012Y0353504
X1085615Y0339815
X1092554Y0340318
X1093841Y0371335
X1082787Y0348501
X1108779Y0327705
X1118848Y0382109
X1091031Y0374810
X1082297Y0340770
X1097976Y0340477
X1092561Y0353374
X1142440Y0396718
X1103432Y0340544
X1079748Y0322743
X1080351Y0331656
X1080351Y0328256
X1145587Y0339148
X1137830Y0336230
X1115000Y0339000
X1115000Y0334000
X1115000Y0329000
X1119853Y0401482
X1119853Y0415655
X1119853Y0398082
X1127153Y0394395
X1127153Y0405168
X1127153Y0419341
X1119853Y0412255
X1127153Y0390995
X1127153Y0408568
X1079863Y0345660
X1077855Y0332434
X1077252Y0323521
X1077855Y0327478
X1091542Y0417500
X1091542Y0403327
X1091542Y0396240
X1091542Y0410413
X1091542Y0389154
X1099575Y0412571
X1104691Y0396240
X1100621Y0404911
X1099342Y0396240
X1106161Y0389154
X1099342Y0389154
X1093994Y0374003
X1101999Y0353495
X1100703Y0340560
X1117453Y0410413
X1117453Y0403327
X1117453Y0396240
X1124753Y0410413
X1122253Y0410413
X1124753Y0403326
X1122253Y0403327
X1124753Y0396240
X1122253Y0396240
X1124753Y0389153
X1117453Y0389154
X1123500Y0334000
X1123500Y0339000
X1123500Y0329000
X1124753Y0417499
X1122253Y0417500
X1117453Y0417500
X1109468Y0414823
X1142440Y0412718
X1129553Y0417499
X1142440Y0404718
X1129553Y0410413
X1129553Y0403326
X1129553Y0396240
X1129553Y0389153
X1142440Y0408718
X1142440Y0400718
X1142440Y0392718
X1145761Y0324148
X1093608Y0281716
X1097060Y0265896
X1147590Y0253198
X1102076Y0266114
X1099549Y0281982
X1091973Y0265701
X1134483Y0249108
X1137103Y0244571
X1093478Y0310305
X1097301Y0256303
X1120376Y0228631
X1141496Y0228646
X1150492Y0227824
X1074522Y0258880
X1152799Y0244297
X1088791Y0270026
X1086291Y0270026
X1083491Y0270026
X1086291Y0267526
X1088791Y0267526
X1083491Y0267526
X1077097Y0264180
X1074597Y0264180
X1079748Y0319343
X1155082Y0230117
X1146237Y0230556
X1125864Y0248371
X1076571Y0310574
X1140453Y0232971
X1150579Y0246874
X1145222Y0242078
X1138535Y0226320
X1151098Y0238714
X1104633Y0231021
X1102933Y0224421
X1107822Y0270695
X1105322Y0270695
X1105322Y0268195
X1107822Y0268195
X1107625Y0248765
X1105125Y0248765
X1107684Y0236189
X1105184Y0236189
X1104633Y0228221
X1110622Y0270695
X1110622Y0268195
X1114282Y0265897
X1116782Y0265897
X1110125Y0248765
X1110184Y0236189
X1071268Y0231226
X1071268Y0228726
X1074814Y0293796
X1071268Y0223726
X1071268Y0226226
X1077602Y0314060
X1077252Y0318565
X1092354Y0290755
X1077314Y0293796
X1082828Y0288190
X1085328Y0285690
X1082828Y0285690
X1085328Y0288190
X1088128Y0288190
X1088128Y0285690
X1085376Y0248891
X1087876Y0248891
X1090376Y0248891
X1090674Y0236611
X1088174Y0236611
X1085674Y0236611
X1089693Y0231786
X1081724Y0228961
X1081724Y0231461
X1089693Y0229286
X1081724Y0223661
X1088231Y0226141
X1081724Y0226461
X1085431Y0226141
X1100354Y0290755
X1096354Y0290755
X1108425Y0288345
X1108425Y0290845
X1108425Y0293645
X1106435Y0281307
X1102331Y0279208
X1093301Y0256535
X1101301Y0256535
X1093386Y0224712
X1110925Y0288345
X1110925Y0290845
X1110925Y0293645
X1125864Y0252371
X1140346Y0253198
X1140427Y0236121
X1137461Y0238589
X1147637Y0247292
X1155098Y0238714
X1146863Y0238689
X1124333Y0124283
X1096576Y0148277
X1134421Y0124663
X1111346Y0152373
X1129399Y0124879
X1099196Y0143740
X1115361Y0172665
X1139402Y0125107
X1112246Y0143518
X1135765Y0138838
X1124188Y0186778
X1119991Y0157370
X1141916Y0148717
X1097037Y0177616
X1115298Y0178560
X1109903Y0171523
X1114708Y0190185
X1097618Y0172190
X1115188Y0183834
X1109433Y0192490
X1124107Y0208864
X1148016Y0143762
X1107759Y0141247
X1115567Y0212455
X1115501Y0207037
X1115478Y0200864
X1100291Y0168697
X1097057Y0215632
X1081724Y0215713
X1097057Y0213132
X1093354Y0211359
X1093354Y0213859
X1088296Y0211695
X1088596Y0208695
X1081724Y0213213
X1081724Y0210713
X1085796Y0211695
X1085796Y0208695
X1081724Y0208213
X1071268Y0210478
X1071268Y0215478
X1071268Y0212978
X1071268Y0207978
X1089318Y0184221
X1091935Y0184012
X1095116Y0181009
X1089110Y0181426
X1092321Y0181366
X1124075Y0196665
X1124075Y0192665
X1114496Y0152562
X1119748Y0219379
X1135756Y0216385
X1138469Y0216970
X1138469Y0219470
X1138469Y0221970
X1131956Y0218085
X1129156Y0218085
X1124107Y0204864
X1116174Y0186629
X1101379Y0191941
X1124075Y0176665
X1124075Y0168665
X1122740Y0161306
X1140875Y0142862
X1091729Y0141247
X1090113Y0167993
X1090113Y0170493
X1080413Y0162368
X1090113Y0162793
X1090113Y0165393
X1083013Y0162368
X1154585Y0125428
X1147285Y0132515
X1148482Y0201748
X1148818Y0206806
X1147045Y0210509
X1144545Y0210509
X1146318Y0206806
X1151482Y0202048
X1151964Y0195176
X1146964Y0195176
X1144464Y0195176
X1151482Y0199248
X1148482Y0199248
X1149464Y0195176
X1087957Y0147540
X1147285Y0135915
X1154585Y0128828
X1092540Y0125396
X1103518Y0221708
X1108518Y0221708
X1103388Y0206767
X1108388Y0206767
X1105888Y0206767
X1106018Y0221708
X1112868Y0221642
X1069224Y0137756
X1072633Y0123583
X1072633Y0130670
X1091474Y0188727
X1091607Y0191941
X1087957Y0151540
X1080633Y0137756
X1090044Y0129574
X1090044Y0124618
X1080633Y0123583
X1080633Y0130670
X1093386Y0222212
X1100087Y0206760
X1098107Y0184619
X1108777Y0185121
X1104139Y0185165
X1108822Y0180527
X1104139Y0180572
X1102439Y0152367
X1105438Y0136687
X1100446Y0136687
X1103537Y0146461
X1100446Y0122513
X1100446Y0131731
X1105438Y0122513
X1105438Y0131731
X1095036Y0124618
X1095036Y0129574
X1124107Y0221864
X1124107Y0216864
X1124107Y0212864
X1124107Y0200864
X1112545Y0192421
X1124075Y0172665
X1124075Y0180665
X1129417Y0195176
X1137217Y0195176
X1131917Y0195176
X1134417Y0195176
X1134036Y0198883
X1128289Y0134579
X1140875Y0146012
X1126142Y0133298
X1134142Y0133298
X1135465Y0206838
X1129277Y0203393
X1131777Y0203393
X1134036Y0201683
X1137965Y0206838
X1166357Y0137756
X1166362Y0130670
X1165309Y0124576
X1153417Y0213539
X1145669Y0150847
X1144885Y0137757
X1149685Y0137757
X1156885Y0137756
X1142781Y0141228
X1156885Y0123583
X1156885Y0130670
X1144885Y0123584
X1144885Y0130670
X1152185Y0123583
X1149685Y0123584
X1149685Y0130670
X1152185Y0130670
X1092540Y0128796
X1102942Y0132509
X1102942Y0135909
X1134842Y0110784
X1129842Y0110784
X1149735Y0095111
X1115842Y0103621
X1164885Y0095236
X1107180Y0100625
X1100199Y0097475
X1111553Y0112083
X1072406Y0099961
X1072456Y0095236
X1154104Y0106561
X1128562Y0086012
X1124655Y0094279
X1122881Y0060438
X1120706Y0094351
X1120021Y0060513
X1083391Y0107649
X1083391Y0104249
X1123703Y0086046
X1120149Y0085731
X1165135Y0090650
X1105741Y0072615
X1105741Y0076587
X1141141Y0102495
X1123899Y0119594
X1123899Y0116594
X1128562Y0094374
X1117789Y0088801
X1081320Y0074793
X1081320Y0077393
X1081320Y0079993
X1081320Y0082593
X1081320Y0085193
X1154585Y0111255
X1154585Y0114655
X1147285Y0121742
X1154339Y0097667
X1135868Y0116594
X1135868Y0119594
X1145485Y0097667
X1147285Y0118342
X1081364Y0092874
X1093195Y0103783
X1100130Y0106186
X1089645Y0098551
X1113659Y0080581
X1113646Y0068581
X1114781Y0058013
X1153945Y0103411
X1092540Y0114623
X1072633Y0109410
X1072633Y0116496
X1072499Y0103037
X1072174Y0053597
X1089645Y0101701
X1085916Y0094017
X1089916Y0094017
X1090280Y0044773
X1080633Y0109410
X1080633Y0116496
X1080633Y0102323
X1090044Y0115401
X1090044Y0110445
X1108362Y0103621
X1097195Y0103783
X1105438Y0117557
X1095036Y0110445
X1095036Y0115401
X1100446Y0117557
X1093916Y0094017
X1097925Y0094017
X1102993Y0080140
X1102993Y0076140
X1102993Y0084140
X1123052Y0057511
X1123899Y0113394
X1116368Y0117261
X1117764Y0091951
X1122613Y0097042
X1126548Y0110784
X1128117Y0102249
X1132117Y0102249
X1141141Y0106495
X1139134Y0109172
X1136117Y0102249
X1125735Y0060922
X1144885Y0116497
X1149685Y0116497
X1152185Y0116497
X1152185Y0109410
X1156885Y0109410
X1156885Y0102323
X1156885Y0116496
X1142134Y0109172
X1154535Y0053597
X1147214Y0044773
X1165137Y0116496
X1165137Y0109410
X1164885Y0102323
X1165347Y0085584
X1167756Y0092734
X1165347Y0080384
X1165347Y0077784
X1165347Y0075184
X1165347Y0082984
X1102942Y0121735
X1102942Y0118335
X1092540Y0111223
X1225405Y-0082678
X1225405Y-0079278
X1081187Y-0069306
X1081187Y-0072706
X1222909Y-0078500
X1222909Y-0083456
X1083683Y-0068528
X1083683Y-0073484
X1228311Y-0086371
X1234592Y-0082584
X1234604Y-0085262
X1231351Y-0085176
X1234589Y-0087777
X1231336Y-0087691
X1234592Y-0079984
X1071988Y-0074890
X1075241Y-0074904
X1078281Y-0076099
X1078281Y-0065613
X1075256Y-0064293
X1072003Y-0064207
X1075241Y-0066808
X1071988Y-0066722
X1072000Y-0069400
X1072000Y-0072000
X1072003Y-0077405
X1075256Y-0077419
X1230761Y-0040228
X1081187Y-0082706
X1081187Y-0079306
X1230761Y-0043628
X1225405Y-0069278
X1230761Y-0030228
X1230761Y-0033628
X1225405Y-0072678
X1228265Y-0034406
X1228265Y-0029450
X1228265Y-0039450
X1228265Y-0044406
X1222909Y-0073456
X1222909Y-0068500
X1083683Y-0083484
X1083683Y-0078528
X1233667Y-0047421
X1233667Y-0036835
X1233667Y-0026535
X1239948Y-0043534
X1239960Y-0046212
X1236707Y-0046212
X1239945Y-0048727
X1236692Y-0048727
X1239960Y-0038044
X1239948Y-0040934
X1236707Y-0038030
X1239960Y-0027730
X1236707Y-0027730
X1239948Y-0030420
X1239945Y-0025215
X1236692Y-0025215
X1239945Y-0035529
X1236692Y-0035515
X1239948Y-0032920
X1228311Y-0075885
X1228311Y-0065585
X1234604Y-0077094
X1231351Y-0077080
X1234604Y-0066780
X1231351Y-0066780
X1234592Y-0069470
X1234589Y-0064265
X1231336Y-0064265
X1234589Y-0074579
X1231336Y-0074565
X1234592Y-0071970
X1072000Y-0080100
X1078281Y-0086399
X1075256Y-0087805
X1072003Y-0087805
X1072000Y-0082600
X1075241Y-0085290
X1071988Y-0085290
X1193330Y0005374
X1212232Y0003000
X1232232Y0003000
X1248216Y0004469
X1237204Y0110784
X1232204Y0110784
X1252097Y0095111
X1209542Y0100625
X1267247Y0095236
X1202561Y0097475
X1218204Y0103621
X1174818Y0095236
X1174768Y0099961
X1213915Y0112083
X1222383Y0060513
X1223068Y0094351
X1256466Y0106561
X1225243Y0060438
X1227017Y0094279
X1230924Y0086012
X1185753Y0104249
X1185753Y0107649
X1226065Y0086046
X1222511Y0085731
X1267497Y0090650
X1208103Y0076587
X1170447Y0090615
X1208103Y0072615
X1243503Y0102495
X1226261Y0119594
X1226261Y0116594
X1230924Y0094374
X1220151Y0088801
X1183682Y0077393
X1183682Y0079993
X1183682Y0074793
X1183682Y0082593
X1183682Y0085193
X1249647Y0121742
X1256947Y0111255
X1249647Y0118342
X1256701Y0097667
X1183726Y0092874
X1202492Y0106186
X1195557Y0103783
X1192007Y0098551
X1216021Y0080581
X1216008Y0068581
X1219783Y0055513
X1238230Y0116594
X1238230Y0119594
X1247847Y0097667
X1256947Y0114655
X1256307Y0103411
X1182995Y0102323
X1182995Y0109410
X1182995Y0116496
X1174995Y0109410
X1174995Y0116496
X1174861Y0103037
X1188278Y0094017
X1174535Y0053597
X1192007Y0101701
X1192278Y0094017
X1200287Y0094017
X1196278Y0094017
X1205355Y0080140
X1205355Y0076140
X1205355Y0084140
X1192643Y0044773
X1192643Y0024773
X1199557Y0103783
X1192406Y0115401
X1192406Y0110445
X1197398Y0115401
X1197398Y0110445
X1202808Y0117557
X1210724Y0103621
X1207800Y0117557
X1218730Y0117261
X1220126Y0091951
X1226261Y0113394
X1228910Y0110784
X1238479Y0102249
X1225041Y0097080
X1228097Y0060922
X1222933Y0055513
X1249577Y0044773
X1249577Y0024773
X1234479Y0102249
X1230479Y0102249
X1267499Y0109410
X1267247Y0102323
X1267709Y0085584
X1267709Y0080384
X1267709Y0077784
X1267709Y0075184
X1267709Y0082984
X1256898Y0053597
X1252047Y0116497
X1254547Y0116497
X1254547Y0109410
X1247247Y0116497
X1241496Y0109172
X1244496Y0109172
X1243503Y0106495
X1259247Y0109410
X1259247Y0102323
X1259247Y0116496
X1267499Y0116496
X1205304Y0121735
X1194902Y0111223
X1194902Y0114623
X1205304Y0118335
X1231761Y0124879
X1198938Y0148277
X1226695Y0124283
X1236783Y0124663
X1213708Y0152373
X1201558Y0143740
X1207753Y0192300
X1217660Y0178560
X1217723Y0172665
X1241764Y0125107
X1238127Y0138838
X1214608Y0143518
X1226550Y0186778
X1212265Y0171523
X1217070Y0190185
X1222353Y0157370
X1244278Y0148717
X1210121Y0141247
X1226469Y0208864
X1250378Y0143762
X1217840Y0200864
X1217929Y0212455
X1217863Y0207037
X1210268Y0198671
X1226437Y0192665
X1217550Y0183834
X1199399Y0177616
X1202653Y0168697
X1199419Y0215632
X1184086Y0215713
X1190658Y0211695
X1199419Y0213132
X1195716Y0213859
X1195716Y0211359
X1188158Y0208695
X1190958Y0208695
X1184086Y0208213
X1184086Y0213213
X1184086Y0210713
X1188158Y0211695
X1173630Y0215478
X1173630Y0212978
X1173630Y0210478
X1173630Y0207978
X1191680Y0184221
X1194297Y0184012
X1197478Y0181009
X1191472Y0181426
X1194683Y0181366
X1199980Y0172190
X1211795Y0192490
X1216858Y0152562
X1222110Y0219379
X1238118Y0216385
X1234318Y0218085
X1231518Y0218085
X1240831Y0216970
X1240831Y0219470
X1240831Y0221970
X1226469Y0204864
X1218536Y0186629
X1203741Y0191941
X1226437Y0168665
X1226437Y0176665
X1225102Y0161306
X1243237Y0142862
X1194091Y0141247
X1192475Y0170493
X1192475Y0167993
X1192475Y0162793
X1192475Y0165393
X1185375Y0162368
X1182775Y0162368
X1256947Y0125428
X1256947Y0128828
X1249647Y0132515
X1249647Y0135915
X1246907Y0210509
X1248680Y0206806
X1251180Y0206806
X1250844Y0201748
X1253844Y0202048
X1249407Y0210509
X1246826Y0195176
X1250844Y0199248
X1249326Y0195176
X1253844Y0199248
X1254326Y0195176
X1251826Y0195176
X1190319Y0147540
X1194902Y0125396
X1205880Y0221708
X1205750Y0206767
X1210880Y0221708
X1208380Y0221708
X1215230Y0221642
X1210750Y0206767
X1208250Y0206767
X1250307Y0140296
X1171586Y0137756
X1182995Y0137756
X1182995Y0123583
X1182995Y0130670
X1174995Y0123583
X1174995Y0130670
X1195748Y0222212
X1202449Y0206760
X1193836Y0188727
X1193969Y0191941
X1200469Y0184619
X1190319Y0151540
X1204801Y0152367
X1202808Y0136687
X1205899Y0146461
X1202808Y0131731
X1202808Y0122513
X1192406Y0129574
X1192406Y0124618
X1197398Y0124618
X1197398Y0129574
X1211184Y0180527
X1206501Y0180572
X1207800Y0136687
X1207800Y0131731
X1207800Y0122513
X1211139Y0185121
X1206501Y0185165
X1214907Y0192421
X1226469Y0221864
X1226469Y0216864
X1237827Y0206838
X1226469Y0212864
X1226469Y0200864
X1231639Y0203393
X1234139Y0203393
X1236398Y0201683
X1231779Y0195176
X1239579Y0195176
X1234279Y0195176
X1236398Y0198883
X1236779Y0195176
X1226437Y0172665
X1226437Y0180665
X1230651Y0134579
X1236504Y0133298
X1229195Y0130898
X1240327Y0206838
X1248031Y0150847
X1252047Y0137757
X1247247Y0137757
X1245143Y0141228
X1243237Y0146012
X1252047Y0130670
X1254547Y0130670
X1254547Y0123583
X1252047Y0123584
X1247247Y0130670
X1247247Y0123584
X1255779Y0213539
X1259247Y0137756
X1268719Y0137756
X1259247Y0123583
X1259247Y0130670
X1268724Y0130670
X1267671Y0124576
X1205304Y0132509
X1194902Y0128796
X1205304Y0135909
X1194335Y0265701
X1204438Y0266114
X1195970Y0281716
X1246808Y0256394
X1236845Y0249108
X1199422Y0265896
X1201911Y0281982
X1239465Y0244571
X1238293Y0317296
X1178045Y0312193
X1232197Y0316964
X1181706Y0310131
X1234904Y0316942
X1263328Y0309003
X1199663Y0256303
X1222738Y0228631
X1174929Y0319167
X1243858Y0228646
X1252854Y0227824
X1257444Y0230117
X1248599Y0230556
X1264088Y0320382
X1255161Y0244297
X1177035Y0257919
X1261659Y0318258
X1181379Y0316049
X1262665Y0302730
X1179901Y0306366
X1266962Y0302167
X1173559Y0304948
X1229028Y0311740
X1241205Y0303962
X1191153Y0270026
X1191153Y0267526
X1188653Y0270026
X1185853Y0270026
X1188653Y0267526
X1185853Y0267526
X1179459Y0264180
X1176959Y0264180
X1228226Y0248371
X1242815Y0232971
X1252941Y0246874
X1201113Y0315039
X1247584Y0242078
X1240897Y0226320
X1253460Y0238714
X1206995Y0231021
X1205295Y0224421
X1210184Y0270695
X1207684Y0270695
X1212984Y0270695
X1207684Y0268195
X1210184Y0268195
X1212984Y0268195
X1216644Y0265897
X1219144Y0265897
X1212487Y0248765
X1209987Y0248765
X1207487Y0248765
X1212546Y0236189
X1210046Y0236189
X1207546Y0236189
X1206995Y0228221
X1229252Y0314890
X1177176Y0293796
X1185190Y0288190
X1187690Y0285690
X1185190Y0285690
X1187690Y0288190
X1187738Y0248891
X1188036Y0236611
X1184086Y0223661
X1190593Y0226141
X1184086Y0226461
X1187793Y0226141
X1184086Y0228961
X1184086Y0231461
X1173630Y0231226
X1173630Y0228726
X1173630Y0223726
X1173630Y0226226
X1176858Y0306534
X1179676Y0293796
X1198716Y0290755
X1190490Y0288190
X1190490Y0285690
X1204693Y0279208
X1195663Y0256535
X1203663Y0256535
X1190238Y0248891
X1192738Y0248891
X1193036Y0236611
X1190536Y0236611
X1192055Y0231786
X1195748Y0224712
X1192055Y0229286
X1202716Y0290755
X1194716Y0290755
X1210787Y0288345
X1210787Y0290845
X1210787Y0293645
X1213287Y0288345
X1213287Y0290845
X1213287Y0293645
X1208797Y0281307
X1224186Y0316731
X1238055Y0303839
X1228226Y0252371
X1242708Y0253198
X1242789Y0236121
X1239823Y0238589
X1249999Y0247292
X1264481Y0300223
X1257460Y0238714
X1263500Y0336000
X1187996Y0331992
X1256000Y0340500
X1229438Y0332584
X1222601Y0369251
X1229122Y0369355
X1266616Y0322456
X1225755Y0369391
X1229922Y0324550
X1259991Y0340691
X1256000Y0338000
X1217177Y0369925
X1223431Y0397912
X1223431Y0377912
X1223431Y0381912
X1188598Y0381500
X1191748Y0392676
X1262500Y0330655
X1195800Y0324000
X1264215Y0333215
X1190127Y0324142
X1268659Y0385123
X1261231Y0399918
X1263484Y0385644
X1268067Y0406060
X1261764Y0391533
X1268328Y0416289
X1268328Y0418889
X1268328Y0421489
X1264336Y0412106
X1253245Y0422088
X1253245Y0419488
X1253245Y0416888
X1220723Y0324466
X1171445Y0422088
X1267944Y0371767
X1264659Y0377173
X1231506Y0353470
X1257000Y0333500
X1215776Y0331072
X1179761Y0336380
X1262075Y0324075
X1229942Y0347937
X1212173Y0391496
X1209872Y0382047
X1212173Y0409000
X1213173Y0386500
X1206693Y0384410
X1210173Y0403500
X1206531Y0393858
X1213173Y0377912
X1235589Y0348015
X1213261Y0397912
X1208173Y0398583
X1211892Y0339559
X1226436Y0324518
X1179184Y0403307
X1179184Y0410394
X1188598Y0390500
X1177036Y0334148
X1182911Y0336516
X1198248Y0381500
X1192500Y0322400
X1206673Y0403307
X1206673Y0410394
X1220985Y0342319
X1221337Y0332017
X1217139Y0324139
X1223431Y0401924
X1223431Y0405924
X1223431Y0409924
X1223431Y0385912
X1223431Y0389912
X1223431Y0393924
X1234656Y0353506
X1230077Y0336324
X1234100Y0322924
X1268659Y0377173
X1266219Y0374300
X1259500Y0330000
X1258925Y0324075
X1267836Y0449045
X1267493Y0454214
X1267540Y0459330
X1259223Y0454334
X1267843Y0473571
X1267843Y0476071
X1267843Y0478571
X1267843Y0481071
X1207480Y0451677
X1209980Y0454177
X1207480Y0454177
X1209980Y0451677
X1188739Y0446606
X1189122Y0442606
X1209184Y0460218
X1209184Y0463618
X1179184Y0446595
X1178083Y0442856
X1206626Y0438269
X1206626Y0440869
X1206626Y0435669
X1206626Y0430469
X1206626Y0433069
X1209426Y0438269
X1209426Y0440869
X1209426Y0435669
X1209426Y0430469
X1209426Y0433069
X1190046Y0463479
X1179184Y0453881
X1196403Y0458572
X1176138Y0458455
X1192957Y0435158
X1192702Y0440489
X1192686Y0449961
X1176699Y0451108
X1170878Y0488597
X1178178Y0470737
X1178178Y0481510
X1178178Y0514871
X1170878Y0477824
X1170878Y0521958
X1170878Y0474424
X1178178Y0511471
X1170878Y0518558
X1178178Y0484910
X1170878Y0491997
X1178178Y0467337
X1193000Y0444841
X1235166Y0511439
X1235166Y0481479
X1235166Y0467306
X1245568Y0477818
X1245568Y0474418
X1245568Y0491991
X1235166Y0470706
X1235166Y0514839
X1245568Y0518552
X1245568Y0521952
X1245568Y0488591
X1235166Y0484879
X1248064Y0473640
X1243072Y0473640
X1248064Y0478596
X1243072Y0478596
X1237662Y0485657
X1232670Y0485657
X1232670Y0480701
X1237662Y0480701
X1206489Y0472579
X1206489Y0486752
X1206489Y0479665
X1198689Y0472579
X1198689Y0479665
X1198689Y0486752
X1180578Y0472579
X1175778Y0472579
X1188520Y0475262
X1175778Y0486752
X1180578Y0486752
X1180578Y0479665
X1175778Y0479666
X1188520Y0482666
X1173278Y0472579
X1173278Y0486752
X1173278Y0479666
X1171255Y0456287
X1169173Y0427017
X1180578Y0465492
X1175778Y0465492
X1180402Y0462264
X1188378Y0466027
X1180578Y0451319
X1180578Y0458406
X1180118Y0432598
X1180118Y0435098
X1180118Y0437598
X1180118Y0440098
X1180118Y0430098
X1196420Y0470136
X1198655Y0460250
X1198689Y0465492
X1198610Y0454744
X1198590Y0443180
X1198552Y0452018
X1198346Y0439963
X1198305Y0437072
X1198489Y0433570
X1198468Y0430760
X1206489Y0465492
X1216630Y0445787
X1212680Y0445908
X1206489Y0458406
X1237662Y0471484
X1232670Y0471484
X1237662Y0466528
X1232670Y0466528
X1259223Y0458334
X1261623Y0447486
X1173278Y0516713
X1173278Y0493839
X1188378Y0509626
X1188993Y0522134
X1189071Y0514608
X1175778Y0516713
X1180578Y0509626
X1180578Y0516713
X1175778Y0509626
X1188336Y0495088
X1180578Y0493839
X1188520Y0489435
X1198689Y0516713
X1198689Y0509626
X1198689Y0493839
X1206489Y0509626
X1206489Y0516713
X1206489Y0493839
X1237662Y0510661
X1232670Y0510661
X1237662Y0515617
X1232670Y0515617
X1243072Y0517774
X1248064Y0517774
X1248064Y0492769
X1243072Y0492769
X1248064Y0487813
X1243072Y0487813
X1267843Y0493618
X1267843Y0491118
X1267843Y0488618
X1234941Y0550137
X1241629Y0550065
X1232149Y0550137
X1232833Y0539315
X1178178Y0589857
X1178178Y0575684
X1170878Y0611117
X1170878Y0600344
X1170878Y0614517
X1170878Y0582771
X1170878Y0568597
X1178178Y0561510
X1170878Y0586171
X1170878Y0536131
X1178178Y0525644
X1178178Y0579084
X1178178Y0564910
X1170878Y0596944
X1170878Y0571997
X1178178Y0593257
X1178178Y0607430
X1170878Y0532731
X1178178Y0529044
X1178178Y0604030
X1245568Y0571991
X1245568Y0586165
X1235166Y0525613
X1245568Y0614511
X1235166Y0561479
X1245568Y0582765
X1235166Y0589825
X1245568Y0600338
X1235166Y0529013
X1245568Y0532725
X1245568Y0611111
X1235166Y0579052
X1235166Y0607399
X1245568Y0536125
X1235166Y0603999
X1245568Y0568591
X1245568Y0596938
X1235166Y0593225
X1235166Y0564879
X1235166Y0575652
X1253087Y0553101
X1173278Y0616359
X1173278Y0595099
X1173278Y0602186
X1173278Y0573839
X1173278Y0588013
X1173278Y0580926
X1173278Y0566752
X1173278Y0530886
X1173278Y0537973
X1173278Y0523800
X1173278Y0609272
X1188759Y0565574
X1188378Y0559665
X1175778Y0559665
X1175778Y0566752
X1180578Y0566752
X1180578Y0559665
X1189636Y0529136
X1189475Y0535677
X1180578Y0530886
X1175778Y0530886
X1180578Y0537973
X1175778Y0523800
X1180578Y0523799
X1188505Y0616358
X1180578Y0609272
X1180578Y0616358
X1175778Y0609272
X1180578Y0595099
X1175778Y0595099
X1180578Y0602185
X1175778Y0602185
X1188406Y0574338
X1175778Y0573839
X1180578Y0573839
X1175778Y0588012
X1180578Y0588012
X1180578Y0580926
X1175778Y0580926
X1197550Y0532756
X1197629Y0525483
X1195149Y0537973
X1198753Y0608117
X1198689Y0573839
X1198539Y0579978
X1198689Y0566752
X1198689Y0559665
X1206489Y0609272
X1206489Y0616358
X1206489Y0595099
X1206489Y0602185
X1206489Y0573839
X1206489Y0588012
X1206489Y0580925
X1206489Y0559665
X1206489Y0566752
X1206489Y0530886
X1206489Y0537973
X1206489Y0523799
X1232670Y0529791
X1232670Y0524835
X1237662Y0529791
X1237662Y0524835
X1232670Y0608177
X1237662Y0608177
X1237662Y0594003
X1232670Y0594003
X1232670Y0603221
X1237662Y0603221
X1237662Y0579830
X1232670Y0574874
X1237662Y0574874
X1232670Y0589047
X1237662Y0589047
X1232670Y0579830
X1237662Y0560701
X1237662Y0565657
X1232670Y0560701
X1232670Y0565657
X1243072Y0531947
X1243072Y0536903
X1248064Y0536903
X1248064Y0531947
X1248064Y0522730
X1243072Y0522730
X1248064Y0610333
X1248064Y0615289
X1243072Y0615289
X1243072Y0610333
X1248064Y0596160
X1243072Y0596160
X1248064Y0601116
X1243072Y0601116
X1243072Y0581987
X1243072Y0586943
X1248064Y0586943
X1248064Y0581987
X1243072Y0572769
X1248064Y0572769
X1243072Y0567813
X1241752Y0564843
X1248064Y0567813
X1169256Y0694983
X1170465Y0677836
X1238695Y0627313
X1238034Y0629961
X1237500Y0632405
X1235292Y0622912
X1235930Y0626229
X1170603Y0715281
X1173122Y0802759
X1173034Y0765060
X1171934Y0733857
X1169697Y0791935
X1176500Y0784933
X1174595Y0771744
X1169266Y0800799
X1173697Y0791911
X1177566Y0778539
X1177745Y0771744
X1198997Y0790610
X1185058Y0883475
X1180239Y0868430
X1181654Y0894671
X1174461Y0914515
X1192431Y0868620
X1184340Y0851072
X1190968Y0848703
X1190213Y0856816
X1183012Y0856553
X1185516Y0844248
X1190210Y0900909
X1192367Y0903785
X1187151Y0921000
X1192152Y0884399
X1179727Y0886197
X1179858Y0883455
X1187431Y0868340
X1178480Y0915220
X1176577Y0885974
X1177775Y0894053
X1183431Y0868340
X1186742Y0855466
X1187703Y0849734
X1190062Y0844378
X1192990Y0914873
X1245400Y1003700
X1248106Y1004700
X1252500Y1014288
X1201800Y1019431
X1195757Y0988131
X1202028Y0998349
X1196300Y0998600
X1197173Y0940645
X1189219Y0940703
X1200008Y1011161
X1203419Y1011161
X1246000Y1014800
X1199700Y1013661
X1193219Y0940703
X1191151Y0936296
X1196352Y0951033
X1182000Y0936500
X1191219Y0967757
X1198644Y0985289
X1191928Y0987314
X1187200Y0963400
X1188431Y0936568
X1178000Y0936500
X1202268Y1013551
X1204919Y1021860
X1198845Y0998504
X1201794Y0985289
X1199615Y0950670
X1195118Y0936296
X1249200Y1014000
X1246800Y1001600
X1252148Y1026223
X1246300Y1027800
X1248721Y1025864
X1253056Y1194917
X1260800Y1191096
X1255628Y1188345
X1250928Y1142828
X1255439Y1172008
X1263921Y1134729
X1266718Y1142666
X1268593Y1157544
X1267104Y1167768
X1262298Y1180175
X1262605Y1187215
X1255296Y1196056
X1261538Y1199814
X1254200Y1146600
X1249363Y1166065
X1256218Y1175987
X1267921Y1134729
X1266113Y1219895
X1263449Y1217228
X1264575Y1201043
X1268571Y1201043
X1253424Y1138130
X1249363Y1173065
X1260539Y1134729
X1251802Y1186071
X1263873Y1148000
X1258736Y1188223
X1264573Y1193019
X1268573Y1193019
X1266709Y1160168
X1180513Y1408495
X1177113Y1408495
X1180513Y1348187
X1177113Y1348187
X1177113Y1396583
X1180513Y1396583
X1180513Y1360099
X1177113Y1360099
X1245966Y1408495
X1242566Y1408495
X1258206Y1384297
X1254806Y1384297
X1267046Y1360099
X1245966Y1360099
X1267046Y1408495
X1233726Y1384297
X1242566Y1360099
X1230326Y1384297
X1254806Y1408495
X1267046Y1384297
X1233726Y1360099
X1258206Y1360099
X1245966Y1384297
X1254806Y1360099
X1258206Y1408495
X1230326Y1360099
X1242566Y1384297
X1233726Y1348187
X1242566Y1396583
X1230326Y1348187
X1233726Y1372385
X1258206Y1348187
X1254806Y1396583
X1267046Y1372385
X1258206Y1396583
X1245966Y1372385
X1254806Y1348187
X1180513Y1372385
X1177113Y1372385
X1242566Y1372385
X1180513Y1384297
X1176335Y1410991
X1176335Y1405999
X1181291Y1410991
X1181291Y1405999
X1176335Y1394087
X1176335Y1399079
X1176335Y1386793
X1181291Y1394087
X1181291Y1399079
X1181291Y1386793
X1176335Y1374881
X1176335Y1381801
X1176335Y1369889
X1181291Y1374881
X1181291Y1381801
X1181291Y1369889
X1176335Y1357603
X1176335Y1362595
X1181291Y1357603
X1181291Y1362595
X1176335Y1350683
X1176335Y1345691
X1181291Y1345691
X1181291Y1350683
X1169051Y1405999
X1169051Y1410991
X1169051Y1386793
X1169051Y1399079
X1169051Y1393993
X1169051Y1369889
X1169051Y1374881
X1169051Y1381801
X1169051Y1362595
X1169051Y1357603
X1169051Y1350683
X1169051Y1345597
X1258984Y1410991
X1258984Y1405999
X1266268Y1405999
X1266268Y1410991
X1258984Y1399079
X1258984Y1386793
X1258984Y1394087
X1266268Y1386793
X1266268Y1394087
X1266268Y1399079
X1258984Y1374881
X1258984Y1369889
X1258984Y1381801
X1266268Y1381801
X1266268Y1374881
X1266268Y1369889
X1258984Y1357603
X1258984Y1362595
X1266268Y1357603
X1266268Y1362595
X1258984Y1345691
X1258984Y1350683
X1266268Y1350683
X1266268Y1345691
X1246744Y1405999
X1246744Y1410991
X1241788Y1405999
X1241788Y1410991
X1254028Y1405999
X1254028Y1410991
X1246744Y1386793
X1246744Y1399079
X1246744Y1393993
X1241788Y1386793
X1241788Y1393993
X1241788Y1399079
X1254028Y1394087
X1254028Y1399079
X1254028Y1386793
X1246744Y1381801
X1246744Y1369795
X1246744Y1374881
X1241788Y1381801
X1241788Y1369795
X1241788Y1374881
X1254028Y1369889
X1254028Y1374881
X1254028Y1381801
X1246744Y1357603
X1246744Y1362595
X1241788Y1357603
X1241788Y1362595
X1254028Y1362595
X1254028Y1357603
X1246744Y1350683
X1246744Y1345691
X1241788Y1350683
X1241788Y1345691
X1254028Y1345691
X1254028Y1350683
X1234504Y1386793
X1229548Y1386793
X1234504Y1381801
X1234504Y1374881
X1234504Y1369889
X1229548Y1381801
X1229548Y1374881
X1229548Y1369889
X1234504Y1362595
X1234504Y1357603
X1229548Y1357603
X1229548Y1362595
X1234504Y1350683
X1234504Y1345691
X1229548Y1345691
X1229548Y1350683
X1258206Y1372385
X1177113Y1384297
X1254806Y1372385
X1230326Y1372385
X1245966Y1396583
X1242566Y1348187
X1245966Y1348187
X1267046Y1396583
X1267046Y1348187
X1253904Y1519645
X1262985Y1519459
X1172944Y1496221
X1172944Y1485598
X1172944Y1491490
X1172944Y1476136
X1172944Y1480867
X1172944Y1470244
X1172944Y1460782
X1172944Y1465513
X1172944Y1516307
X1172944Y1511576
X1172944Y1500952
X1172944Y1506845
X1181605Y1496621
X1181605Y1491890
X1181605Y1487159
X1181605Y1481267
X1181605Y1476536
X1181605Y1471805
X1181605Y1461182
X1181605Y1456451
X1181605Y1465913
X1181605Y1511976
X1181605Y1502514
X1181605Y1507245
X1190267Y1516307
X1198928Y1511977
X1198928Y1502515
X1198928Y1507246
X1190267Y1511576
X1190267Y1500952
X1190267Y1506845
X1190267Y1491490
X1198928Y1496622
X1198928Y1487160
X1198928Y1491891
X1190267Y1496221
X1190267Y1485598
X1198928Y1471806
X1198928Y1476537
X1190267Y1480867
X1190267Y1470244
X1190267Y1476136
X1198928Y1481268
X1198928Y1461183
X1198928Y1456452
X1198928Y1465914
X1190267Y1460782
X1190267Y1465513
X1262891Y1535334
X1250434Y1535334
X1262891Y1527334
X1267333Y1531334
X1267183Y1539334
X1249894Y1527805
X1254275Y1531334
X1254275Y1539334
X1245900Y1528000
X1263242Y1523458
X1260260Y1546500
X1172944Y1587960
X1172944Y1593853
X1172944Y1583229
X1172944Y1572606
X1172944Y1578498
X1172944Y1567875
X1172944Y1563144
X1172944Y1618669
X1172944Y1613938
X1172944Y1609207
X1172944Y1603315
X1172944Y1598584
X1181605Y1594253
X1181605Y1589522
X1181605Y1583629
X1181605Y1578898
X1181605Y1574167
X1181605Y1568275
X1181605Y1563544
X1181605Y1558813
X1181605Y1614338
X1181605Y1604876
X1181605Y1609607
X1181605Y1598984
X1198928Y1563544
X1190267Y1563144
X1198928Y1558813
X1198928Y1614338
X1190267Y1618669
X1190267Y1613938
X1198928Y1604876
X1198928Y1598984
X1198928Y1609607
X1190267Y1603315
X1190267Y1598584
X1190267Y1609207
X1198928Y1589522
X1198928Y1594253
X1190267Y1587960
X1190267Y1593853
X1198928Y1583629
X1190267Y1583229
X1198928Y1574167
X1198928Y1578898
X1190267Y1572606
X1190267Y1578498
X1198928Y1568275
X1190267Y1567875
X1172000Y1644980
X1192000Y1644980
X1212000Y1644980
X1232000Y1644980
X1292000Y1644980
X1312000Y1644980
X1332000Y1644980
X1352000Y1644980
X1302866Y1614338
X1302866Y1604876
X1302866Y1598984
X1302866Y1609607
X1302866Y1583629
X1302866Y1589522
X1302866Y1594253
X1302866Y1568275
X1302866Y1574167
X1302866Y1578898
X1302866Y1563544
X1302866Y1558813
X1311527Y1572606
X1311527Y1578498
X1311527Y1567875
X1311527Y1563144
X1311527Y1618669
X1311527Y1613938
X1311527Y1603315
X1311527Y1598584
X1311527Y1609207
X1311527Y1587960
X1311527Y1593853
X1311527Y1583229
X1320189Y1568275
X1328850Y1572606
X1328850Y1578498
X1320189Y1578898
X1320189Y1574167
X1328850Y1567875
X1328850Y1563144
X1320189Y1563544
X1320189Y1558813
X1320189Y1614338
X1328850Y1618669
X1328850Y1613938
X1328850Y1598584
X1328850Y1609207
X1320189Y1598984
X1320189Y1604876
X1320189Y1609607
X1328850Y1603315
X1320189Y1583629
X1328850Y1587960
X1328850Y1593853
X1320189Y1594253
X1320189Y1589522
X1328850Y1583229
X1346173Y1567875
X1337512Y1568275
X1346173Y1572606
X1346173Y1578498
X1337512Y1578898
X1337512Y1574167
X1346173Y1563144
X1337512Y1563544
X1337512Y1558813
X1346173Y1618669
X1346173Y1613938
X1337512Y1614338
X1346173Y1603315
X1346173Y1598584
X1346173Y1609207
X1337512Y1598984
X1337512Y1604876
X1337512Y1609607
X1346173Y1587960
X1346173Y1593853
X1337512Y1594253
X1337512Y1589522
X1346173Y1583229
X1337512Y1583629
X1363496Y1578498
X1363496Y1567875
X1354834Y1578898
X1354834Y1574167
X1354834Y1568275
X1363496Y1563144
X1354834Y1563544
X1354834Y1558813
X1363496Y1618669
X1363496Y1613938
X1354834Y1614338
X1363496Y1603315
X1363496Y1598584
X1363496Y1609207
X1354834Y1598984
X1354834Y1604876
X1354834Y1609607
X1363496Y1587960
X1363496Y1593853
X1363496Y1583229
X1354834Y1594253
X1354834Y1589522
X1354834Y1583629
X1363496Y1572606
X1302866Y1511976
X1302866Y1502514
X1302866Y1507245
X1302866Y1496621
X1302866Y1487159
X1302866Y1491890
X1302866Y1481267
X1302866Y1471805
X1302866Y1476536
X1302866Y1465913
X1302866Y1456451
X1302866Y1461182
X1311527Y1470244
X1311527Y1476136
X1311527Y1480867
X1311527Y1460782
X1311527Y1465513
X1311527Y1516307
X1311527Y1511576
X1311527Y1500952
X1311527Y1506845
X1311527Y1496221
X1311527Y1485598
X1311527Y1491490
X1320189Y1476536
X1320189Y1471805
X1328850Y1480867
X1320189Y1481267
X1328850Y1470244
X1328850Y1476136
X1320189Y1461182
X1320189Y1456451
X1320189Y1465913
X1328850Y1460782
X1328850Y1465513
X1328850Y1516307
X1320189Y1507245
X1320189Y1511976
X1328850Y1511576
X1328850Y1500952
X1328850Y1506845
X1320189Y1502514
X1320189Y1491890
X1320189Y1487159
X1328850Y1496221
X1320189Y1496621
X1328850Y1485598
X1328850Y1491490
X1337512Y1476536
X1337512Y1471805
X1346173Y1480867
X1337512Y1481267
X1346173Y1470244
X1346173Y1476136
X1337512Y1456451
X1337512Y1465913
X1346173Y1460782
X1346173Y1465513
X1337512Y1461182
X1346173Y1516307
X1337512Y1511976
X1346173Y1511576
X1346173Y1500952
X1346173Y1506845
X1337512Y1502514
X1337512Y1507245
X1346173Y1496221
X1337512Y1496621
X1337512Y1491890
X1337512Y1487159
X1346173Y1491490
X1346173Y1485598
X1354834Y1476536
X1354834Y1471805
X1363496Y1480867
X1363496Y1470244
X1363496Y1476136
X1354834Y1481267
X1363496Y1460782
X1363496Y1465513
X1354834Y1461182
X1354834Y1456451
X1354834Y1465913
X1363496Y1516307
X1354834Y1507245
X1363496Y1500952
X1363496Y1506845
X1363496Y1511576
X1354834Y1511976
X1354834Y1502514
X1354834Y1491890
X1363496Y1496221
X1363496Y1491490
X1363496Y1485598
X1354834Y1496621
X1354834Y1487159
X1279286Y1384297
X1282686Y1384297
X1294926Y1360099
X1270446Y1360099
X1270446Y1408495
X1291526Y1360099
X1294926Y1384297
X1343886Y1384297
X1331646Y1360099
X1340486Y1384297
X1303766Y1408495
X1282686Y1408495
X1352726Y1360099
X1307166Y1408495
X1328246Y1408495
X1282686Y1360099
X1328246Y1360099
X1291526Y1384297
X1356126Y1408495
X1279286Y1360099
X1303766Y1360099
X1319406Y1384297
X1279286Y1408495
X1316006Y1384297
X1352726Y1408495
X1270446Y1384297
X1356126Y1360099
X1307166Y1360099
X1331646Y1408495
X1328246Y1396583
X1282686Y1372385
X1352726Y1396583
X1294926Y1348187
X1352726Y1372385
X1319406Y1372385
X1294926Y1372385
X1331646Y1396583
X1352726Y1348187
X1282686Y1396583
X1331646Y1348187
X1303766Y1348187
X1307166Y1396583
X1291526Y1372385
X1307166Y1348187
X1279286Y1396583
X1328246Y1348187
X1279286Y1348187
X1356126Y1396583
X1282686Y1348187
X1340486Y1372385
X1356126Y1348187
X1343886Y1372385
X1270446Y1372385
X1303766Y1396583
X1328246Y1384297
X1307166Y1384297
X1356126Y1384297
X1319406Y1408495
X1316006Y1408495
X1294926Y1408495
X1340486Y1408495
X1316006Y1360099
X1291526Y1408495
X1340486Y1360099
X1343886Y1408495
X1356904Y1374881
X1356904Y1405999
X1356904Y1410991
X1356904Y1399079
X1356904Y1394087
X1356904Y1386793
X1356904Y1369889
X1356904Y1381801
X1356904Y1362595
X1356904Y1357603
X1356904Y1350683
X1356904Y1345691
X1344664Y1405999
X1344664Y1410991
X1339708Y1405999
X1339708Y1410991
X1351948Y1405999
X1351948Y1410991
X1344664Y1386793
X1344664Y1399079
X1344664Y1393993
X1339708Y1386793
X1339708Y1393993
X1339708Y1399079
X1351948Y1399079
X1351948Y1394087
X1351948Y1386793
X1344664Y1381801
X1344664Y1374881
X1344664Y1369889
X1339708Y1369889
X1339708Y1381801
X1339708Y1374881
X1351948Y1369889
X1351948Y1381801
X1351948Y1374881
X1344664Y1357603
X1344664Y1362595
X1339708Y1357603
X1339708Y1362595
X1351948Y1362595
X1351948Y1357603
X1344664Y1350683
X1344664Y1345597
X1339708Y1350683
X1339708Y1345597
X1351948Y1345691
X1351948Y1350683
X1320184Y1405999
X1320184Y1410991
X1327468Y1405999
X1327468Y1410991
X1332424Y1405999
X1332424Y1410991
X1320184Y1386793
X1320184Y1394087
X1320184Y1399079
X1327468Y1399079
X1327468Y1394087
X1327468Y1386793
X1332424Y1399079
X1332424Y1394087
X1332424Y1386793
X1320184Y1369889
X1320184Y1374881
X1320184Y1381801
X1327468Y1374881
X1327468Y1369889
X1327468Y1381801
X1332424Y1374881
X1332424Y1369889
X1332424Y1381801
X1320184Y1357603
X1320184Y1362595
X1327468Y1362595
X1327468Y1357603
X1332424Y1357603
X1332424Y1362595
X1320184Y1345691
X1320184Y1350683
X1327468Y1345691
X1327468Y1350683
X1332424Y1350683
X1332424Y1345691
X1307944Y1405999
X1307944Y1410991
X1315228Y1405999
X1315228Y1410991
X1307944Y1394087
X1307944Y1399079
X1307944Y1386793
X1315228Y1386793
X1315228Y1394087
X1315228Y1399079
X1307944Y1369889
X1307944Y1381801
X1307944Y1374881
X1315228Y1374881
X1315228Y1369889
X1315228Y1381801
X1307944Y1362595
X1307944Y1357603
X1315228Y1357603
X1315228Y1362595
X1307944Y1345691
X1307944Y1350683
X1315228Y1350683
X1315228Y1345691
X1295704Y1405999
X1295704Y1410991
X1290748Y1405999
X1290748Y1410991
X1302988Y1405999
X1302988Y1410991
X1295704Y1386793
X1295704Y1399079
X1295704Y1394087
X1290748Y1386793
X1290748Y1394087
X1290748Y1399079
X1302988Y1394087
X1302988Y1399079
X1302988Y1386793
X1295704Y1369889
X1295704Y1374881
X1295704Y1381801
X1290748Y1374881
X1290748Y1381801
X1290748Y1369889
X1302988Y1369889
X1302988Y1381801
X1302988Y1374881
X1295704Y1357603
X1295704Y1362595
X1290748Y1357603
X1290748Y1362595
X1302988Y1357603
X1302988Y1362595
X1295704Y1345691
X1295704Y1350683
X1290748Y1345691
X1290748Y1350683
X1302988Y1350683
X1302988Y1345691
X1271224Y1405999
X1271224Y1410991
X1278508Y1405999
X1278508Y1410991
X1283464Y1405999
X1283464Y1410991
X1271224Y1386793
X1271224Y1399079
X1271224Y1394087
X1278508Y1394087
X1278508Y1399079
X1278508Y1386793
X1283464Y1394087
X1283464Y1399079
X1283464Y1386793
X1271224Y1381801
X1271224Y1374881
X1271224Y1369889
X1278508Y1374881
X1278508Y1369889
X1278508Y1381801
X1283464Y1374881
X1283464Y1369889
X1283464Y1381801
X1271224Y1357603
X1271224Y1362595
X1278508Y1362595
X1278508Y1357603
X1283464Y1357603
X1283464Y1362595
X1271224Y1350683
X1271224Y1345691
X1278508Y1350683
X1278508Y1345691
X1283464Y1350683
X1283464Y1345691
X1343886Y1396583
X1340486Y1348187
X1328246Y1372385
X1356126Y1372385
X1270446Y1396583
X1291526Y1396583
X1331646Y1372385
X1319406Y1360099
X1343886Y1348187
X1343886Y1360099
X1303766Y1384297
X1352726Y1384297
X1291526Y1348187
X1331646Y1384297
X1316006Y1348187
X1270446Y1348187
X1340486Y1396583
X1303766Y1372385
X1294926Y1396583
X1316006Y1396583
X1279286Y1372385
X1307166Y1372385
X1319406Y1396583
X1319406Y1348187
X1316006Y1372385
X1318287Y1291381
X1318287Y1295381
X1272235Y1226016
X1303900Y1288000
X1310773Y1282411
X1308107Y1283395
X1269388Y1223170
X1274446Y1228226
X1319237Y1241428
X1315237Y1241428
X1319237Y1225428
X1319237Y1229428
X1319237Y1233428
X1319237Y1237428
X1315237Y1225428
X1315237Y1229428
X1315237Y1233428
X1315237Y1237428
X1311237Y1225428
X1311237Y1229428
X1311237Y1233428
X1335237Y1245428
X1331237Y1241428
X1331237Y1245428
X1327237Y1241428
X1327237Y1245428
X1323237Y1225428
X1323237Y1229428
X1323237Y1233428
X1323237Y1237428
X1335237Y1225428
X1335237Y1229428
X1335237Y1233428
X1335237Y1237428
X1331237Y1225428
X1331237Y1229428
X1331237Y1233428
X1331237Y1237428
X1327237Y1225428
X1327237Y1229428
X1327237Y1233428
X1327237Y1237428
X1323237Y1241428
X1323237Y1245428
X1335237Y1241428
X1339237Y1241428
X1339237Y1245428
X1343237Y1245428
X1343237Y1241428
X1347237Y1241428
X1347237Y1245428
X1339237Y1225428
X1339237Y1229428
X1339237Y1233428
X1339237Y1237428
X1343237Y1237428
X1343237Y1233428
X1343237Y1229428
X1347237Y1229428
X1347237Y1233428
X1347237Y1237428
X1333876Y1260160
X1333876Y1257160
X1339876Y1260160
X1342876Y1260160
X1336876Y1257160
X1336876Y1260160
X1351876Y1257160
X1351876Y1260160
X1348876Y1257160
X1348876Y1260160
X1345876Y1257160
X1345876Y1260160
X1342876Y1257160
X1339876Y1257160
X1366876Y1257160
X1366876Y1260160
X1354876Y1257160
X1357876Y1257160
X1360876Y1257160
X1360876Y1260160
X1357876Y1260160
X1354876Y1260160
X1363876Y1257160
X1363876Y1260160
X1307167Y1245696
X1308276Y1276446
X1357070Y1297498
X1351670Y1297498
X1346270Y1297498
X1340870Y1297498
X1335470Y1297498
X1330070Y1297498
X1280575Y1200969
X1275794Y1134729
X1275050Y1157404
X1272123Y1167768
X1280395Y1180235
X1280602Y1185238
X1275965Y1187232
X1271256Y1185205
X1276575Y1201039
X1272541Y1201043
X1271921Y1134729
X1280694Y1208993
X1271246Y1178240
X1280306Y1170767
X1295815Y1124943
X1351149Y1158200
X1315237Y1221428
X1311237Y1221428
X1318178Y1190121
X1318178Y1192621
X1317437Y1160834
X1319237Y1221428
X1323237Y1221428
X1335237Y1221428
X1331237Y1221428
X1327237Y1221428
X1331643Y1190121
X1331643Y1192621
X1323135Y1174884
X1325635Y1174884
X1320493Y1179209
X1320493Y1181709
X1320493Y1184209
X1320493Y1186709
X1334793Y1186921
X1334793Y1184421
X1334793Y1181921
X1334793Y1179421
X1323135Y1169884
X1323135Y1167384
X1323135Y1164884
X1323135Y1162384
X1323135Y1172384
X1325635Y1169884
X1325635Y1167384
X1325635Y1164884
X1325635Y1162384
X1325635Y1172384
X1339237Y1221428
X1343237Y1221428
X1347237Y1221428
X1345108Y1192621
X1345108Y1190121
X1337108Y1190121
X1337108Y1192621
X1350963Y1174884
X1341405Y1174884
X1343905Y1174884
X1347423Y1179209
X1347423Y1181709
X1347423Y1184209
X1347423Y1186709
X1350963Y1162384
X1350963Y1164884
X1350963Y1167384
X1350963Y1169884
X1350963Y1172384
X1341405Y1162384
X1341405Y1164884
X1341405Y1167384
X1341405Y1169884
X1341405Y1172384
X1343905Y1172384
X1343905Y1169884
X1343905Y1167384
X1343905Y1164884
X1343905Y1162384
X1353463Y1174884
X1361723Y1186921
X1361723Y1184421
X1361723Y1181921
X1361723Y1179421
X1353463Y1162384
X1353463Y1164884
X1353463Y1167384
X1353463Y1169884
X1353463Y1172384
X1364038Y1192621
X1364038Y1190121
X1343725Y1128738
X1347300Y1128332
X1282830Y1150087
X1282421Y1137129
X1275788Y1124088
X1269876Y1132319
X1284198Y1218754
X1275032Y1209589
X1279402Y1213958
X1277108Y1211664
X1272573Y1193019
X1280573Y1193019
X1276573Y1193019
X1280306Y1162817
X1272120Y1159455
X1282830Y1146937
X1273865Y1132497
X1318178Y1200821
X1318178Y1198321
X1317437Y1152684
X1334793Y1212117
X1334793Y1209617
X1334793Y1207117
X1320493Y1209405
X1320493Y1211905
X1320493Y1206905
X1331643Y1198321
X1331643Y1200821
X1334793Y1204617
X1320493Y1204405
X1326269Y1155213
X1326269Y1152713
X1320279Y1144435
X1320279Y1146935
X1320279Y1141935
X1323405Y1125801
X1331805Y1125801
X1334305Y1125801
X1321805Y1129301
X1324305Y1129301
X1326805Y1129301
X1329305Y1129301
X1331805Y1129301
X1334305Y1129301
X1320279Y1139435
X1320279Y1136935
X1320279Y1134435
X1320279Y1131935
X1323405Y1123101
X1331405Y1123101
X1333905Y1123101
X1352407Y1139435
X1352407Y1136935
X1352407Y1134435
X1352407Y1131935
X1349907Y1139435
X1349907Y1136935
X1349907Y1134435
X1347423Y1206905
X1347423Y1211905
X1347423Y1209405
X1345108Y1198321
X1345108Y1200821
X1337108Y1198321
X1337108Y1200821
X1347423Y1204405
X1351405Y1152402
X1351405Y1154902
X1336669Y1155213
X1336669Y1152713
X1352407Y1144435
X1352407Y1146935
X1352407Y1141935
X1349907Y1144435
X1349907Y1146935
X1349907Y1141935
X1343505Y1141935
X1343505Y1144435
X1343505Y1146935
X1349907Y1131935
X1343505Y1131935
X1343505Y1139435
X1343505Y1134435
X1343505Y1136935
X1336805Y1125801
X1339305Y1125801
X1336805Y1129301
X1339305Y1129301
X1364038Y1200821
X1364038Y1198321
X1361723Y1204617
X1366797Y1155213
X1366797Y1152713
X1357397Y1152713
X1357397Y1155213
X1363933Y1129301
X1361433Y1129301
X1358933Y1129301
X1356433Y1129301
X1353933Y1129301
X1366433Y1125801
X1363933Y1125801
X1355533Y1125801
X1366433Y1129301
X1366033Y1123101
X1363533Y1123101
X1355533Y1123101
X1361723Y1207117
X1361723Y1209617
X1361723Y1212117
X1368933Y1129301
X1368933Y1125801
X1345650Y1118396
X1364797Y1106867
X1332669Y1106867
X1363290Y1104792
X1331162Y1104792
X1299717Y1024136
X1339169Y1106897
X1322773Y1040599
X1320549Y1037876
X1306385Y1036646
X1312873Y1036543
X1315756Y1039344
X1315606Y1042825
X1295893Y1122182
X1333974Y1033483
X1339234Y1101917
X1357265Y1026266
X1323021Y1093956
X1323021Y1090956
X1323163Y1082501
X1323189Y1087705
X1323189Y1085205
X1329189Y1088205
X1326471Y1091227
X1326189Y1088205
X1329189Y1085205
X1329163Y1082501
X1326189Y1085205
X1326163Y1082501
X1358382Y1113648
X1360882Y1113648
X1355533Y1118801
X1355533Y1116101
X1354082Y1113648
X1353297Y1110597
X1351097Y1109397
X1351197Y1112397
X1348997Y1110897
X1348997Y1113797
X1323405Y1116101
X1323405Y1118801
X1328754Y1113648
X1326254Y1113648
X1321954Y1113648
X1321169Y1110597
X1316869Y1110897
X1316869Y1113797
X1318969Y1109397
X1319069Y1112397
X1353197Y1107997
X1350418Y1093088
X1348997Y1107997
X1321069Y1107997
X1316869Y1107997
X1347552Y1081816
X1350418Y1090288
X1347552Y1084316
X1347552Y1086816
X1345052Y1086816
X1345052Y1084316
X1345052Y1081816
X1347552Y1089316
X1347552Y1091816
X1334956Y1105552
X1366265Y1039880
X1367084Y1105552
X1344241Y1106298
X1345650Y1115896
X1337514Y1104335
X1341984Y1110092
X1365049Y1028416
X1340665Y1026123
X1343465Y1026123
X1340665Y1028923
X1343465Y1028923
X1357265Y1034266
X1324221Y1060697
X1321721Y1060697
X1329221Y1060697
X1326721Y1060697
X1326721Y1058097
X1324221Y1058097
X1321721Y1058097
X1329221Y1058097
X1319221Y1060697
X1319221Y1058097
X1313089Y1097278
X1310589Y1097278
X1313459Y1081599
X1344880Y1060498
X1344880Y1062998
X1347380Y1062998
X1347380Y1060498
X1344880Y1057998
X1344880Y1055498
X1347380Y1055498
X1347380Y1057998
X1331890Y1051919
X1319326Y1040723
X1309937Y1037038
X1304664Y1023462
X1334161Y1098518
X1331359Y1098898
X1334835Y1119422
X1334835Y1113822
X1332355Y1119422
X1332355Y1113822
X1337315Y1119422
X1337315Y1113822
X1339349Y1098767
X1364483Y1113822
X1364483Y1119422
X1366963Y1113822
X1366963Y1119422
X1361037Y1098428
X1366289Y1098518
X1364418Y1093068
X1364418Y1090568
X1357265Y1030266
X1357265Y1022766
X1363941Y1047047
X1364237Y1043140
X1290792Y0961363
X1346500Y0925500
X1319554Y0925585
X1297852Y1014475
X1292836Y0975244
X1283493Y0929858
X1292631Y0979845
X1272661Y0929858
X1279493Y0929858
X1275493Y0929858
X1307561Y0986951
X1307707Y0979870
X1326500Y0925500
X1322427Y0988221
X1334500Y0925500
X1327267Y0988271
X1326500Y0943500
X1323000Y0934075
X1329199Y0933825
X1325550Y0960445
X1342500Y0925500
X1336000Y0943500
X1338500Y0925500
X1330500Y0925500
X1346500Y0930500
X1333132Y0933781
X1324735Y0989966
X1311325Y0928918
X1362500Y0925500
X1329834Y0988132
X1321256Y0943815
X1342500Y0930500
X1319874Y0989856
X1350500Y0925500
X1332404Y0988215
X1300500Y0960000
X1350500Y0930500
X1358500Y0925500
X1358500Y0930500
X1354500Y0930500
X1337514Y0988259
X1366500Y0925500
X1332500Y0961500
X1334909Y0990340
X1312575Y0943974
X1315441Y0960000
X1354500Y0925500
X1311000Y0970124
X1313867Y0925605
X1366500Y0930500
X1329503Y0991088
X1362500Y0930500
X1338500Y0930500
X1289547Y0941000
X1281733Y0949475
X1295453Y0928047
X1349848Y0936755
X1297558Y0970216
X1292500Y0928000
X1313152Y0936605
X1300882Y0937144
X1304949Y0928546
X1361948Y0943603
X1357948Y0938842
X1345948Y0943603
X1365948Y0939475
X1353948Y0943603
X1307000Y0960500
X1281400Y0940256
X1365314Y1021793
X1317053Y0988111
X1317254Y0990777
X1361265Y1019766
X1289500Y0949500
X1367444Y1003763
X1324000Y0930925
X1333425Y0930925
X1315779Y0943743
X1306500Y0936500
X1309103Y0936559
X1302500Y0939500
X1296500Y0961500
X1311000Y0961500
X1321028Y0961749
X1300500Y0970187
X1307000Y0970000
X1327000Y0969500
X1332000Y0969500
X1335343Y0961727
X1357765Y1019766
X1364765Y1004766
X1341820Y0947407
X1323554Y0967623
X1284021Y0940008
X1295453Y0940953
X1298090Y0940852
X1289547Y0928047
X1307580Y0990314
X1303907Y0960093
X1318375Y0943951
X1316893Y0925603
X1321104Y0964398
X1328457Y0959986
X1367884Y1018825
X1366493Y1000828
X1363905Y1000855
X1363173Y0994483
X1270892Y0856343
X1310535Y0870775
X1282285Y0865602
X1313756Y0842470
X1323205Y0842470
X1316906Y0836170
X1332654Y0851918
X1326355Y0851918
X1313756Y0848769
X1283025Y0848305
X1323205Y0867665
X1364148Y0848769
X1367298Y0839320
X1367298Y0836170
X1364148Y0833021
X1359425Y0829000
X1357849Y0842470
X1354699Y0886562
X1329504Y0883413
X1323204Y0889713
X1320055Y0889712
X1274396Y0866896
X1335803Y0886562
X1351511Y0900000
X1367298Y0886562
X1364148Y0883413
X1302000Y0917000
X1319500Y0905000
X1281777Y0823500
X1331078Y0900500
X1270586Y0905324
X1332654Y0886562
X1283494Y0907176
X1329504Y0873964
X1332654Y0873964
X1305740Y0877534
X1269629Y0848124
X1323204Y0855067
X1316906Y0858218
X1313756Y0855066
X1296466Y0899610
X1298966Y0899610
X1320055Y0883413
X1335803Y0870814
X1335803Y0873964
X1335803Y0867665
X1320055Y0861367
X1335803Y0861367
X1335803Y0858218
X1335803Y0855068
X1320055Y0842470
X1357849Y0851918
X1354699Y0851918
X1351550Y0851918
X1345252Y0851918
X1342103Y0851918
X1338953Y0851918
X1364148Y0839320
X1345252Y0839320
X1332654Y0839320
X1310687Y0827706
X1310687Y0832706
X1310687Y0830206
X1360999Y0873964
X1360999Y0870814
X1360999Y0867665
X1360999Y0861367
X1360999Y0858218
X1360999Y0855068
X1367298Y0855068
X1364148Y0892862
X1351550Y0892862
X1332654Y0892862
X1354699Y0880263
X1342103Y0880263
X1357849Y0877114
X1351550Y0877114
X1345252Y0877114
X1338953Y0877114
X1354699Y0870814
X1351550Y0867665
X1351550Y0870814
X1345252Y0867665
X1345252Y0870814
X1342103Y0870814
X1351550Y0861367
X1342103Y0858218
X1345252Y0861367
X1345252Y0858218
X1351550Y0858218
X1354699Y0858218
X1360999Y0886562
X1274400Y0914123
X1351550Y0886562
X1351550Y0889712
X1274670Y0919808
X1309753Y0877589
X1332654Y0858218
X1323204Y0839319
X1310555Y0848675
X1310994Y0866859
X1296687Y0839500
X1329504Y0848769
X1320055Y0877114
X1323205Y0877114
X1323205Y0848769
X1320055Y0855068
X1296770Y0828775
X1323205Y0880263
X1320055Y0867665
X1320055Y0880263
X1291129Y0892267
X1323205Y0883413
X1326355Y0848769
X1282184Y0898854
X1326355Y0861367
X1367298Y0848769
X1367298Y0851918
X1316906Y0855068
X1351550Y0845619
X1332654Y0867665
X1294000Y0863500
X1351550Y0848769
X1293500Y0827500
X1320055Y0839320
X1297667Y0832150
X1316906Y0839320
X1293500Y0835500
X1332654Y0848769
X1293500Y0851500
X1323205Y0851918
X1293500Y0875800
X1293500Y0843500
X1329504Y0851918
X1293500Y0871800
X1285302Y0877283
X1285302Y0881783
X1279693Y0919800
X1279460Y0864487
X1291059Y0917000
X1285500Y0835500
X1279460Y0879487
X1323204Y0873965
X1279460Y0859487
X1332654Y0870814
X1279460Y0869487
X1279460Y0874487
X1320055Y0873964
X1279460Y0854487
X1329504Y0870814
X1279460Y0889487
X1326355Y0877114
X1313756Y0836170
X1313756Y0833021
X1279299Y0898813
X1293500Y0879800
X1288500Y0901254
X1285302Y0885783
X1332654Y0861367
X1293500Y0883800
X1293272Y0887800
X1332654Y0877114
X1301657Y0899129
X1281269Y0835492
X1326355Y0883413
X1329504Y0880263
X1269221Y0894760
X1332654Y0880263
X1281331Y0843331
X1320055Y0858218
X1285500Y0851500
X1285500Y0843500
X1351550Y0842470
X1279460Y0884487
X1326355Y0873964
X1323205Y0858218
X1323205Y0845619
X1281388Y0827388
X1285500Y0855500
X1329504Y0861367
X1285500Y0859500
X1285500Y0863500
X1285500Y0867500
X1285500Y0827500
X1305356Y0902597
X1351550Y0883413
X1313756Y0858218
X1310971Y0842319
X1326355Y0858218
X1320055Y0848769
X1326355Y0855068
X1332654Y0855068
X1329504Y0867665
X1320055Y0870814
X1323205Y0870814
X1326355Y0870814
X1326355Y0867665
X1367298Y0867665
X1320055Y0851918
X1326355Y0842470
X1320055Y0836170
X1326355Y0845619
X1329504Y0858218
X1320055Y0845619
X1320055Y0886562
X1305250Y0889250
X1329504Y0855068
X1316906Y0848769
X1350000Y0825500
X1360999Y0836170
X1354699Y0839320
X1367298Y0833021
X1360999Y0845619
X1360999Y0848769
X1367298Y0842470
X1367298Y0829871
X1360999Y0839320
X1357849Y0845619
X1364148Y0829871
X1349976Y0829000
X1354699Y0845619
X1360999Y0842470
X1340000Y0903000
X1357849Y0836170
X1357850Y0839319
X1332654Y0883413
X1364148Y0842470
X1338953Y0836170
X1323205Y0833021
X1345252Y0848769
X1335803Y0833021
X1329504Y0886562
X1302501Y0824747
X1338953Y0842470
X1324000Y0901000
X1329504Y0842470
X1335803Y0836170
X1342103Y0848769
X1323205Y0836170
X1354699Y0883413
X1323205Y0829871
X1340000Y0906000
X1360999Y0889712
X1345252Y0842470
X1329504Y0839320
X1357849Y0892862
X1338952Y0839319
X1338953Y0848769
X1342103Y0839320
X1335803Y0848769
X1314500Y0905000
X1335803Y0845619
X1329504Y0836170
X1345252Y0845619
X1342103Y0842470
X1335803Y0842470
X1326355Y0836170
X1364148Y0886562
X1332654Y0845619
X1329504Y0845619
X1351550Y0836170
X1332654Y0842470
X1329504Y0833021
X1323205Y0892862
X1335803Y0839320
X1342103Y0836170
X1338953Y0886562
X1345252Y0833021
X1342103Y0889712
X1320055Y0892862
X1271438Y0861846
X1316906Y0833021
X1342103Y0892862
X1305786Y0867704
X1326355Y0839320
X1316906Y0829871
X1319500Y0901500
X1338953Y0845619
X1357849Y0886562
X1345252Y0836170
X1342103Y0845619
X1335803Y0829871
X1335803Y0826500
X1367000Y0900500
X1360999Y0880263
X1354699Y0889712
X1342103Y0886562
X1329504Y0889712
X1357849Y0880263
X1326355Y0892862
X1335803Y0889712
X1338953Y0892862
X1309103Y0917000
X1351500Y0906500
X1335803Y0892862
X1332654Y0889712
X1363000Y0900500
X1335803Y0880263
X1345252Y0880263
X1329504Y0892862
X1367298Y0858218
X1351550Y0880263
X1367298Y0889712
X1357849Y0883413
X1338952Y0889713
X1364148Y0861367
X1364148Y0855068
X1336000Y0900500
X1345252Y0883413
X1367000Y0904500
X1364148Y0889712
X1357850Y0889713
X1342103Y0883413
X1367298Y0845619
X1351500Y0903000
X1354185Y0906498
X1335803Y0883413
X1364148Y0858218
X1338953Y0880263
X1326355Y0889712
X1360999Y0883413
X1345252Y0886562
X1314500Y0911500
X1345252Y0889712
X1367298Y0892862
X1336096Y0905042
X1360999Y0892862
X1354699Y0892862
X1331056Y0904557
X1274264Y0898591
X1367298Y0880263
X1364148Y0880263
X1367298Y0870814
X1364148Y0877114
X1367298Y0861367
X1364148Y0873964
X1367298Y0873964
X1364148Y0870814
X1367298Y0877114
X1364148Y0851918
X1357849Y0833021
X1354699Y0836170
X1364148Y0845619
X1357849Y0848769
X1354699Y0848769
X1354699Y0842470
X1311061Y0889361
X1296866Y0894993
X1294264Y0905595
X1329504Y0877114
X1308220Y0889253
X1270276Y0897062
X1326355Y0880263
X1364148Y0867665
X1367298Y0883413
X1340000Y0900000
X1323205Y0886562
X1338953Y0883413
X1294075Y0917000
X1298000Y0917000
X1281075Y0911075
X1310715Y0822991
X1288164Y0892354
X1271121Y0892513
X1326355Y0886562
X1270515Y0908277
X1277039Y0916484
X1285493Y0892175
X1291955Y0901295
X1282317Y0880193
X1300091Y0854824
X1300097Y0851193
X1300204Y0859088
X1300504Y0835985
X1300516Y0832047
X1316906Y0842470
X1313756Y0829871
X1313756Y0899161
X1305761Y0899161
X1309856Y0899161
X1316906Y0892862
X1316906Y0883413
X1316906Y0867665
X1308857Y0836076
X1335802Y0896011
X1364148Y0896011
X1274417Y0861964
X1360999Y0851918
X1357850Y0855067
X1357849Y0858218
X1354699Y0861367
X1357849Y0861367
X1354699Y0867665
X1357849Y0867665
X1357849Y0870814
X1335803Y0877114
X1338952Y0873965
X1342103Y0873964
X1345252Y0873964
X1345252Y0892862
X1351550Y0873964
X1354699Y0873964
X1357850Y0873965
X1360999Y0877114
X1335803Y0851918
X1338952Y0855067
X1338953Y0858218
X1323205Y0861367
X1338953Y0861367
X1342103Y0861367
X1338953Y0867665
X1342103Y0867665
X1338953Y0870814
X1332654Y0836170
X1342103Y0855068
X1345252Y0855068
X1351550Y0855068
X1351550Y0839320
X1354699Y0855068
X1364148Y0836170
X1352817Y0788000
X1352817Y0796000
X1348917Y0788000
X1348917Y0796000
X1298720Y0798975
X1291604Y0771435
X1291604Y0776576
X1291604Y0781576
X1325000Y0788000
X1321000Y0804000
X1313000Y0804000
X1317000Y0804000
X1321000Y0788000
X1319000Y0811620
X1335000Y0811620
X1329000Y0788000
X1341000Y0804000
X1345000Y0804000
X1337000Y0804000
X1343000Y0728458
X1343000Y0811620
X1340522Y0724133
X1337000Y0788000
X1361000Y0804000
X1347000Y0811620
X1357000Y0804000
X1345226Y0777675
X1330295Y0751328
X1359000Y0811620
X1336661Y0737675
X1351000Y0811620
X1336746Y0781675
X1349000Y0804000
X1333000Y0788000
X1336661Y0745675
X1323000Y0811620
X1330086Y0763758
X1333000Y0804000
X1336661Y0753675
X1325000Y0804000
X1326970Y0736464
X1315000Y0811620
X1319000Y0732500
X1279539Y0753576
X1282539Y0761076
X1327000Y0732500
X1282539Y0751076
X1282539Y0756076
X1279539Y0758576
X1279539Y0748576
X1282539Y0766076
X1329000Y0804000
X1327000Y0811620
X1353000Y0804000
X1345000Y0788000
X1313000Y0788000
X1341000Y0788000
X1331000Y0811620
X1317000Y0788000
X1369000Y0804000
X1363000Y0811620
X1355000Y0811620
X1365000Y0804000
X1367000Y0811620
X1279539Y0763576
X1345000Y0796000
X1336450Y0765675
X1282539Y0746076
X1333000Y0799000
X1337000Y0796000
X1341000Y0799000
X1325000Y0799000
X1317000Y0799000
X1313000Y0796000
X1321000Y0796000
X1329000Y0796000
X1302140Y0812625
X1344768Y0781350
X1330295Y0746328
X1335000Y0732500
X1344768Y0773675
X1330324Y0779030
X1310715Y0817991
X1310715Y0820491
X1295491Y0798821
X1289730Y0806845
X1279539Y0780576
X1279539Y0768576
X1279539Y0784576
X1285092Y0819500
X1344768Y0757675
X1344768Y0761675
X1344768Y0753675
X1344768Y0749675
X1344768Y0745675
X1344768Y0741675
X1344768Y0737675
X1319000Y0728500
X1319000Y0724500
X1347136Y0780040
X1335000Y0728500
X1335000Y0724500
X1344768Y0769675
X1279539Y0776576
X1279539Y0772576
X1303520Y0748403
X1290066Y0804246
X1305134Y0812065
X1305412Y0799061
X1324217Y0780595
X1284900Y0678800
X1298963Y0659609
X1327000Y0716500
X1340299Y0686243
X1350929Y0687043
X1343000Y0636958
X1340522Y0632633
X1343000Y0681458
X1340522Y0677133
X1327011Y0646064
X1319000Y0641000
X1327000Y0641000
X1338000Y0653500
X1319000Y0685500
X1346738Y0655492
X1327000Y0685500
X1327000Y0657500
X1342053Y0625839
X1327003Y0623940
X1346378Y0623734
X1283400Y0715500
X1338000Y0700500
X1346738Y0702492
X1313979Y0677726
X1289317Y0706932
X1283400Y0719700
X1327000Y0629000
X1342053Y0670339
X1346533Y0667780
X1346533Y0714780
X1342053Y0717339
X1327000Y0700500
X1346533Y0628398
X1305836Y0660009
X1339289Y0659461
X1346533Y0672898
X1339289Y0706461
X1346533Y0719898
X1289811Y0677612
X1327000Y0695500
X1327000Y0711500
X1278255Y0722241
X1335000Y0641000
X1335000Y0685500
X1319000Y0716500
X1319000Y0712500
X1319000Y0700500
X1319000Y0696500
X1319000Y0677500
X1319000Y0681500
X1319000Y0665500
X1319000Y0669500
X1319000Y0649500
X1319000Y0653500
X1319000Y0637000
X1319000Y0625000
X1319000Y0633000
X1335000Y0681500
X1335000Y0677500
X1319000Y0673500
X1319000Y0657500
X1319000Y0629000
X1335000Y0637000
X1335000Y0633000
X1345451Y0699032
X1355255Y0652032
X1319000Y0720500
X1319000Y0704500
X1339289Y0568461
X1346533Y0581898
X1338000Y0562500
X1346738Y0564492
X1343000Y0590458
X1340522Y0586133
X1346738Y0611192
X1338000Y0609000
X1327000Y0594500
X1335532Y0622260
X1327000Y0621000
X1344680Y0619085
X1346533Y0576780
X1342053Y0579339
X1301194Y0565518
X1300817Y0568635
X1327000Y0605000
X1327000Y0613000
X1331096Y0549931
X1333224Y0615484
X1319323Y0598454
X1327000Y0583826
X1326946Y0567906
X1344433Y0601201
X1327000Y0609000
X1344129Y0606914
X1327000Y0562500
X1327043Y0573346
X1327000Y0578500
X1326993Y0556788
X1339289Y0614961
X1335000Y0594500
X1317945Y0523058
X1321164Y0523130
X1319000Y0609000
X1319000Y0621000
X1319000Y0590500
X1319000Y0605000
X1319000Y0578500
X1319000Y0574500
X1319000Y0586500
X1319000Y0558500
X1319000Y0562500
X1319000Y0613000
X1319000Y0582500
X1319000Y0566500
X1335000Y0586500
X1335000Y0590500
X1355255Y0607532
X1355255Y0561032
X1352259Y0452601
X1346613Y0440101
X1340820Y0452987
X1352271Y0442114
X1329083Y0448931
X1346248Y0452718
X1335440Y0452799
X1352251Y0447121
X1352008Y0435101
X1346443Y0431112
X1332974Y0474513
X1281737Y0456034
X1281737Y0461034
X1319974Y0475560
X1319474Y0467560
X1360719Y0424601
X1299304Y0487382
X1299807Y0472020
X1311488Y0475560
X1271915Y0477053
X1274415Y0477053
X1277897Y0476376
X1277897Y0478876
X1280631Y0477694
X1280631Y0480194
X1275927Y0462060
X1272927Y0462060
X1307835Y0470382
X1299466Y0466409
X1299867Y0477318
X1307819Y0474382
X1326297Y0443721
X1329097Y0443721
X1309750Y0443893
X1299757Y0443893
X1326297Y0440921
X1329097Y0440921
X1326297Y0438121
X1326297Y0435321
X1329097Y0438121
X1329097Y0435321
X1309750Y0441093
X1309750Y0438293
X1290092Y0439318
X1290092Y0442118
X1299757Y0441093
X1299757Y0438293
X1271828Y0426689
X1282092Y0439318
X1282092Y0442118
X1272215Y0435518
X1272215Y0432718
X1297383Y0424067
X1299883Y0424067
X1294883Y0424067
X1292383Y0424067
X1271828Y0424089
X1343846Y0461607
X1318160Y0520053
X1321450Y0520268
X1339049Y0471334
X1301314Y0484882
X1339846Y0461607
X1347846Y0461607
X1311488Y0471560
X1288505Y0485580
X1291005Y0485580
X1286005Y0485580
X1290219Y0470001
X1287719Y0470001
X1288144Y0489036
X1290380Y0492836
X1290380Y0495636
X1270397Y0447081
X1273397Y0447081
X1275927Y0450091
X1272927Y0450091
X1329606Y0459170
X1336388Y0424939
X1336388Y0427439
X1325927Y0474513
X1307825Y0482382
X1307919Y0478382
X1311488Y0479560
X1280616Y0472189
X1283455Y0465288
X1283455Y0468088
X1281737Y0452740
X1282092Y0446318
X1282092Y0449118
X1279127Y0450091
X1272215Y0439718
X1272215Y0442518
X1290272Y0462309
X1290272Y0454309
X1290272Y0458309
X1299757Y0455641
X1299757Y0452841
X1299757Y0450041
X1290092Y0446318
X1290092Y0449118
X1309750Y0452841
X1309750Y0450041
X1308006Y0423944
X1310806Y0423944
X1313306Y0423944
X1315806Y0423944
X1326020Y0424240
X1308010Y0466409
X1309750Y0455641
X1346483Y0436164
X1347897Y0433975
X1332927Y0468607
X1329626Y0455039
X1326020Y0426740
X1360352Y0447101
X1270951Y0491870
X1276060Y0493758
X1273451Y0491870
X1276060Y0496258
X1279505Y0490070
X1279505Y0487570
X1296783Y0511956
X1307996Y0487382
X1325630Y0513238
X1326912Y0493153
X1292500Y0335000
X1289345Y0330655
X1274436Y0377350
X1311283Y0370801
X1331922Y0359836
X1349636Y0340862
X1346093Y0340805
X1341169Y0325926
X1347990Y0322539
X1332359Y0322685
X1315397Y0333709
X1294080Y0349820
X1312240Y0334681
X1313103Y0339606
X1349763Y0371908
X1284419Y0359377
X1363535Y0347025
X1363535Y0343625
X1363535Y0327877
X1363535Y0331277
X1337509Y0373401
X1366535Y0351499
X1366535Y0339151
X1366535Y0335751
X1366535Y0354899
X1334109Y0373401
X1302896Y0340397
X1302896Y0343797
X1338471Y0356959
X1346065Y0347106
X1331005Y0356670
X1299959Y0356954
X1346009Y0336080
X1315256Y0336510
X1325573Y0326719
X1332563Y0326356
X1308012Y0348109
X1326489Y0356945
X1303000Y0326692
X1303000Y0331000
X1284659Y0377173
X1280699Y0377173
X1284333Y0391569
X1280659Y0385123
X1273659Y0385123
X1297618Y0413611
X1300118Y0413611
X1295118Y0413611
X1292618Y0413611
X1271828Y0418889
X1271828Y0421489
X1271828Y0416289
X1271828Y0411089
X1271828Y0413689
X1297537Y0398278
X1300037Y0398278
X1298264Y0401981
X1295764Y0401981
X1296100Y0407039
X1293100Y0406739
X1296100Y0409539
X1293100Y0409539
X1271828Y0408489
X1271828Y0405889
X1272421Y0403300
X1298346Y0379028
X1287437Y0379429
X1308410Y0379591
X1293048Y0379088
X1295410Y0371076
X1325007Y0370951
X1310172Y0367956
X1293000Y0338500
X1294000Y0324000
X1305910Y0377581
X1282760Y0401066
X1276659Y0385123
X1291410Y0371060
X1348410Y0408104
X1345610Y0408104
X1342810Y0408104
X1348127Y0420375
X1345327Y0420375
X1342527Y0420375
X1320594Y0384651
X1320594Y0382151
X1320594Y0387151
X1328896Y0386567
X1331606Y0386567
X1334285Y0386567
X1306113Y0388817
X1306113Y0386317
X1315426Y0387702
X1312626Y0387702
X1306113Y0383817
X1308826Y0389402
X1338275Y0341603
X1278724Y0409032
X1282760Y0409016
X1275984Y0396866
X1271391Y0396866
X1275407Y0402867
X1271346Y0392183
X1275940Y0392228
X1287437Y0370010
X1281834Y0374839
X1283494Y0339495
X1291165Y0395248
X1299410Y0370976
X1303158Y0371043
X1299959Y0351454
X1300400Y0344575
X1300400Y0339619
X1292731Y0331820
X1301500Y0329000
X1315866Y0413611
X1313366Y0413611
X1310866Y0413611
X1308066Y0413611
X1306617Y0401949
X1309117Y0398949
X1310546Y0407104
X1310546Y0409904
X1316191Y0402642
X1313691Y0402642
X1308410Y0370899
X1316017Y0349889
X1328559Y0420393
X1323559Y0420393
X1323441Y0408240
X1328441Y0408240
X1325941Y0408240
X1321016Y0396661
X1321016Y0401661
X1321016Y0399161
X1333049Y0396768
X1333049Y0401768
X1333049Y0399268
X1329064Y0370951
X1333331Y0370905
X1320903Y0370995
X1323816Y0348868
X1331085Y0348868
X1323816Y0341615
X1323816Y0334347
X1331085Y0334347
X1338287Y0370905
X1338378Y0348830
X1338378Y0334347
X1326059Y0420393
X1364039Y0355677
X1361039Y0347803
X1364039Y0350721
X1361039Y0342847
X1364039Y0339929
X1364039Y0334973
X1361039Y0332055
X1361039Y0327099
X1301784Y0265896
X1296697Y0265701
X1298332Y0281716
X1304273Y0281982
X1306800Y0266114
X1344007Y0279054
X1340104Y0279117
X1271571Y0281185
X1302025Y0256303
X1325100Y0228631
X1348419Y0265222
X1279246Y0258880
X1318362Y0310562
X1326236Y0307562
X1329636Y0307562
X1337510Y0310562
X1321762Y0310562
X1334110Y0310562
X1291015Y0267526
X1293515Y0267526
X1288215Y0267526
X1288215Y0270026
X1291015Y0270026
X1293515Y0270026
X1279321Y0264180
X1281821Y0264180
X1308428Y0318250
X1305928Y0318250
X1315346Y0270695
X1310046Y0270695
X1312546Y0270695
X1319006Y0265897
X1315346Y0268195
X1312546Y0268195
X1310046Y0268195
X1314849Y0248765
X1309849Y0248765
X1312349Y0248765
X1312408Y0236189
X1314908Y0236189
X1309908Y0236189
X1307657Y0224421
X1309357Y0228221
X1309357Y0231021
X1321506Y0265897
X1282038Y0293796
X1279538Y0293796
X1286448Y0231461
X1286448Y0228961
X1286448Y0226461
X1286448Y0223661
X1275992Y0228726
X1275992Y0231226
X1275992Y0226226
X1275992Y0223726
X1287552Y0285690
X1290052Y0285690
X1287552Y0288190
X1301078Y0290755
X1297078Y0290755
X1295100Y0248891
X1292600Y0248891
X1290100Y0248891
X1298025Y0256535
X1294417Y0231786
X1292898Y0236611
X1295398Y0236611
X1290398Y0236611
X1298110Y0224712
X1294417Y0229286
X1290155Y0226141
X1292955Y0226141
X1294425Y0321425
X1305078Y0290755
X1292852Y0285690
X1292852Y0288190
X1290052Y0288190
X1317584Y0313058
X1312069Y0318013
X1314569Y0318013
X1315649Y0293645
X1315649Y0290845
X1315649Y0288345
X1313149Y0293645
X1313149Y0290845
X1313149Y0288345
X1311159Y0281307
X1307055Y0279208
X1306025Y0256535
X1333332Y0313058
X1322540Y0313058
X1325458Y0310058
X1330414Y0310058
X1338288Y0313058
X1348939Y0148277
X1363709Y0152373
X1351559Y0143740
X1310115Y0192300
X1320022Y0178560
X1320085Y0172665
X1364609Y0143518
X1328912Y0186778
X1360122Y0141247
X1328831Y0208864
X1320291Y0212455
X1320225Y0207037
X1320202Y0200864
X1328799Y0196665
X1328799Y0192665
X1314157Y0192490
X1314627Y0171523
X1319432Y0190185
X1319912Y0183834
X1305015Y0168697
X1301781Y0215632
X1286448Y0215713
X1293320Y0208695
X1290520Y0208695
X1293020Y0211695
X1290520Y0211695
X1298078Y0213859
X1298078Y0211359
X1301781Y0213132
X1286448Y0208213
X1286448Y0210713
X1286448Y0213213
X1275992Y0207978
X1275992Y0210478
X1275992Y0212978
X1275992Y0215478
X1296659Y0184012
X1294042Y0184221
X1297045Y0181366
X1293834Y0181426
X1299840Y0181009
X1302342Y0172190
X1301761Y0177616
X1366859Y0152562
X1324472Y0219379
X1320898Y0186629
X1306103Y0191941
X1328799Y0176665
X1328831Y0204864
X1328799Y0168665
X1344092Y0141247
X1294837Y0170493
X1294837Y0167993
X1294837Y0165393
X1287737Y0162368
X1294837Y0162793
X1285137Y0162368
X1340320Y0147540
X1308242Y0221708
X1317592Y0221642
X1310742Y0221708
X1313242Y0221708
X1310612Y0206767
X1313112Y0206767
X1308112Y0206767
X1285357Y0130670
X1277357Y0123583
X1277357Y0130670
X1285357Y0137756
X1273555Y0137756
X1285357Y0123583
X1298110Y0222212
X1296198Y0188727
X1302831Y0184619
X1296331Y0191941
X1294768Y0124618
X1299760Y0124618
X1299760Y0129574
X1294768Y0129574
X1305170Y0136687
X1310162Y0136687
X1305170Y0131731
X1305170Y0122513
X1310162Y0131731
X1310162Y0122513
X1304811Y0206760
X1313501Y0185121
X1317269Y0192421
X1308863Y0185165
X1308863Y0180572
X1313546Y0180527
X1328831Y0216864
X1328831Y0221864
X1328831Y0200864
X1328831Y0212864
X1328799Y0180665
X1328799Y0172665
X1354802Y0152367
X1355900Y0146461
X1340320Y0151540
X1297264Y0125396
X1297264Y0128796
X1307666Y0135909
X1307666Y0132509
X1320566Y0103621
X1311904Y0100625
X1304923Y0097475
X1277180Y0095236
X1277130Y0099961
X1316277Y0112083
X1302785Y0031168
X1336623Y0030483
X1324120Y0022742
X1302139Y0026325
X1336551Y0026534
X1288115Y0107649
X1288115Y0104249
X1328318Y0027333
X1328003Y0032403
X1318859Y0045448
X1314887Y0045448
X1272809Y0090615
X1336646Y0022627
X1331073Y0033400
X1286044Y0077739
X1286044Y0080339
X1286044Y0075139
X1286044Y0082939
X1286044Y0085539
X1286088Y0092874
X1304854Y0106186
X1297919Y0103783
X1294369Y0098551
X1322853Y0037530
X1310853Y0037543
X1297785Y0033768
X1270263Y0092849
X1285357Y0102323
X1285357Y0109410
X1285357Y0116496
X1277357Y0109410
X1277357Y0116496
X1277223Y0103037
X1276898Y0053597
X1294768Y0115401
X1294768Y0110445
X1299760Y0115401
X1299760Y0110445
X1301919Y0103783
X1294640Y0094017
X1294369Y0101701
X1290640Y0094017
X1298640Y0094017
X1302649Y0094017
X1295005Y0044773
X1297785Y0030618
X1295005Y0024773
X1303229Y0023274
X1313086Y0103621
X1305170Y0117557
X1310162Y0117557
X1307717Y0080140
X1307717Y0076140
X1307717Y0084140
X1321092Y0117261
X1334223Y0033425
X1307666Y0121735
X1297264Y0111223
X1307666Y0118335
X1297264Y0114623
X1297687Y-0043656
X1297687Y-0030256
X1297687Y-0040256
X1297687Y-0033656
X1337687Y-0072706
X1337687Y-0069306
X1340183Y-0073484
X1340183Y-0068528
X1300183Y-0039478
X1300183Y-0034434
X1300183Y-0029478
X1300183Y-0044434
X1334781Y-0065513
X1334781Y-0076099
X1328500Y-0069400
X1328488Y-0066722
X1331741Y-0066708
X1328503Y-0064207
X1331756Y-0064193
X1328488Y-0074890
X1328500Y-0072000
X1331741Y-0074904
X1328503Y-0077405
X1331756Y-0077419
X1294781Y-0026463
X1294781Y-0037049
X1294781Y-0047349
X1288500Y-0030350
X1288488Y-0027672
X1291741Y-0027658
X1288503Y-0025157
X1291756Y-0025143
X1288488Y-0035840
X1288500Y-0032950
X1291741Y-0035854
X1288488Y-0046154
X1291741Y-0046154
X1288500Y-0043464
X1288503Y-0048669
X1291756Y-0048669
X1288503Y-0038355
X1291756Y-0038369
X1288500Y-0040964
X1295692Y0005374
X1302232Y0003000
X1322232Y0003000
X1362232Y0003000
X1342232Y0003000
X1337687Y-0082706
X1337687Y-0079306
X1340183Y-0078528
X1340183Y-0083484
X1334781Y-0086499
X1328488Y-0085290
X1331741Y-0085290
X1328500Y-0082600
X1328503Y-0087805
X1331756Y-0087805
X1328500Y-0080100
X1398216Y0004469
X1382232Y0003000
X1445692Y0005374
X1462675Y0014334
X1464594Y0003000
X1449685Y0034228
X1387205Y0110784
X1382205Y0110784
X1457829Y0026425
X1455013Y0043128
X1457347Y0031518
X1402098Y0095111
X1454924Y0097475
X1417248Y0095236
X1461905Y0100625
X1427181Y0095236
X1427131Y0099961
X1466278Y0112083
X1406467Y0106561
X1438116Y0104249
X1438116Y0107649
X1422810Y0090615
X1460466Y0072615
X1417498Y0090650
X1460466Y0076587
X1452717Y0034052
X1393504Y0102495
X1376262Y0119594
X1376262Y0116594
X1406948Y0114655
X1436045Y0079993
X1436045Y0082593
X1436045Y0085193
X1436045Y0074793
X1436045Y0077393
X1399648Y0118342
X1399648Y0121742
X1406948Y0111255
X1406702Y0097667
X1436089Y0092874
X1406308Y0103411
X1454855Y0106186
X1447920Y0103783
X1388231Y0116594
X1388231Y0119594
X1444370Y0098551
X1397848Y0097667
X1468384Y0080581
X1468371Y0068581
X1457667Y0121735
X1457667Y0118335
X1388480Y0102249
X1399577Y0044773
X1399577Y0024773
X1384480Y0102249
X1380480Y0102249
X1378911Y0110784
X1376262Y0113394
X1397248Y0116497
X1393504Y0106495
X1394497Y0109172
X1391497Y0109172
X1426898Y0053597
X1409248Y0116496
X1404548Y0109410
X1402048Y0116497
X1404548Y0116497
X1409248Y0102323
X1409248Y0109410
X1417248Y0102323
X1406898Y0053597
X1444370Y0101701
X1440641Y0094017
X1445005Y0044773
X1445005Y0024773
X1427358Y0109410
X1427358Y0116496
X1417500Y0116496
X1417500Y0109410
X1427224Y0103037
X1417710Y0085584
X1420264Y0092849
X1417710Y0080384
X1417710Y0077784
X1417710Y0075184
X1417710Y0082984
X1435358Y0102323
X1444769Y0115401
X1444769Y0110445
X1449761Y0110445
X1449761Y0115401
X1435358Y0109410
X1435358Y0116496
X1448641Y0094017
X1444641Y0094017
X1451920Y0103783
X1463087Y0103621
X1455171Y0117557
X1460163Y0117557
X1452650Y0094017
X1457718Y0080140
X1457718Y0076140
X1457718Y0084140
X1447265Y0114623
X1447265Y0111223
X1381762Y0124879
X1451301Y0148277
X1376696Y0124283
X1466071Y0152373
X1386784Y0124663
X1453921Y0143740
X1391765Y0125107
X1388128Y0138838
X1466971Y0143518
X1372354Y0157370
X1394279Y0148717
X1400379Y0143762
X1462484Y0141247
X1464158Y0192490
X1464628Y0171523
X1452343Y0172190
X1455016Y0168697
X1451782Y0215632
X1436449Y0215713
X1451782Y0213132
X1436449Y0208213
X1443321Y0208695
X1440521Y0208695
X1443021Y0211695
X1440521Y0211695
X1436449Y0210713
X1436449Y0213213
X1448079Y0213859
X1448079Y0211359
X1425993Y0215478
X1425993Y0210478
X1425993Y0207978
X1425993Y0212978
X1446660Y0184012
X1444043Y0184221
X1443835Y0181426
X1447046Y0181366
X1449841Y0181009
X1451762Y0177616
X1381519Y0218085
X1384319Y0218085
X1388119Y0216385
X1390832Y0221970
X1390832Y0219470
X1390832Y0216970
X1456104Y0191941
X1375103Y0161306
X1446454Y0141247
X1393238Y0142862
X1444838Y0167993
X1444838Y0170493
X1444838Y0165393
X1444838Y0162793
X1437738Y0162368
X1435138Y0162368
X1406948Y0125428
X1406948Y0128828
X1399648Y0135915
X1399648Y0132515
X1442682Y0147540
X1403845Y0202048
X1396908Y0210509
X1399408Y0210509
X1401181Y0206806
X1398681Y0206806
X1400845Y0201748
X1404327Y0195176
X1401827Y0195176
X1403845Y0199248
X1400845Y0199248
X1396827Y0195176
X1399327Y0195176
X1458243Y0221708
X1460743Y0221708
X1463243Y0221708
X1460613Y0206767
X1463113Y0206767
X1458113Y0206767
X1467593Y0221642
X1457667Y0132509
X1457667Y0135909
X1447265Y0128796
X1447265Y0125396
X1386399Y0201683
X1381640Y0203393
X1384140Y0203393
X1381780Y0195176
X1384280Y0195176
X1380652Y0134579
X1378505Y0133298
X1387828Y0206838
X1390328Y0206838
X1386780Y0195176
X1386399Y0198883
X1389580Y0195176
X1398032Y0150847
X1397248Y0137757
X1395144Y0141228
X1393238Y0146012
X1397248Y0123584
X1397248Y0130670
X1386505Y0133298
X1405780Y0213539
X1402048Y0137757
X1409248Y0137756
X1404548Y0130670
X1409248Y0123583
X1409248Y0130670
X1404548Y0123583
X1402048Y0123584
X1402048Y0130670
X1418720Y0137756
X1423515Y0137756
X1418725Y0130670
X1427358Y0123583
X1427358Y0130670
X1421700Y0122900
X1448111Y0222212
X1446199Y0188727
X1446332Y0191941
X1442682Y0151540
X1435358Y0137756
X1449761Y0129574
X1435358Y0123583
X1435358Y0130670
X1444769Y0129574
X1444769Y0124618
X1449761Y0124618
X1452832Y0184619
X1463502Y0185121
X1458864Y0185165
X1458864Y0180572
X1463547Y0180527
X1457164Y0152367
X1455171Y0136687
X1460163Y0136687
X1458262Y0146461
X1455171Y0131731
X1460163Y0122513
X1460163Y0131731
X1455171Y0122513
X1454812Y0206760
X1467270Y0192421
X1448333Y0281716
X1456801Y0266114
X1454274Y0281982
X1446698Y0265701
X1396809Y0256394
X1386846Y0249108
X1451785Y0265896
X1389466Y0244571
X1452026Y0256303
X1393859Y0228646
X1398600Y0230556
X1402855Y0227824
X1405162Y0244297
X1429247Y0258880
X1437064Y0320861
X1449060Y0320861
X1395726Y0320529
X1384265Y0320871
X1407445Y0230117
X1438216Y0267526
X1443516Y0267526
X1438216Y0270026
X1443516Y0270026
X1441016Y0270026
X1441016Y0267526
X1431822Y0264180
X1429322Y0264180
X1378227Y0248371
X1392816Y0232971
X1402942Y0246874
X1459060Y0320861
X1397585Y0242078
X1390898Y0226320
X1403461Y0238714
X1465347Y0268195
X1465347Y0270695
X1462547Y0268195
X1462547Y0270695
X1460047Y0268195
X1460047Y0270695
X1462350Y0248765
X1464850Y0248765
X1459850Y0248765
X1462409Y0236189
X1464909Y0236189
X1459909Y0236189
X1459358Y0228221
X1459358Y0231021
X1457658Y0224421
X1469007Y0265897
X1378227Y0252371
X1392709Y0253198
X1389824Y0238589
X1392790Y0236121
X1399226Y0238689
X1400000Y0247292
X1407461Y0238714
X1432039Y0293796
X1429539Y0293796
X1425993Y0223726
X1425993Y0226226
X1425993Y0228726
X1425993Y0231226
X1437553Y0288190
X1447079Y0290755
X1442853Y0285690
X1442853Y0288190
X1440053Y0288190
X1437553Y0285690
X1440053Y0285690
X1445101Y0248891
X1442601Y0248891
X1440101Y0248891
X1448026Y0256535
X1445399Y0236611
X1444418Y0231786
X1442899Y0236611
X1440399Y0236611
X1436449Y0231461
X1448111Y0224712
X1436449Y0223661
X1440156Y0226141
X1436449Y0226461
X1442956Y0226141
X1444418Y0229286
X1436449Y0228961
X1463150Y0293645
X1463150Y0290845
X1463150Y0288345
X1465650Y0290845
X1465650Y0288345
X1451079Y0290755
X1455079Y0290755
X1465650Y0293645
X1461160Y0281307
X1457056Y0279208
X1456026Y0256535
X1458214Y0406231
X1387847Y0366710
X1443041Y0363648
X1445906Y0366030
X1407844Y0411033
X1408254Y0398041
X1390271Y0417578
X1402968Y0390177
X1468309Y0408861
X1391623Y0409900
X1389431Y0421593
X1400231Y0390256
X1421005Y0407616
X1415674Y0421278
X1439719Y0350387
X1383963Y0366675
X1434697Y0347125
X1399884Y0367165
X1415610Y0417644
X1414369Y0398056
X1372232Y0361298
X1404690Y0362209
X1447502Y0360785
X1390553Y0397436
X1393575Y0397310
X1399571Y0397418
X1402921Y0322403
X1396528Y0397454
X1409830Y0347649
X1387125Y0417312
X1375108Y0420838
X1377024Y0397713
X1440523Y0382747
X1442633Y0371502
X1434038Y0334114
X1438829Y0329861
X1435818Y0352361
X1434166Y0325361
X1440420Y0346833
X1439712Y0336673
X1434164Y0339232
X1448500Y0340575
X1449060Y0352361
X1448948Y0326448
X1448734Y0332910
X1448822Y0345324
X1449060Y0329861
X1448572Y0349441
X1395726Y0330529
X1395726Y0345529
X1395568Y0325529
X1395726Y0355529
X1395726Y0340529
X1395736Y0335529
X1395726Y0350529
X1384265Y0352371
X1384265Y0334371
X1383634Y0342766
X1384265Y0325371
X1384265Y0329871
X1383551Y0337808
X1383505Y0349437
X1416470Y0381397
X1408854Y0381207
X1416912Y0386903
X1441180Y0354909
X1395726Y0360529
X1391896Y0365529
X1463145Y0391579
X1459873Y0391705
X1438768Y0371655
X1434608Y0362584
X1459060Y0352361
X1459060Y0347861
X1449060Y0356861
X1375073Y0361371
X1375073Y0356871
X1459060Y0334361
X1459060Y0343361
X1459060Y0338861
X1459060Y0329861
X1459060Y0325361
X1373748Y0397758
X1384174Y0362641
X1384447Y0356871
X1384253Y0346826
X1389295Y0408443
X1387814Y0397136
X1397550Y0390484
X1386286Y0350218
X1385971Y0336791
X1386057Y0341200
X1386143Y0331982
X1385971Y0327688
X1385943Y0323222
X1413889Y0415642
X1411400Y0398032
X1416830Y0407134
X1416347Y0384373
X1408666Y0324733
X1386809Y0414173
X1438588Y0380589
X1437758Y0362584
X1449619Y0363290
X1440568Y0369566
X1458212Y0403374
X1455979Y0391756
X1458982Y0356861
X1451186Y0350447
X1451387Y0345609
X1451300Y0332225
X1451344Y0336620
X1451272Y0340971
X1451330Y0327588
X1451215Y0323193
X1436930Y0461818
X1427484Y0462004
X1427117Y0443071
X1432414Y0459371
X1418903Y0461419
X1417856Y0448419
X1434997Y0442603
X1410903Y0461919
X1415823Y0482165
X1431484Y0470045
X1389557Y0424678
X1375360Y0432234
X1435424Y0430361
X1375400Y0435192
X1375171Y0424741
X1393177Y0424804
X1466231Y0423671
X1393336Y0431100
X1466653Y0428582
X1393208Y0428109
X1410903Y0470419
X1406910Y0491982
X1383343Y0508228
X1394044Y0510990
X1416413Y0495649
X1406910Y0495982
X1418903Y0469905
X1440390Y0461652
X1440390Y0459152
X1442890Y0461652
X1442890Y0459152
X1442890Y0456652
X1440390Y0456652
X1445221Y0495151
X1449293Y0498633
X1449293Y0496133
X1449293Y0493633
X1445221Y0498151
X1437663Y0495487
X1433960Y0493714
X1442421Y0498151
X1437663Y0492987
X1442721Y0495151
X1449293Y0491133
X1433960Y0491214
X1415623Y0492268
X1415064Y0500202
X1464536Y0433114
X1383907Y0516591
X1393944Y0507856
X1403085Y0460565
X1411269Y0481467
X1417903Y0439919
X1426384Y0476125
X1424999Y0485138
X1427499Y0485138
X1428084Y0482425
X1426384Y0478625
X1419650Y0485128
X1422499Y0485138
X1414903Y0469905
X1425927Y0459339
X1423427Y0459339
X1425927Y0454339
X1423427Y0454339
X1425927Y0456839
X1423427Y0456839
X1411002Y0517401
X1413502Y0517401
X1416002Y0517401
X1411061Y0504825
X1413561Y0504825
X1416061Y0504825
X1449293Y0483886
X1449293Y0481086
X1449293Y0478586
X1441076Y0478446
X1441076Y0475946
X1445586Y0480705
X1449293Y0476086
X1437631Y0484634
X1437631Y0482134
X1442786Y0480705
X1406910Y0483982
X1406910Y0478982
X1375375Y0428995
X1411950Y0448466
X1388788Y0428348
X1422903Y0469905
X1427484Y0470045
X1417856Y0455466
X1428782Y0445874
X1424196Y0446352
X1427019Y0434508
X1431019Y0434508
X1435484Y0470045
X1437879Y0444269
X1437757Y0447201
X1435019Y0434508
X1406910Y0499982
X1406910Y0487982
X1431493Y0521804
X1430512Y0516979
X1433012Y0516979
X1430810Y0504699
X1433310Y0504699
X1430930Y0500086
X1442036Y0519518
X1439536Y0519518
X1444536Y0519518
X1439462Y0522129
X1435512Y0516979
X1447036Y0519518
X1435810Y0504699
X1407754Y0616905
X1407566Y0622285
X1411622Y0610548
X1378415Y0569776
X1378415Y0563984
X1438944Y0605637
X1397079Y0527726
X1382997Y0581317
X1378415Y0616276
X1378415Y0610484
X1383000Y0584500
X1378957Y0584457
X1390741Y0565000
X1390741Y0569000
X1395605Y0556217
X1390741Y0561000
X1390741Y0615500
X1390741Y0607500
X1390741Y0611500
X1434944Y0597130
X1431000Y0591000
X1378415Y0558795
X1383556Y0554388
X1378415Y0605295
X1430944Y0605443
X1434944Y0605443
X1435119Y0590801
X1454944Y0596729
X1448994Y0596782
X1449993Y0578405
X1455419Y0578986
X1443775Y0596089
X1419632Y0610562
X1422432Y0610562
X1425232Y0607762
X1425232Y0610562
X1422432Y0607762
X1419632Y0607762
X1416832Y0607762
X1416832Y0610562
X1419460Y0591215
X1422260Y0591215
X1416660Y0591215
X1443597Y0573303
X1446243Y0573689
X1446600Y0576484
X1419460Y0581222
X1422260Y0581222
X1416660Y0581222
X1446183Y0570478
X1458912Y0581659
X1443388Y0570686
X1417903Y0571194
X1417903Y0563194
X1415103Y0571194
X1415103Y0563194
X1439462Y0545377
X1439462Y0542877
X1441988Y0548418
X1439488Y0548418
X1444488Y0548418
X1435390Y0541895
X1439462Y0540377
X1417903Y0555194
X1432890Y0541895
X1427832Y0542231
X1435390Y0544895
X1432590Y0544895
X1424129Y0540458
X1415103Y0555194
X1439462Y0537877
X1446988Y0548418
X1427832Y0539731
X1424129Y0537658
X1405708Y0552726
X1405619Y0541135
X1405992Y0534909
X1397079Y0544726
X1449393Y0561097
X1449393Y0563697
X1449393Y0566797
X1449393Y0558497
X1449393Y0555897
X1449393Y0553297
X1405685Y0546553
X1401438Y0534211
X1458944Y0605443
X1450944Y0605443
X1398946Y0621311
X1383608Y0618427
X1438944Y0597232
X1383425Y0590425
X1435668Y0582747
X1391087Y0581317
X1383608Y0571927
X1397079Y0548726
X1401383Y0611071
X1433114Y0617853
X1433114Y0620653
X1440930Y0619513
X1440930Y0616713
X1440930Y0613913
X1453000Y0619758
X1453000Y0616958
X1453000Y0614158
X1409618Y0531948
X1412668Y0531882
X1415168Y0531882
X1416553Y0525369
X1416553Y0522569
X1417668Y0531882
X1418253Y0529169
X1446355Y0532949
X1443555Y0532949
X1383556Y0604838
X1383425Y0593575
X1383184Y0587653
X1383556Y0558338
X1400912Y0591215
X1400912Y0581222
X1391086Y0577192
X1397079Y0540726
X1397079Y0552726
X1397079Y0536726
X1397079Y0531726
X1405514Y0611091
X1406512Y0591215
X1403712Y0591215
X1403712Y0581222
X1406512Y0581222
X1410903Y0571194
X1408103Y0571194
X1410903Y0563194
X1408103Y0563194
X1410903Y0555194
X1408103Y0555194
X1421099Y0546830
X1427800Y0531378
X1431493Y0524304
X1432955Y0527449
X1427800Y0528578
X1435668Y0572975
X1442990Y0579475
X1442444Y0585507
X1447037Y0585507
X1438882Y0572842
X1439462Y0524629
X1439462Y0527129
X1435755Y0527449
X1439462Y0529929
X1446944Y0605443
X1434049Y0608311
X1435241Y0593796
X1447082Y0590190
X1442488Y0590145
X1454944Y0605443
X1425452Y0633473
X1407835Y0627713
X1413432Y0633716
X1407952Y0633724
X1418439Y0633736
X1430175Y0627852
X1420452Y0628078
X1378415Y0707776
X1378415Y0701984
X1437533Y0699280
X1433053Y0701839
X1435952Y0642184
X1418000Y0681000
X1418000Y0685000
X1383000Y0675500
X1378957Y0675457
X1451428Y0673252
X1378957Y0627988
X1378957Y0719488
X1386289Y0672488
X1434000Y0712958
X1431522Y0708633
X1378415Y0654984
X1378415Y0660776
X1417969Y0720894
X1410000Y0717000
X1418000Y0717000
X1384657Y0631620
X1378957Y0630957
X1418000Y0689000
X1418000Y0705000
X1437738Y0686992
X1429000Y0685000
X1378415Y0649795
X1378415Y0696795
X1397000Y0652000
X1460111Y0683536
X1397000Y0699000
X1433464Y0692658
X1437533Y0704398
X1468372Y0673812
X1418000Y0701000
X1451976Y0693844
X1397000Y0703000
X1438930Y0716363
X1426615Y0674112
X1397000Y0660000
X1448991Y0694392
X1397000Y0707000
X1446538Y0719548
X1433529Y0660564
X1397000Y0656000
X1425909Y0691120
X1430481Y0658153
X1446323Y0673183
X1461474Y0655807
X1455761Y0683448
X1418000Y0696000
X1398946Y0625311
X1426000Y0717000
X1404500Y0722000
X1405000Y0703000
X1405000Y0707000
X1410000Y0713000
X1410000Y0709000
X1410000Y0697000
X1410000Y0701000
X1404500Y0675000
X1410000Y0681000
X1410000Y0685000
X1383425Y0681425
X1405000Y0660000
X1405229Y0652028
X1398946Y0629311
X1391586Y0623692
X1383425Y0636925
X1437790Y0625013
X1383425Y0684140
X1381244Y0673623
X1383425Y0640075
X1381118Y0634033
X1388241Y0722000
X1388414Y0675000
X1391587Y0627817
X1410000Y0705000
X1410000Y0689000
X1405000Y0699000
X1405000Y0656000
X1407952Y0641817
X1413452Y0641817
X1426000Y0713000
X1426000Y0709000
X1424389Y0627948
X1427233Y0628183
X1437784Y0683532
X1440930Y0638805
X1440930Y0633205
X1440930Y0636005
X1437770Y0628242
X1453000Y0639050
X1453000Y0636250
X1453000Y0633450
X1405402Y0819917
X1401300Y0820485
X1375193Y0811724
X1406483Y0811717
X1402417Y0811692
X1398530Y0811717
X1394537Y0803653
X1390537Y0803679
X1386335Y0803704
X1381428Y0812287
X1437533Y0748398
X1447000Y0818500
X1454738Y0772492
X1446000Y0770500
X1454533Y0784780
X1450253Y0787339
X1418023Y0765343
X1418000Y0761000
X1410000Y0761000
X1437738Y0730992
X1429000Y0729000
X1433153Y0745839
X1385290Y0722400
X1378957Y0722457
X1437533Y0743280
X1391040Y0812027
X1385360Y0811757
X1447000Y0810500
X1453102Y0821102
X1451000Y0798458
X1451000Y0793458
X1434000Y0751958
X1434000Y0756958
X1427000Y0802500
X1407482Y0750853
X1435000Y0802500
X1404249Y0735858
X1418000Y0733000
X1435000Y0818500
X1373000Y0804000
X1409115Y0773520
X1381000Y0804000
X1371000Y0811620
X1447289Y0776461
X1454533Y0789898
X1430289Y0734961
X1418000Y0745000
X1414597Y0792375
X1418000Y0729000
X1435000Y0765500
X1418000Y0724000
X1418000Y0740000
X1406867Y0783273
X1435000Y0809500
X1435000Y0770500
X1460816Y0727964
X1455159Y0763714
X1454504Y0777575
X1455291Y0759656
X1446717Y0735536
X1446860Y0730735
X1435000Y0814500
X1443000Y0802500
X1426000Y0761000
X1427000Y0814500
X1427000Y0810500
X1427000Y0794500
X1427000Y0770500
X1427000Y0781834
X1427000Y0766500
X1410000Y0753000
X1410000Y0757000
X1410000Y0741000
X1410000Y0745000
X1410000Y0725000
X1410000Y0729000
X1383425Y0728425
X1383425Y0731575
X1381932Y0722547
X1410000Y0749000
X1410000Y0733000
X1427000Y0774500
X1426000Y0753000
X1426000Y0757000
X1436567Y0727532
X1453032Y0769032
X1427000Y0818500
X1427000Y0790500
X1443000Y0794500
X1443000Y0798500
X1453775Y0813032
X1390541Y0900086
X1387504Y0899931
X1448726Y0864400
X1417284Y0911009
X1426085Y0910281
X1429059Y0908579
X1376747Y0839320
X1399872Y0845109
X1395955Y0832697
X1376747Y0845619
X1383046Y0839320
X1379896Y0833021
X1402187Y0908270
X1394891Y0914783
X1413449Y0823934
X1376747Y0883413
X1388488Y0857822
X1391316Y0857849
X1370447Y0861367
X1376747Y0842470
X1400069Y0827515
X1390979Y0892923
X1385979Y0892923
X1388479Y0892923
X1387582Y0873487
X1390182Y0873460
X1387753Y0912629
X1376747Y0836170
X1413500Y0852000
X1448000Y0834500
X1413500Y0844000
X1413500Y0856000
X1413500Y0860000
X1413500Y0864000
X1383046Y0842470
X1370447Y0855068
X1453102Y0826500
X1454541Y0831339
X1413500Y0868000
X1413500Y0872000
X1427000Y0846500
X1413500Y0900000
X1417797Y0879501
X1370447Y0845619
X1370447Y0842470
X1383046Y0861367
X1413500Y0888000
X1413500Y0884000
X1413500Y0892000
X1417081Y0896000
X1379896Y0892862
X1413500Y0904000
X1452619Y0836457
X1449000Y0844500
X1435000Y0846500
X1435000Y0834500
X1383046Y0858218
X1413500Y0876000
X1373598Y0839319
X1379896Y0873964
X1383046Y0886562
X1373597Y0877114
X1379896Y0880263
X1413500Y0828000
X1413500Y0832000
X1413500Y0836000
X1413500Y0840000
X1413500Y0848000
X1370447Y0836170
X1370447Y0829871
X1373597Y0836170
X1370447Y0833021
X1373597Y0833021
X1376708Y0901000
X1404760Y0915186
X1376747Y0848769
X1405500Y0836000
X1373597Y0848769
X1405500Y0860000
X1370447Y0858218
X1373597Y0892862
X1370447Y0851918
X1379896Y0851918
X1379896Y0839320
X1379896Y0848769
X1370447Y0889712
X1435212Y0854042
X1373598Y0855067
X1370447Y0848769
X1376747Y0892862
X1373597Y0851918
X1383046Y0851918
X1402000Y0864000
X1373597Y0842470
X1376747Y0861367
X1373597Y0845619
X1402000Y0848000
X1373597Y0858218
X1376747Y0855068
X1405500Y0844000
X1373597Y0861367
X1370447Y0892862
X1376747Y0851918
X1402000Y0840000
X1379896Y0845619
X1376747Y0858218
X1383046Y0845619
X1387520Y0905307
X1383046Y0870814
X1373597Y0886562
X1402000Y0892000
X1405500Y0896000
X1373597Y0883413
X1379896Y0889712
X1379896Y0867665
X1383046Y0889712
X1373597Y0867665
X1376747Y0889712
X1402000Y0884000
X1376747Y0877114
X1402000Y0876000
X1376747Y0867665
X1373597Y0870814
X1376747Y0870814
X1405500Y0868000
X1370447Y0870814
X1383046Y0883413
X1383046Y0880263
X1376747Y0873964
X1370447Y0880263
X1383046Y0877114
X1402000Y0900000
X1373597Y0880263
X1379896Y0877114
X1405500Y0888000
X1370447Y0873964
X1376747Y0886562
X1373598Y0889713
X1370447Y0883413
X1405500Y0904000
X1405500Y0880000
X1373598Y0873965
X1435000Y0825500
X1434975Y0830500
X1370447Y0839320
X1370447Y0877114
X1379896Y0861367
X1379896Y0886562
X1376747Y0880263
X1383046Y0873964
X1379896Y0855068
X1452641Y0888033
X1461113Y0871389
X1441223Y0891957
X1447261Y0898571
X1439103Y0898564
X1383046Y0892862
X1435082Y0869475
X1462500Y0905295
X1423190Y0905295
X1451286Y0898549
X1443231Y0899006
X1445367Y0891888
X1457218Y0888764
X1435043Y0874694
X1435745Y0901500
X1443000Y0846500
X1409876Y0907848
X1417376Y0907848
X1414876Y0907848
X1412376Y0907848
X1413733Y0911137
X1388980Y0921075
X1439891Y0873821
X1427000Y0838500
X1427000Y0842500
X1427000Y0826500
X1427000Y0830500
X1379896Y0883413
X1370447Y0886562
X1379896Y0842470
X1383046Y0899161
X1379896Y0870814
X1379896Y0858218
X1383046Y0829871
X1396163Y0868597
X1395561Y0876204
X1396916Y0862829
X1413575Y0915186
X1404689Y0910897
X1424126Y0900295
X1422813Y0910065
X1427000Y0834500
X1435288Y0897500
X1449072Y0892581
X1437703Y0880067
X1443041Y0873683
X1438188Y0867633
X1443000Y0838500
X1443000Y0842500
X1459420Y0899226
X1460472Y0885985
X1462694Y0877859
X1462694Y0874859
X1461241Y0867475
X1370447Y0867665
X1383162Y0991829
X1398854Y0987277
X1402215Y1020440
X1419337Y0942285
X1461888Y0936055
X1402064Y0965913
X1430839Y0965546
X1439031Y0957683
X1468869Y1018469
X1440869Y1010256
X1382775Y0930281
X1420699Y0958452
X1435669Y1005366
X1381519Y0996280
X1389192Y0992568
X1392031Y1004375
X1394885Y0999941
X1378500Y0930500
X1370500Y0930500
X1457352Y0976277
X1419446Y0977192
X1428864Y0996766
X1428823Y1020266
X1416244Y0942285
X1382500Y0925500
X1370500Y0925500
X1459267Y1013678
X1467096Y0988813
X1401000Y0925789
X1465658Y1006648
X1458892Y1007522
X1463025Y1018307
X1374369Y0925499
X1374500Y0930500
X1378500Y0925500
X1459519Y0989432
X1457937Y0966712
X1458202Y0960288
X1462000Y0957000
X1369948Y0943603
X1440700Y0981763
X1435516Y0936000
X1373948Y0940103
X1441088Y0976409
X1414143Y0985486
X1407265Y0989465
X1401265Y0989465
X1396869Y0958707
X1416802Y0936845
X1424897Y0936777
X1429907Y0936998
X1456966Y0998507
X1412759Y1016266
X1376359Y1016825
X1378938Y1000586
X1412609Y1008766
X1412698Y0997590
X1373534Y1004680
X1374059Y1018860
X1374034Y1015825
X1373534Y1012325
X1446022Y0927000
X1405214Y0965074
X1428740Y1016266
X1420740Y1012266
X1420740Y0996766
X1428740Y1000766
X1420740Y1008766
X1416618Y0992307
X1433996Y0981437
X1448137Y0949440
X1444453Y0938806
X1427473Y0965621
X1411038Y0985379
X1383669Y1017303
X1383669Y1011303
X1370384Y1004680
X1371379Y0986717
X1398247Y0926261
X1395669Y1017303
X1389669Y1011303
X1395669Y1011303
X1404317Y0989436
X1413322Y0958908
X1420740Y1016266
X1420740Y1000766
X1420740Y1004766
X1427553Y0939200
X1440610Y1021567
X1439449Y0979009
X1466076Y0979746
X1460655Y0964253
X1462000Y0960378
X1462819Y0949996
X1451005Y0931848
X1455939Y1018368
X1462388Y1006560
X1467096Y0997860
X1468500Y0974181
X1411237Y1118396
X1443365Y1118396
X1377778Y1118396
X1398256Y1106867
X1430384Y1106867
X1373874Y1035716
X1373874Y1032266
X1399852Y1039779
X1399807Y1036155
X1459683Y1028377
X1419669Y1113648
X1423969Y1113648
X1426469Y1113648
X1421120Y1118801
X1421120Y1116101
X1418884Y1110597
X1416684Y1109397
X1414584Y1110897
X1416784Y1112397
X1414584Y1113797
X1391841Y1113648
X1387541Y1113648
X1388992Y1116101
X1388992Y1118801
X1394341Y1113648
X1386756Y1110597
X1384556Y1109397
X1382456Y1113797
X1382456Y1110897
X1384656Y1112397
X1418784Y1107997
X1414584Y1107997
X1416005Y1093088
X1386656Y1107997
X1388451Y1093048
X1382456Y1107997
X1416005Y1090288
X1405677Y1084296
X1408177Y1084296
X1410677Y1084296
X1413177Y1084296
X1415677Y1084296
X1415677Y1086796
X1413177Y1086796
X1410677Y1086796
X1408177Y1086796
X1405677Y1086796
X1390191Y1086724
X1390191Y1084224
X1390191Y1081724
X1392691Y1081724
X1392691Y1084224
X1392691Y1086724
X1392086Y1092743
X1392691Y1089224
X1388523Y1090090
X1396749Y1104792
X1428877Y1104792
X1404756Y1106897
X1385929Y1038665
X1387813Y1030952
X1371297Y1106897
X1389762Y1043055
X1436884Y1106897
X1384784Y1033783
X1385152Y1046591
X1385732Y1029482
X1456280Y1023405
X1404821Y1101917
X1436949Y1101917
X1371362Y1101917
X1432671Y1105552
X1378559Y1038534
X1400543Y1105552
X1442674Y1106365
X1410546Y1106298
X1377087Y1106365
X1377778Y1115896
X1374112Y1110092
X1369642Y1104335
X1403101Y1104335
X1407571Y1110092
X1435229Y1104335
X1411237Y1115896
X1443365Y1115896
X1439699Y1110092
X1465846Y1023900
X1435197Y1028372
X1417351Y1060697
X1409851Y1060697
X1407351Y1060697
X1412351Y1060697
X1414851Y1060697
X1417351Y1058097
X1409851Y1058097
X1407351Y1058097
X1412351Y1058097
X1414851Y1058097
X1420107Y1052514
X1392822Y1060498
X1392822Y1062998
X1390322Y1062998
X1390322Y1060498
X1392822Y1057998
X1392822Y1055498
X1390322Y1055498
X1390322Y1057998
X1376601Y1030218
X1383669Y1023303
X1369443Y1113822
X1369443Y1119422
X1371477Y1098767
X1374451Y1093068
X1374451Y1090568
X1397942Y1113822
X1400422Y1113822
X1400422Y1119422
X1397942Y1119422
X1394496Y1098428
X1399748Y1098518
X1389669Y1023303
X1395669Y1023303
X1402902Y1113822
X1402902Y1119422
X1404936Y1098767
X1430070Y1113822
X1430070Y1119422
X1432550Y1113822
X1432550Y1119422
X1426624Y1098428
X1431876Y1098518
X1430005Y1093068
X1430005Y1090568
X1420740Y1030766
X1435030Y1113822
X1435030Y1119422
X1437064Y1098767
X1435266Y1031522
X1465503Y1030233
X1468371Y1030701
X1379959Y1193471
X1379959Y1197471
X1375459Y1193471
X1375459Y1197471
X1416736Y1158200
X1436736Y1222194
X1432736Y1222194
X1428736Y1222194
X1424736Y1222194
X1420736Y1222194
X1416736Y1222194
X1412736Y1222194
X1408736Y1222194
X1437240Y1190121
X1437240Y1192621
X1418310Y1190121
X1418310Y1192621
X1404845Y1192621
X1404845Y1190121
X1410310Y1190121
X1410310Y1192621
X1391380Y1192621
X1391380Y1190121
X1437320Y1174884
X1434820Y1174884
X1434925Y1186921
X1434925Y1184421
X1434925Y1181921
X1434925Y1179421
X1420625Y1179209
X1420625Y1181709
X1420625Y1184209
X1420625Y1186709
X1419050Y1174884
X1407995Y1186921
X1407995Y1184421
X1407995Y1181921
X1407995Y1179421
X1406992Y1174884
X1409492Y1174884
X1416550Y1174884
X1393695Y1179209
X1393695Y1181709
X1393695Y1184209
X1393695Y1186709
X1391222Y1174884
X1388722Y1174884
X1437320Y1162384
X1437320Y1164884
X1437320Y1167384
X1437320Y1169884
X1437320Y1172384
X1434820Y1172384
X1434820Y1169884
X1434820Y1167384
X1434820Y1164884
X1434820Y1162384
X1442448Y1160834
X1419050Y1172384
X1419050Y1169884
X1419050Y1167384
X1419050Y1164884
X1419050Y1162384
X1409492Y1164884
X1409492Y1162384
X1406992Y1162384
X1406992Y1164884
X1406992Y1167384
X1416550Y1172384
X1416550Y1169884
X1416550Y1167384
X1416550Y1164884
X1416550Y1162384
X1406992Y1169884
X1406992Y1172384
X1409492Y1172384
X1409492Y1169884
X1409492Y1167384
X1391222Y1172384
X1391222Y1169884
X1391222Y1167384
X1391222Y1164884
X1391222Y1162384
X1388722Y1172384
X1388722Y1169884
X1388722Y1167384
X1388722Y1164884
X1388722Y1162384
X1383024Y1160834
X1376861Y1160834
X1371733Y1174884
X1369233Y1174884
X1369233Y1167384
X1369233Y1164884
X1369233Y1162384
X1371733Y1162384
X1371733Y1164884
X1371733Y1167384
X1371733Y1169884
X1371733Y1172384
X1369233Y1172384
X1369233Y1169884
X1413177Y1128894
X1409425Y1129238
X1383366Y1144435
X1383366Y1146935
X1383366Y1141935
X1375633Y1141935
X1375633Y1144435
X1375633Y1146935
X1376861Y1152684
X1383024Y1152684
X1371433Y1129301
X1371433Y1125801
X1383366Y1139435
X1383366Y1136935
X1383366Y1134435
X1383366Y1131935
X1375633Y1131935
X1375633Y1139435
X1375633Y1134435
X1375633Y1136935
X1393695Y1209405
X1393695Y1211905
X1393695Y1206905
X1391380Y1198321
X1391380Y1200821
X1393695Y1204405
X1385866Y1144435
X1385866Y1146935
X1385866Y1141935
X1391856Y1152713
X1391856Y1155213
X1399892Y1129301
X1397392Y1129301
X1394892Y1129301
X1392392Y1129301
X1389892Y1129301
X1387392Y1129301
X1399892Y1125801
X1397392Y1125801
X1388992Y1125801
X1385866Y1139435
X1385866Y1136935
X1385866Y1134435
X1385866Y1131935
X1399492Y1123101
X1396992Y1123101
X1388992Y1123101
X1409092Y1144435
X1409092Y1146935
X1415494Y1141935
X1415494Y1146935
X1415494Y1144435
X1402256Y1152713
X1402256Y1155213
X1416736Y1155213
X1416736Y1152713
X1409092Y1141935
X1404892Y1129301
X1402392Y1129301
X1404892Y1125801
X1402392Y1125801
X1409092Y1131935
X1409092Y1139435
X1409092Y1134435
X1409092Y1136935
X1415494Y1131935
X1415494Y1134435
X1415494Y1136935
X1415494Y1139435
X1407995Y1212117
X1407995Y1209617
X1407995Y1207117
X1404845Y1200821
X1404845Y1198321
X1410310Y1198321
X1410310Y1200821
X1407995Y1204617
X1419520Y1129301
X1432020Y1125801
X1429520Y1125801
X1421120Y1125801
X1417994Y1131935
X1417994Y1134435
X1417994Y1136935
X1417994Y1139435
X1431620Y1123101
X1429120Y1123101
X1421120Y1123101
X1420625Y1209405
X1420625Y1206905
X1418310Y1200821
X1418310Y1198321
X1420625Y1204405
X1417994Y1141935
X1417994Y1146935
X1417994Y1144435
X1422984Y1155213
X1422984Y1152713
X1432384Y1152713
X1432384Y1155213
X1432020Y1129301
X1429520Y1129301
X1427020Y1129301
X1424520Y1129301
X1422020Y1129301
X1442448Y1152684
X1441220Y1146935
X1441220Y1144435
X1441220Y1141935
X1437020Y1129301
X1434520Y1129301
X1437020Y1125801
X1434520Y1125801
X1441220Y1136935
X1441220Y1134435
X1441220Y1139435
X1441220Y1131935
X1434925Y1212117
X1434925Y1209617
X1434925Y1207117
X1437240Y1198321
X1437240Y1200821
X1434925Y1204617
X1440260Y1310698
X1443660Y1310698
X1424732Y1301603
X1428009Y1301760
X1389052Y1303139
X1385052Y1303139
X1417711Y1301729
X1421238Y1301712
X1431080Y1301702
X1410817Y1305417
X1428736Y1242194
X1428736Y1246194
X1424736Y1242194
X1424736Y1246194
X1420736Y1242194
X1420736Y1246194
X1408736Y1246194
X1408736Y1242194
X1416736Y1242194
X1416736Y1246194
X1412736Y1242194
X1412736Y1246194
X1436736Y1226194
X1432736Y1226194
X1432736Y1230194
X1432736Y1234194
X1428736Y1226194
X1428736Y1230194
X1428736Y1234194
X1428736Y1238194
X1424736Y1226194
X1424736Y1230194
X1424736Y1234194
X1424736Y1238194
X1420736Y1226194
X1420736Y1230194
X1420736Y1234194
X1420736Y1238194
X1416736Y1226194
X1416736Y1230194
X1416736Y1234194
X1416736Y1238194
X1412736Y1226194
X1412736Y1230194
X1412736Y1234194
X1412736Y1238194
X1408736Y1226194
X1408736Y1230194
X1408736Y1234194
X1408736Y1238194
X1421821Y1260160
X1418821Y1260160
X1418821Y1257160
X1421821Y1257160
X1406821Y1260160
X1403821Y1260160
X1415821Y1257160
X1415821Y1260160
X1403821Y1257160
X1406821Y1257160
X1409821Y1257160
X1412821Y1257160
X1412821Y1260160
X1409821Y1260160
X1391821Y1260160
X1394821Y1260160
X1388821Y1260160
X1400821Y1257160
X1400821Y1260160
X1397821Y1257160
X1397821Y1260160
X1388821Y1257160
X1385821Y1257160
X1394821Y1257160
X1391821Y1257160
X1385821Y1260160
X1404019Y1285290
X1415903Y1282590
X1390492Y1285466
X1385992Y1285466
X1377390Y1254164
X1377390Y1250760
X1377390Y1244055
X1439482Y1308312
X1444438Y1308312
X1425652Y1297411
X1436408Y1303462
X1414346Y1303020
X1432258Y1414600
X1435900Y1340800
X1441200Y1338700
X1439258Y1414600
X1446817Y1335846
X1461370Y1360099
X1461370Y1384297
X1464770Y1384297
X1464770Y1360099
X1461370Y1348187
X1461370Y1372385
X1465548Y1350683
X1465548Y1345691
X1460592Y1350683
X1460592Y1345691
X1465548Y1362595
X1465548Y1357603
X1460592Y1362595
X1460592Y1357603
X1465548Y1369889
X1465548Y1374881
X1465548Y1381801
X1460592Y1369889
X1460592Y1374881
X1460592Y1381801
X1465548Y1386793
X1460592Y1386793
X1428840Y1407740
X1433386Y1343309
X1441286Y1335776
X1464770Y1348187
X1464770Y1372385
X1421964Y1502813
X1407825Y1426975
X1423930Y1520364
X1420877Y1494706
X1430374Y1492474
X1432499Y1512175
X1423065Y1508327
X1422176Y1491198
X1372300Y1422900
X1372157Y1511977
X1372157Y1507246
X1372157Y1502515
X1372157Y1496622
X1372157Y1491891
X1372157Y1487160
X1372157Y1481268
X1372157Y1476537
X1372157Y1471806
X1372157Y1465914
X1372157Y1456452
X1372157Y1461183
X1443769Y1562173
X1443103Y1527201
X1446135Y1530876
X1429587Y1527450
X1440153Y1563093
X1441145Y1540415
X1408536Y1536570
X1433405Y1546001
X1408044Y1559306
X1407747Y1549054
X1407255Y1571732
X1432913Y1568679
X1433558Y1555366
X1425260Y1558072
X1423701Y1563978
X1425558Y1537432
X1424245Y1543338
X1423806Y1524252
X1437293Y1546125
X1404239Y1547755
X1436801Y1568803
X1403747Y1570433
X1372157Y1614338
X1372157Y1609607
X1372157Y1598984
X1372157Y1604876
X1372157Y1594253
X1372157Y1589522
X1372157Y1583629
X1372157Y1578898
X1372157Y1574167
X1372157Y1568275
X1372157Y1563544
X1372157Y1558813
X1372000Y1644980
X1392000Y1644980
X1412000Y1644980
X1432000Y1644980
X1452000Y1644980
X1472000Y1644980
X1492000Y1644980
X1512000Y1644980
X1532000Y1644980
X1552000Y1644980
X1476094Y1589522
X1476094Y1594253
X1476094Y1583629
X1476094Y1574167
X1476094Y1578898
X1476094Y1568275
X1476094Y1558813
X1476094Y1563544
X1476094Y1614338
X1476094Y1604876
X1476094Y1598984
X1476094Y1609607
X1493417Y1563544
X1493417Y1558813
X1484755Y1563144
X1493417Y1614338
X1484755Y1618669
X1484755Y1613938
X1493417Y1598984
X1493417Y1604876
X1493417Y1609607
X1484755Y1603315
X1484755Y1598584
X1484755Y1609207
X1493417Y1594253
X1493417Y1589522
X1493417Y1583629
X1484755Y1587960
X1484755Y1593853
X1484755Y1583229
X1493417Y1574167
X1493417Y1568275
X1484755Y1572606
X1484755Y1578498
X1484755Y1567875
X1493417Y1578898
X1510740Y1598984
X1510740Y1604876
X1510740Y1609607
X1502078Y1603315
X1502078Y1598584
X1502078Y1609207
X1510740Y1594253
X1510740Y1589522
X1510740Y1583629
X1502078Y1587960
X1502078Y1593853
X1502078Y1583229
X1510740Y1574167
X1510740Y1568275
X1502078Y1572606
X1502078Y1578498
X1502078Y1567875
X1510740Y1578898
X1510740Y1558813
X1502078Y1563144
X1510740Y1563544
X1510740Y1614338
X1502078Y1618669
X1502078Y1613938
X1519401Y1593853
X1519401Y1583229
X1528062Y1594253
X1528062Y1589522
X1528062Y1583629
X1519401Y1587960
X1528062Y1574167
X1528062Y1568275
X1519401Y1572606
X1519401Y1578498
X1519401Y1567875
X1528062Y1578898
X1528062Y1563544
X1528062Y1558813
X1519401Y1563144
X1528062Y1614338
X1519401Y1618669
X1519401Y1613938
X1528062Y1598984
X1528062Y1604876
X1528062Y1609607
X1519401Y1603315
X1519401Y1598584
X1519401Y1609207
X1536724Y1587960
X1536724Y1593853
X1545385Y1583629
X1536724Y1583229
X1545385Y1574167
X1545385Y1578898
X1536724Y1572606
X1536724Y1578498
X1545385Y1568275
X1536724Y1567875
X1536724Y1563144
X1545385Y1558813
X1545385Y1563544
X1536724Y1618669
X1536724Y1613938
X1545385Y1614338
X1545385Y1604876
X1545385Y1598984
X1545385Y1609607
X1536724Y1603315
X1536724Y1598584
X1536724Y1609207
X1545385Y1589522
X1545385Y1594253
X1476094Y1507245
X1476094Y1511976
X1476094Y1502514
X1476094Y1496621
X1476094Y1487159
X1476094Y1491890
X1476094Y1476536
X1476094Y1481267
X1476094Y1471805
X1476094Y1456451
X1476094Y1461182
X1476094Y1465913
X1484755Y1480867
X1484755Y1470244
X1493417Y1461182
X1493417Y1456451
X1493417Y1465913
X1484755Y1460782
X1484755Y1465513
X1484755Y1516307
X1493417Y1511976
X1493417Y1502514
X1493417Y1507245
X1484755Y1511576
X1484755Y1500952
X1484755Y1506845
X1484755Y1485598
X1484755Y1491490
X1493417Y1496621
X1493417Y1491890
X1493417Y1487159
X1484755Y1496221
X1484755Y1476136
X1493417Y1481267
X1493417Y1476536
X1493417Y1471805
X1510740Y1461182
X1510740Y1456451
X1510740Y1465913
X1502078Y1460782
X1502078Y1465513
X1502078Y1516307
X1502078Y1511576
X1502078Y1500952
X1502078Y1506845
X1510740Y1511976
X1510740Y1502514
X1510740Y1507245
X1510740Y1496621
X1510740Y1491890
X1510740Y1487159
X1502078Y1496221
X1502078Y1485598
X1502078Y1491490
X1502078Y1476136
X1510740Y1481267
X1510740Y1476536
X1510740Y1471805
X1502078Y1480867
X1502078Y1470244
X1528062Y1496621
X1528062Y1491890
X1528062Y1487159
X1519401Y1496221
X1519401Y1485598
X1519401Y1491490
X1528062Y1476536
X1528062Y1471805
X1519401Y1480867
X1519401Y1470244
X1519401Y1476136
X1528062Y1481267
X1528062Y1461182
X1528062Y1456451
X1528062Y1465913
X1519401Y1460782
X1519401Y1465513
X1519401Y1516307
X1528062Y1511976
X1528062Y1502514
X1528062Y1507245
X1519401Y1511576
X1519401Y1500952
X1519401Y1506845
X1545385Y1481268
X1545385Y1471806
X1545385Y1476537
X1536724Y1480867
X1536724Y1470244
X1536724Y1476136
X1545385Y1456452
X1545385Y1465914
X1536724Y1460782
X1536724Y1465513
X1545385Y1461183
X1536724Y1516307
X1545385Y1511977
X1545385Y1502515
X1545385Y1507246
X1536724Y1511576
X1536724Y1500952
X1536724Y1506845
X1545385Y1496622
X1545385Y1487160
X1545385Y1491891
X1536724Y1496221
X1536724Y1485598
X1536724Y1491490
X1547050Y1360099
X1550450Y1360099
X1547050Y1408495
X1534810Y1360099
X1522570Y1408495
X1538210Y1384297
X1550450Y1408495
X1525970Y1408495
X1562690Y1408495
X1550450Y1384297
X1534810Y1408495
X1559290Y1384297
X1562690Y1360099
X1559290Y1408495
X1538210Y1360099
X1534810Y1384297
X1562690Y1384297
X1559290Y1360099
X1547050Y1384297
X1538210Y1408495
X1501490Y1408495
X1477010Y1384297
X1477010Y1360099
X1489250Y1384297
X1522570Y1384297
X1513730Y1408495
X1477010Y1408495
X1489250Y1360099
X1510330Y1408495
X1510330Y1384297
X1513730Y1384297
X1485850Y1360099
X1498090Y1360099
X1485850Y1408495
X1498090Y1384297
X1513730Y1360099
X1501490Y1360099
X1489250Y1408495
X1473610Y1408495
X1501490Y1384297
X1473610Y1384297
X1485850Y1384297
X1473610Y1360099
X1498090Y1408495
X1510330Y1360099
X1525970Y1384297
X1525970Y1360099
X1522570Y1360099
X1522570Y1372385
X1501490Y1396583
X1473610Y1348187
X1498090Y1348187
X1501490Y1348187
X1513730Y1396583
X1522570Y1348187
X1473610Y1396583
X1498090Y1372385
X1510330Y1348187
X1525970Y1396583
X1547050Y1396583
X1550450Y1372385
X1559290Y1396583
X1534810Y1396583
X1562690Y1348187
X1534810Y1348187
X1559290Y1348187
X1563468Y1357603
X1558512Y1357603
X1558512Y1362595
X1551228Y1374881
X1551228Y1381801
X1551228Y1369889
X1563468Y1381801
X1563468Y1369889
X1563468Y1374881
X1558512Y1381801
X1558512Y1369889
X1558512Y1374881
X1551228Y1399079
X1551228Y1394087
X1551228Y1386793
X1563468Y1386793
X1563468Y1394087
X1563468Y1399079
X1558512Y1386793
X1558512Y1394087
X1558512Y1399079
X1551228Y1410991
X1551228Y1405999
X1563468Y1410991
X1563468Y1405999
X1558512Y1410991
X1558512Y1405999
X1538988Y1374881
X1538988Y1381801
X1538988Y1369889
X1534032Y1374881
X1534032Y1381801
X1534032Y1369889
X1546272Y1381801
X1546272Y1369889
X1546272Y1374881
X1538988Y1386793
X1538988Y1399079
X1538988Y1394087
X1534032Y1386793
X1534032Y1399079
X1534032Y1394087
X1546272Y1399079
X1546272Y1394087
X1546272Y1386793
X1538988Y1410991
X1538988Y1405999
X1534032Y1410991
X1534032Y1405999
X1546272Y1410991
X1546272Y1405999
X1551228Y1345691
X1551228Y1350683
X1563468Y1345691
X1563468Y1350683
X1558512Y1350683
X1558512Y1345691
X1551228Y1362595
X1551228Y1357603
X1563468Y1362595
X1521792Y1369889
X1521792Y1381801
X1521792Y1374881
X1526748Y1381801
X1526748Y1374881
X1526748Y1369889
X1521792Y1399079
X1521792Y1394087
X1521792Y1386793
X1526748Y1394087
X1526748Y1399079
X1526748Y1386793
X1521792Y1410991
X1521792Y1405999
X1526748Y1410991
X1526748Y1405999
X1538988Y1350683
X1538988Y1345691
X1534032Y1345691
X1534032Y1350683
X1546272Y1345691
X1546272Y1350683
X1538988Y1357603
X1538988Y1362595
X1534032Y1362595
X1534032Y1357603
X1546272Y1362595
X1546272Y1357603
X1502268Y1369889
X1502268Y1374881
X1502268Y1381801
X1514508Y1381801
X1514508Y1369889
X1514508Y1374881
X1509552Y1381801
X1509552Y1369889
X1509552Y1374881
X1502268Y1394087
X1502268Y1399079
X1502268Y1386793
X1514508Y1386793
X1514508Y1399079
X1514508Y1394087
X1509552Y1386793
X1509552Y1399079
X1509552Y1394087
X1502268Y1410991
X1502268Y1405999
X1514508Y1410991
X1514508Y1405999
X1509552Y1410991
X1509552Y1405999
X1521792Y1350683
X1521792Y1345691
X1526748Y1350683
X1526748Y1345691
X1521792Y1362595
X1521792Y1357603
X1526748Y1362595
X1526748Y1357603
X1497312Y1369889
X1497312Y1374881
X1497312Y1381801
X1490028Y1386793
X1490028Y1394087
X1490028Y1399079
X1485072Y1386793
X1485072Y1399079
X1485072Y1394087
X1497312Y1399079
X1497312Y1394087
X1497312Y1386793
X1490028Y1410991
X1490028Y1405999
X1485072Y1410991
X1485072Y1405999
X1497312Y1410991
X1497312Y1405999
X1502268Y1345691
X1502268Y1350683
X1514508Y1345691
X1514508Y1350683
X1509552Y1345691
X1509552Y1350683
X1502268Y1362595
X1502268Y1357603
X1514508Y1362595
X1514508Y1357603
X1509552Y1357603
X1509552Y1362595
X1472832Y1399079
X1472832Y1393993
X1472832Y1386793
X1477788Y1393993
X1477788Y1399079
X1477788Y1386793
X1472832Y1410991
X1472832Y1405999
X1477788Y1410991
X1477788Y1405999
X1490028Y1350683
X1490028Y1345691
X1485072Y1350683
X1485072Y1345691
X1497312Y1345691
X1497312Y1350683
X1490028Y1362595
X1490028Y1357603
X1485072Y1357603
X1485072Y1362595
X1497312Y1362595
X1497312Y1357603
X1490028Y1381801
X1490028Y1374881
X1490028Y1369889
X1485072Y1381801
X1485072Y1374881
X1485072Y1369889
X1472832Y1345691
X1472832Y1350683
X1477788Y1345691
X1477788Y1350683
X1472832Y1362595
X1472832Y1357603
X1477788Y1362595
X1477788Y1357603
X1472832Y1374881
X1472832Y1369795
X1472832Y1381801
X1477788Y1374881
X1477788Y1369795
X1477788Y1381801
X1538210Y1396583
X1547050Y1348187
X1547050Y1372385
X1562690Y1396583
X1522570Y1396583
X1534810Y1372385
X1550450Y1348187
X1550450Y1396583
X1538210Y1372385
X1513730Y1348187
X1559290Y1372385
X1501490Y1372385
X1562690Y1372385
X1477010Y1372385
X1538210Y1348187
X1485850Y1348187
X1477010Y1348187
X1513730Y1372385
X1489250Y1396583
X1489250Y1348187
X1510330Y1396583
X1485850Y1372385
X1485850Y1396583
X1525970Y1372385
X1477010Y1396583
X1489250Y1372385
X1473610Y1372385
X1498090Y1396583
X1525970Y1348187
X1510330Y1372385
X1507058Y1229402
X1507692Y1224472
X1506807Y1234921
X1500675Y1227300
X1497693Y1230407
X1484055Y1223749
X1496185Y1152491
X1496185Y1127291
X1496185Y1139891
X1480231Y1185164
X1474384Y1185164
X1480231Y1159964
X1474384Y1159964
X1480231Y1172564
X1474384Y1172564
X1480231Y1147364
X1474384Y1147364
X1480231Y1134764
X1474384Y1134764
X1496185Y1177691
X1496185Y1165091
X1501640Y1142891
X1496140Y1142891
X1496140Y1180691
X1501640Y1180691
X1501640Y1168091
X1496140Y1168091
X1496140Y1130291
X1501640Y1130291
X1501640Y1155491
X1496140Y1155491
X1479063Y1218169
X1489793Y1207737
X1508356Y1220068
X1483308Y1214372
X1482705Y1200001
X1540649Y1155610
X1536909Y1159350
X1536909Y1151870
X1480675Y1202103
X1477846Y1204932
X1492471Y1215195
X1498197Y1209607
X1474384Y1165091
X1480193Y1165091
X1483693Y1165091
X1505130Y1168091
X1474384Y1152491
X1480193Y1152491
X1483693Y1152491
X1505130Y1155491
X1474384Y1139891
X1480193Y1139891
X1483693Y1139891
X1505130Y1142891
X1474384Y1127291
X1480193Y1127291
X1483693Y1127291
X1505130Y1130291
X1505130Y1180691
X1483693Y1177691
X1474384Y1177691
X1480193Y1177691
X1532067Y1041832
X1526810Y1025090
X1480231Y1122164
X1474384Y1122164
X1480231Y1109564
X1474384Y1109564
X1491877Y1029427
X1486030Y1029427
X1496185Y1102091
X1482535Y1024254
X1496185Y1114691
X1496140Y1117691
X1501640Y1117691
X1513286Y1024954
X1507786Y1024954
X1501640Y1105091
X1496140Y1105091
X1503572Y1034538
X1517855Y1053457
X1531546Y1062769
X1522099Y1035521
X1531947Y1046212
X1521939Y1040818
X1524953Y1051037
X1531961Y1050849
X1471374Y1118654
X1473230Y1030672
X1476230Y1030672
X1531993Y1056453
X1479624Y1035102
X1471854Y1035088
X1474384Y1102091
X1480193Y1102091
X1483693Y1102091
X1505130Y1105091
X1474384Y1114691
X1480193Y1114691
X1483693Y1114691
X1505130Y1117691
X1516776Y1024954
X1548629Y0927836
X1548616Y0931602
X1480144Y0946880
X1507831Y1009354
X1522904Y1021256
X1487266Y1002046
X1490235Y1004816
X1475062Y1002453
X1475062Y1008300
X1491877Y1016827
X1486030Y1016827
X1507831Y1021954
X1507786Y1012354
X1513286Y1012354
X1527096Y0997860
X1515096Y0988813
X1519096Y0988813
X1483096Y0988813
X1503096Y0988813
X1523096Y0988813
X1499096Y0988813
X1475096Y0988813
X1495096Y0988813
X1531096Y0988813
X1471296Y0988813
X1491096Y0988813
X1479096Y0988813
X1507096Y0988813
X1487096Y0988813
X1511096Y0988813
X1480414Y0975064
X1479196Y0970000
X1552000Y0969850
X1482237Y0966028
X1480414Y0952214
X1530594Y0979952
X1525005Y0974323
X1519863Y0977637
X1521085Y0957340
X1496072Y0953981
X1501812Y0938397
X1487240Y0924453
X1516500Y0947500
X1484824Y0927324
X1528500Y0947612
X1485500Y0932500
X1551163Y0952888
X1489500Y0972500
X1495500Y0972500
X1509500Y0944138
X1509500Y0937000
X1509500Y0950500
X1521500Y0947500
X1480109Y0943496
X1471096Y0980330
X1475096Y0980330
X1530767Y0972981
X1511000Y0970500
X1476500Y0974000
X1479441Y0961941
X1529128Y0952978
X1522209Y0937846
X1527267Y0932647
X1482921Y0931324
X1483324Y0939324
X1496072Y0940201
X1497063Y0934000
X1487240Y0952012
X1497075Y0961000
X1512161Y0957541
X1498973Y0975443
X1525583Y0968500
X1551099Y0959096
X1474349Y0949394
X1475096Y0997860
X1471096Y0997860
X1479096Y0997860
X1492560Y0974654
X1485226Y0973886
X1486500Y0947000
X1482591Y0961909
X1496072Y0950044
X1496425Y0943075
X1485100Y0943900
X1487096Y0997860
X1495096Y0997860
X1483096Y0997860
X1491096Y0997860
X1499096Y0997860
X1511096Y0997860
X1503096Y0997860
X1507096Y0997860
X1510740Y0973740
X1514000Y0968739
X1501400Y0966000
X1505888Y0965964
X1513955Y0950396
X1510500Y0931500
X1514354Y0938811
X1523096Y0997860
X1519096Y0997860
X1531096Y0997860
X1515096Y0997860
X1523966Y0980281
X1525522Y0971075
X1530174Y0956986
X1525022Y0957340
X1524500Y0949500
X1528087Y0936394
X1527876Y0939439
X1525740Y0928740
X1523000Y0923740
X1486030Y1009354
X1491839Y1009354
X1495339Y1009354
X1516776Y1012354
X1486030Y1021954
X1491839Y1021954
X1495339Y1021954
X1482535Y1002453
X1482535Y1008262
X1482535Y1011762
X1522954Y0897951
X1522881Y0901034
X1512712Y0867418
X1548504Y0915689
X1476677Y0827626
X1482195Y0885807
X1494954Y0895264
X1495240Y0825000
X1473489Y0861354
X1480343Y0914776
X1493038Y0833898
X1492625Y0837324
X1486957Y0836457
X1488138Y0872839
X1486386Y0825296
X1488138Y0878339
X1515179Y0921094
X1521085Y0921094
X1505337Y0921240
X1502158Y0899479
X1504208Y0909740
X1518452Y0873780
X1518517Y0878898
X1509274Y0921226
X1525022Y0909558
X1547644Y0903060
X1548080Y0910757
X1500353Y0859855
X1504938Y0859711
X1513927Y0908951
X1510527Y0908951
X1474883Y0868206
X1473387Y0897425
X1473433Y0891043
X1482387Y0872940
X1473468Y0874267
X1474060Y0877196
X1482566Y0882154
X1470925Y0920575
X1500638Y0873839
X1510527Y0833500
X1491425Y0842425
X1496621Y0829000
X1481454Y0911570
X1510280Y0899732
X1473634Y0864337
X1474075Y0920575
X1487075Y0920925
X1496000Y0922000
X1496500Y0919000
X1497208Y0909740
X1496383Y0898023
X1492101Y0894860
X1498084Y0894825
X1494000Y0884000
X1491414Y0875383
X1497488Y0873839
X1489805Y0866386
X1489650Y0836985
X1496500Y0836000
X1491425Y0845575
X1507305Y0912262
X1498446Y0912370
X1507358Y0909740
X1507034Y0888133
X1526611Y0921442
X1523053Y0912262
X1519116Y0912240
X1516283Y0912240
X1517153Y0908367
X1517344Y0903179
X1515743Y0888133
X1517344Y0896999
X1519063Y0876339
X1547813Y0906581
X1470801Y0739280
X1471006Y0744818
X1497000Y0781000
X1496814Y0773000
X1496806Y0817000
X1480000Y0739500
X1480000Y0731500
X1496845Y0809000
X1487050Y0809413
X1495170Y0796670
X1486957Y0792457
X1493716Y0789898
X1476716Y0748398
X1474000Y0753093
X1469957Y0750957
X1496629Y0765000
X1479665Y0754555
X1472000Y0727500
X1499633Y0787794
X1493092Y0820444
X1493301Y0776911
X1488731Y0739500
X1488000Y0731500
X1496447Y0821000
X1504495Y0796844
X1491425Y0798425
X1496756Y0785000
X1496763Y0777000
X1474425Y0756925
X1495500Y0750500
X1479657Y0735500
X1479759Y0743500
X1474425Y0760075
X1479500Y0750500
X1471415Y0748629
X1479962Y0727500
X1496473Y0769000
X1496845Y0813000
X1491425Y0801575
X1496500Y0792000
X1491062Y0793003
X1479500Y0697630
X1479500Y0689630
X1479794Y0709388
X1568872Y0686971
X1474000Y0707000
X1469957Y0706957
X1561552Y0665455
X1476716Y0704398
X1474713Y0685247
X1475264Y0680933
X1469116Y0719055
X1479759Y0720885
X1476794Y0691447
X1524200Y0646098
X1520729Y0634190
X1519185Y0623600
X1564670Y0650122
X1474425Y0712925
X1477597Y0682997
X1479297Y0693630
X1565132Y0668153
X1478710Y0685630
X1474425Y0716075
X1479500Y0706500
X1473525Y0710052
X1523646Y0634946
X1565132Y0677843
X1561535Y0653161
X1562385Y0610400
X1519185Y0619600
X1519185Y0603600
X1546875Y0550907
X1544375Y0550907
X1546875Y0553407
X1544375Y0553407
X1546183Y0545263
X1546183Y0541863
X1548645Y0566929
X1548359Y0569426
X1546036Y0568475
X1546293Y0570962
X1543946Y0569928
X1542704Y0572162
X1513284Y0552466
X1556588Y0545528
X1565323Y0577716
X1519952Y0524033
X1519952Y0538206
X1509550Y0531094
X1512046Y0526916
X1507054Y0531872
X1512046Y0531872
X1507054Y0526916
X1511963Y0536382
X1528635Y0555234
X1522448Y0524811
X1522448Y0534028
X1517456Y0534028
X1517456Y0524811
X1517456Y0538984
X1522448Y0538984
X1519153Y0607588
X1519185Y0615600
X1516930Y0597580
X1519153Y0599588
X1518415Y0589556
X1518354Y0592354
X1516869Y0594668
X1519156Y0596095
X1528350Y0562003
X1562385Y0606400
X1562385Y0614400
X1548374Y0595108
X1562385Y0594400
X1562385Y0602400
X1562385Y0598400
X1547910Y0602197
X1556900Y0574102
X1558127Y0560675
X1558668Y0572334
X1556359Y0562443
X1557036Y0550123
X1556914Y0552872
X1548629Y0547106
X1556429Y0525847
X1548629Y0532933
X1548629Y0525847
X1548629Y0540020
X1519952Y0534806
X1509550Y0527694
X1520200Y0455921
X1516636Y0458711
X1471375Y0433115
X1518780Y0463600
X1521963Y0453682
X1519952Y0433521
X1509550Y0513521
X1509550Y0426460
X1509550Y0486960
X1509550Y0483560
X1509550Y0429860
X1519952Y0490673
X1509550Y0516921
X1509550Y0469387
X1519952Y0520633
X1509550Y0444033
X1509550Y0440633
X1519952Y0476499
X1566329Y0479104
X1565482Y0472772
X1548629Y0474626
X1556429Y0474626
X1548629Y0481713
X1556690Y0480828
X1522448Y0475721
X1522448Y0480677
X1517456Y0475721
X1517456Y0480677
X1512046Y0482782
X1507054Y0482782
X1512046Y0473565
X1507054Y0473565
X1473900Y0433100
X1469293Y0428815
X1507054Y0430638
X1512046Y0430638
X1507054Y0439855
X1512046Y0439855
X1507054Y0425682
X1512046Y0425682
X1522448Y0423525
X1517456Y0423525
X1512046Y0468609
X1507054Y0468609
X1507864Y0450750
X1507054Y0444811
X1512046Y0444811
X1522448Y0432743
X1517456Y0437699
X1517456Y0432743
X1522448Y0437699
X1548629Y0467539
X1556429Y0467539
X1548629Y0445847
X1558160Y0445847
X1548629Y0431673
X1548629Y0438760
X1548629Y0424587
X1557849Y0426299
X1566740Y0467539
X1567573Y0447953
X1565538Y0436447
X1565933Y0429832
X1565863Y0422864
X1512046Y0512743
X1507054Y0512743
X1512046Y0517699
X1507054Y0517699
X1512046Y0487738
X1507054Y0487738
X1522448Y0519855
X1517456Y0519855
X1522448Y0494851
X1517456Y0494851
X1522448Y0489895
X1517456Y0489895
X1556429Y0511673
X1556429Y0518760
X1562089Y0516841
X1548629Y0518760
X1548629Y0511673
X1558640Y0498834
X1548629Y0495886
X1548629Y0488799
X1565050Y0511673
X1566740Y0495886
X1566216Y0487711
X1519436Y0458711
X1509550Y0472787
X1519952Y0494073
X1519952Y0436921
X1519952Y0422747
X1519952Y0479899
X1494286Y0372699
X1469538Y0416795
X1480702Y0368516
X1516838Y0347422
X1515909Y0354601
X1486890Y0368576
X1545434Y0352363
X1499839Y0354001
X1495925Y0358700
X1486360Y0322700
X1475236Y0412482
X1551175Y0347283
X1544951Y0343363
X1553862Y0344867
X1545846Y0334363
X1553597Y0336601
X1542797Y0329863
X1545636Y0325363
X1553910Y0331798
X1553534Y0327337
X1495521Y0340700
X1495605Y0322700
X1500659Y0330024
X1495689Y0332534
X1486860Y0327200
X1487152Y0331272
X1501684Y0336561
X1486913Y0340327
X1500386Y0344642
X1495521Y0349681
X1486360Y0345200
X1486360Y0349700
X1519321Y0382600
X1563877Y0352363
X1538133Y0354553
X1477549Y0354200
X1477549Y0349700
X1477549Y0358700
X1563877Y0334363
X1563877Y0343363
X1563877Y0329863
X1477549Y0331700
X1477549Y0340700
X1477549Y0345200
X1563877Y0325363
X1477549Y0322700
X1477549Y0327200
X1519952Y0419347
X1519952Y0391001
X1511950Y0398113
X1519952Y0405174
X1519952Y0408574
X1511950Y0401513
X1509550Y0415687
X1472403Y0417338
X1473364Y0410724
X1483813Y0368516
X1486360Y0354200
X1486360Y0358700
X1487926Y0347387
X1497760Y0336543
X1484682Y0338394
X1488255Y0342921
X1484876Y0329377
X1484968Y0325025
X1512046Y0416465
X1507054Y0411509
X1507054Y0416465
X1512046Y0411509
X1514446Y0397335
X1509454Y0397335
X1514446Y0402291
X1509454Y0402291
X1501807Y0323766
X1522448Y0418569
X1517456Y0418569
X1522448Y0409352
X1522448Y0404396
X1522448Y0395179
X1517456Y0409352
X1517456Y0404396
X1517456Y0395179
X1522448Y0390223
X1517456Y0390223
X1515779Y0351594
X1541283Y0354553
X1548629Y0396240
X1561778Y0396240
X1557708Y0404911
X1556429Y0396240
X1548629Y0410413
X1548629Y0403327
X1548629Y0389154
X1563248Y0389154
X1556429Y0389154
X1554403Y0352363
X1556353Y0345636
X1556498Y0340958
X1556380Y0336917
X1556437Y0332022
X1556294Y0327814
X1541534Y0322850
X1548629Y0417500
X1556662Y0412571
X1566555Y0414823
X1519321Y0378600
X1509550Y0412287
X1519952Y0394401
X1501000Y0317500
X1501500Y0321000
X1499171Y0256394
X1550695Y0281716
X1554147Y0265896
X1556636Y0281982
X1489208Y0249108
X1549060Y0265701
X1559163Y0266114
X1491828Y0244571
X1475101Y0228631
X1554388Y0256303
X1496221Y0228646
X1505217Y0227824
X1500962Y0230556
X1509807Y0230117
X1507524Y0244297
X1531609Y0258880
X1503884Y0295549
X1497446Y0295877
X1544736Y0305156
X1550931Y0305158
X1539140Y0320863
X1545583Y0316363
X1554403Y0316363
X1487318Y0318200
X1545878Y0267526
X1540578Y0267526
X1543378Y0267526
X1540578Y0270026
X1543378Y0270026
X1545878Y0270026
X1531684Y0264180
X1534184Y0264180
X1480589Y0248371
X1495178Y0232971
X1505304Y0246874
X1563877Y0316363
X1499947Y0242078
X1493260Y0226320
X1505823Y0238714
X1471507Y0265897
X1562409Y0270695
X1562409Y0268195
X1562212Y0248765
X1562271Y0236189
X1561720Y0228221
X1561720Y0231021
X1560020Y0224421
X1564909Y0268195
X1564909Y0270695
X1567709Y0268195
X1567709Y0270695
X1567212Y0248765
X1564712Y0248765
X1567271Y0236189
X1564771Y0236189
X1480589Y0252371
X1484796Y0320359
X1495071Y0253198
X1495152Y0236121
X1492186Y0238589
X1500480Y0295727
X1501588Y0238689
X1502362Y0247292
X1509823Y0238714
X1528355Y0231226
X1528355Y0226226
X1528355Y0223726
X1528355Y0228726
X1544963Y0248891
X1542463Y0248891
X1546780Y0231786
X1545261Y0236611
X1542761Y0236611
X1545318Y0226141
X1538811Y0223661
X1546780Y0229286
X1538811Y0231461
X1538811Y0228961
X1542518Y0226141
X1538811Y0226461
X1534401Y0293796
X1545215Y0285690
X1545215Y0288190
X1542415Y0288190
X1539915Y0285690
X1542415Y0285690
X1539915Y0288190
X1531901Y0293796
X1556151Y0318596
X1547972Y0304906
X1557441Y0290755
X1553441Y0290755
X1549441Y0290755
X1563522Y0281307
X1559418Y0279208
X1547463Y0248891
X1558388Y0256535
X1550388Y0256535
X1547761Y0236611
X1550473Y0224712
X1565512Y0290845
X1565512Y0293645
X1568012Y0288345
X1568012Y0290845
X1568012Y0293645
X1565512Y0288345
X1484124Y0124879
X1553663Y0148277
X1479058Y0124283
X1489146Y0124663
X1568433Y0152373
X1556283Y0143740
X1470086Y0172665
X1494127Y0125107
X1490490Y0138838
X1478913Y0186778
X1474716Y0157370
X1496641Y0148717
X1564846Y0141247
X1502741Y0143762
X1478832Y0208864
X1470203Y0200864
X1470226Y0207037
X1470292Y0212455
X1478800Y0196665
X1478800Y0192665
X1554124Y0177616
X1554705Y0172190
X1557378Y0168697
X1554144Y0215632
X1538811Y0215713
X1550441Y0213859
X1550441Y0211359
X1554144Y0213132
X1538811Y0208213
X1545683Y0208695
X1542883Y0208695
X1545383Y0211695
X1542883Y0211695
X1538811Y0210713
X1538811Y0213213
X1528355Y0207978
X1528355Y0212978
X1528355Y0215478
X1528355Y0210478
X1549022Y0184012
X1546405Y0184221
X1549408Y0181366
X1552203Y0181009
X1546197Y0181426
X1566520Y0192490
X1566990Y0171523
X1470023Y0178560
X1469913Y0183834
X1469433Y0190185
X1469221Y0152562
X1474473Y0219379
X1483881Y0218085
X1486681Y0218085
X1493194Y0219470
X1493194Y0216970
X1490481Y0216385
X1493194Y0221970
X1478832Y0204864
X1558466Y0191941
X1470899Y0186629
X1478800Y0176665
X1478800Y0168665
X1477465Y0161306
X1548816Y0141247
X1495600Y0142862
X1502010Y0132515
X1547200Y0170493
X1547200Y0167993
X1547200Y0165393
X1547200Y0162793
X1537500Y0162368
X1540100Y0162368
X1509310Y0128828
X1509310Y0125428
X1502010Y0135915
X1545044Y0147540
X1503543Y0206806
X1501770Y0210509
X1501043Y0206806
X1499270Y0210509
X1503207Y0201748
X1506207Y0202048
X1504189Y0195176
X1499189Y0195176
X1503207Y0199248
X1501689Y0195176
X1506207Y0199248
X1506689Y0195176
X1563105Y0221708
X1560605Y0221708
X1562975Y0206767
X1560475Y0206767
X1565605Y0221708
X1565475Y0206767
X1549627Y0125396
X1481368Y0130898
X1491942Y0195176
X1484142Y0195176
X1483014Y0134579
X1497506Y0141228
X1495600Y0146012
X1488867Y0133298
X1478832Y0221864
X1478832Y0216864
X1478832Y0212864
X1478832Y0200864
X1478800Y0172665
X1478800Y0180665
X1486502Y0203393
X1484002Y0203393
X1490190Y0206838
X1492690Y0206838
X1488761Y0201683
X1489142Y0195176
X1488761Y0198883
X1486642Y0195176
X1508142Y0213539
X1500394Y0150847
X1504410Y0137757
X1499610Y0137757
X1511610Y0137756
X1511610Y0130670
X1506910Y0123583
X1504410Y0123584
X1504410Y0130670
X1506910Y0130670
X1499610Y0123584
X1499610Y0130670
X1511610Y0123583
X1521082Y0137756
X1526311Y0137756
X1521087Y0130670
X1529720Y0123583
X1529720Y0130670
X1520034Y0124576
X1548561Y0188727
X1545044Y0151540
X1537720Y0137756
X1547131Y0124618
X1537720Y0123583
X1537720Y0130670
X1547131Y0129574
X1561226Y0180572
X1559526Y0152367
X1562525Y0136687
X1557533Y0136687
X1560624Y0146461
X1562525Y0131731
X1557533Y0122513
X1557533Y0131731
X1552123Y0124618
X1552123Y0129574
X1562525Y0122513
X1550473Y0222212
X1557174Y0206760
X1561226Y0185165
X1555194Y0184619
X1548694Y0191941
X1565864Y0185121
X1565909Y0180527
X1560029Y0135909
X1560029Y0132509
X1549627Y0128796
X1484567Y0110784
X1489567Y0110784
X1490563Y0023043
X1489829Y0029424
X1504460Y0095111
X1470567Y0103621
X1557286Y0097475
X1519610Y0095236
X1564267Y0100625
X1529543Y0095236
X1529493Y0099961
X1568640Y0112083
X1477606Y0060438
X1479380Y0094279
X1474746Y0060513
X1475431Y0094351
X1508829Y0106561
X1483287Y0086012
X1540478Y0104249
X1540478Y0107649
X1478428Y0086046
X1474874Y0085731
X1519860Y0090650
X1562828Y0076587
X1525172Y0090615
X1562828Y0072615
X1495866Y0102495
X1478624Y0119594
X1478624Y0116594
X1483287Y0094374
X1472514Y0088801
X1479972Y0040780
X1498621Y0023043
X1498621Y0031043
X1502010Y0118342
X1538407Y0077739
X1538407Y0080339
X1538407Y0075139
X1538407Y0082939
X1538407Y0085539
X1509310Y0111255
X1509310Y0114655
X1502010Y0121742
X1538451Y0092874
X1509064Y0097667
X1508670Y0103411
X1550282Y0103783
X1557217Y0106186
X1490593Y0119594
X1490593Y0116594
X1546732Y0098551
X1500210Y0097667
X1472146Y0055513
X1549627Y0114623
X1549627Y0111223
X1560029Y0118335
X1481273Y0110784
X1478624Y0113394
X1471093Y0117261
X1472489Y0091951
X1475296Y0055513
X1480460Y0060922
X1476822Y0040780
X1495866Y0106495
X1496859Y0109172
X1493859Y0109172
X1482842Y0102249
X1486842Y0102249
X1490842Y0102249
X1498621Y0027043
X1498621Y0035043
X1506910Y0109410
X1504410Y0116497
X1506910Y0116497
X1499610Y0116497
X1511610Y0102323
X1511610Y0109410
X1511610Y0116496
X1509260Y0053597
X1501939Y0044773
X1501939Y0024773
X1529720Y0109410
X1529720Y0116496
X1519862Y0116496
X1519862Y0109410
X1519610Y0102323
X1529586Y0103037
X1520072Y0085584
X1522626Y0092849
X1520072Y0080384
X1520072Y0077784
X1520072Y0075184
X1520072Y0082984
X1529260Y0053597
X1537720Y0102323
X1537720Y0109410
X1537720Y0116496
X1547131Y0115401
X1547131Y0110445
X1546732Y0101701
X1543003Y0094017
X1547003Y0094017
X1547367Y0044773
X1554282Y0103783
X1552123Y0110445
X1552123Y0115401
X1557533Y0117557
X1562525Y0117557
X1551003Y0094017
X1555012Y0094017
X1560080Y0080140
X1560080Y0076140
X1560080Y0084140
X1565449Y0103621
X1560029Y0121735
X1517261Y-0043758
X1517261Y-0030358
X1517261Y-0040358
X1592187Y-0082706
X1592187Y-0079306
X1517261Y-0033758
X1481905Y-0072678
X1481905Y-0069278
X1489556Y0017645
X1594683Y-0078528
X1594683Y-0083484
X1514765Y-0034536
X1514765Y-0029580
X1514765Y-0039580
X1514765Y-0044536
X1479409Y-0073456
X1479409Y-0068500
X1589281Y-0086399
X1582988Y-0085204
X1586241Y-0085204
X1583000Y-0082514
X1583003Y-0087719
X1586256Y-0087719
X1583000Y-0080014
X1520167Y-0047451
X1520167Y-0036965
X1520167Y-0026665
X1526448Y-0043664
X1526460Y-0046342
X1523207Y-0046342
X1526445Y-0048857
X1523192Y-0048857
X1526460Y-0038174
X1526448Y-0041064
X1523207Y-0038160
X1526460Y-0027860
X1523207Y-0027860
X1526448Y-0030550
X1526445Y-0025345
X1523192Y-0025345
X1526445Y-0035659
X1523192Y-0035645
X1526448Y-0033050
X1484811Y-0075885
X1484811Y-0065585
X1491104Y-0077094
X1487851Y-0077080
X1491104Y-0066780
X1487851Y-0066780
X1491092Y-0069470
X1491089Y-0064265
X1487836Y-0064265
X1491089Y-0074579
X1487836Y-0074565
X1491092Y-0071970
X1498621Y0019043
X1498621Y0015043
X1484594Y0003000
X1500578Y0004469
X1582187Y-0040386
X1582187Y-0030386
X1592187Y-0072706
X1481905Y-0082678
X1481905Y-0079278
X1592187Y-0069306
X1582187Y-0043786
X1582187Y-0033786
X1584683Y-0039608
X1584683Y-0034564
X1584683Y-0029608
X1584683Y-0044564
X1594683Y-0073484
X1594683Y-0068528
X1479409Y-0078500
X1479409Y-0083456
X1589281Y-0065613
X1589281Y-0076099
X1583000Y-0069400
X1582988Y-0066722
X1586241Y-0066722
X1583003Y-0064207
X1586256Y-0064207
X1582988Y-0074890
X1583000Y-0072000
X1586241Y-0074904
X1583003Y-0077405
X1586256Y-0077419
X1579281Y-0026693
X1579281Y-0037179
X1579281Y-0047479
X1573000Y-0030480
X1572988Y-0027802
X1576241Y-0027788
X1573003Y-0025287
X1576256Y-0025273
X1572988Y-0035970
X1573000Y-0033080
X1576241Y-0035984
X1572988Y-0046284
X1576241Y-0046284
X1573000Y-0043594
X1573003Y-0048799
X1576256Y-0048799
X1573003Y-0038485
X1576256Y-0038499
X1573000Y-0041094
X1484811Y-0086371
X1491092Y-0082584
X1491104Y-0085262
X1487851Y-0085262
X1491089Y-0087777
X1487836Y-0087777
X1491092Y-0079984
X1650417Y0005374
X1591929Y0110784
X1586929Y0110784
X1606822Y0095111
X1666629Y0100625
X1659648Y0097475
X1621972Y0095236
X1572929Y0103621
X1631855Y0099961
X1631905Y0095236
X1611191Y0106561
X1585649Y0086012
X1577108Y0060513
X1577793Y0094351
X1579968Y0060438
X1581742Y0094279
X1642840Y0107649
X1642840Y0104249
X1577236Y0085731
X1580790Y0086046
X1627534Y0090615
X1665190Y0072615
X1622222Y0090650
X1665190Y0076587
X1598228Y0102495
X1580986Y0119594
X1580986Y0116594
X1585649Y0094374
X1574876Y0088801
X1611426Y0097667
X1640813Y0092874
X1611672Y0114655
X1640769Y0077739
X1640769Y0080339
X1640769Y0075139
X1640769Y0082939
X1640769Y0085539
X1611032Y0103411
X1611672Y0111255
X1604372Y0121742
X1659579Y0106186
X1652644Y0103783
X1592955Y0116594
X1592955Y0119594
X1649094Y0098551
X1602572Y0097667
X1604372Y0118342
X1570746Y0080581
X1570733Y0068581
X1571895Y0058013
X1651989Y0111223
X1651989Y0114623
X1573455Y0117261
X1574851Y0091951
X1580327Y0057448
X1593204Y0102249
X1582822Y0060922
X1583635Y0110784
X1580986Y0113394
X1589204Y0102249
X1585204Y0102249
X1598228Y0106495
X1599221Y0109172
X1596221Y0109172
X1606772Y0116497
X1609272Y0116497
X1601972Y0116497
X1609272Y0109410
X1611622Y0053597
X1604301Y0044773
X1631622Y0053597
X1613972Y0109410
X1613972Y0102323
X1613972Y0116496
X1622224Y0116496
X1622224Y0109410
X1621972Y0102323
X1622434Y0085584
X1624988Y0092849
X1622434Y0077784
X1622434Y0075184
X1622434Y0080384
X1622434Y0082984
X1640082Y0102323
X1640082Y0109410
X1640082Y0116496
X1632082Y0109410
X1632082Y0116496
X1631948Y0103037
X1656644Y0103783
X1649493Y0115401
X1649493Y0110445
X1654485Y0115401
X1654485Y0110445
X1659895Y0117557
X1649094Y0101701
X1645365Y0094017
X1653365Y0094017
X1657374Y0094017
X1649365Y0094017
X1649730Y0044773
X1649730Y0024773
X1667811Y0103621
X1664887Y0117557
X1662442Y0080140
X1662442Y0076140
X1662442Y0084140
X1662391Y0121735
X1662391Y0118335
X1656025Y0148277
X1591508Y0124663
X1586486Y0124879
X1581420Y0124283
X1658645Y0143740
X1664840Y0192300
X1572448Y0172665
X1596489Y0125107
X1569333Y0143518
X1592852Y0138838
X1581275Y0186778
X1577078Y0157370
X1599003Y0148717
X1605103Y0143762
X1581194Y0208864
X1572588Y0207037
X1572565Y0200864
X1572654Y0212455
X1581162Y0196665
X1667318Y0198828
X1581162Y0192665
X1667208Y0141247
X1572385Y0178560
X1668882Y0192490
X1657067Y0172190
X1659740Y0168697
X1656506Y0215632
X1641173Y0215713
X1645245Y0211695
X1652803Y0213859
X1652803Y0211359
X1656506Y0213132
X1648045Y0208695
X1645245Y0208695
X1647745Y0211695
X1630717Y0207978
X1630717Y0212978
X1630717Y0215478
X1630717Y0210478
X1641173Y0208213
X1641173Y0210713
X1641173Y0213213
X1648767Y0184221
X1651384Y0184012
X1651770Y0181366
X1648559Y0181426
X1654565Y0181009
X1571795Y0190185
X1572275Y0183834
X1656486Y0177616
X1571583Y0152562
X1576835Y0219379
X1589043Y0218085
X1595556Y0221970
X1595556Y0219470
X1595556Y0216970
X1592843Y0216385
X1586243Y0218085
X1581194Y0204864
X1660828Y0191941
X1573261Y0186629
X1581162Y0176665
X1581162Y0168665
X1579827Y0161306
X1651178Y0141247
X1597962Y0142862
X1604372Y0135915
X1604372Y0132515
X1649562Y0170493
X1649562Y0167993
X1649562Y0165393
X1649562Y0162793
X1642462Y0162368
X1639862Y0162368
X1611672Y0128828
X1611672Y0125428
X1647406Y0147540
X1605569Y0201748
X1608569Y0202048
X1604132Y0210509
X1601632Y0210509
X1605905Y0206806
X1603405Y0206806
X1608569Y0199248
X1609051Y0195176
X1606551Y0195176
X1601551Y0195176
X1605569Y0199248
X1604051Y0195176
X1569955Y0221642
X1662967Y0221708
X1665467Y0221708
X1667967Y0221708
X1665337Y0206767
X1667837Y0206767
X1662837Y0206767
X1651989Y0128796
X1651989Y0125396
X1662391Y0132509
X1569632Y0192421
X1581194Y0216864
X1581194Y0221864
X1592552Y0206838
X1595052Y0206838
X1591123Y0201683
X1588864Y0203393
X1586364Y0203393
X1581194Y0200864
X1581194Y0212864
X1591504Y0195176
X1591123Y0198883
X1589004Y0195176
X1594304Y0195176
X1586504Y0195176
X1581162Y0172665
X1581162Y0180665
X1585376Y0134579
X1583229Y0133298
X1591229Y0133298
X1610504Y0213539
X1602756Y0150847
X1601972Y0137757
X1599868Y0141228
X1597962Y0146012
X1606772Y0137757
X1606772Y0130670
X1609272Y0130670
X1609272Y0123583
X1606772Y0123584
X1601972Y0130670
X1601972Y0123584
X1613972Y0137756
X1623444Y0137756
X1613972Y0123583
X1613972Y0130670
X1623449Y0130670
X1622396Y0124576
X1640082Y0137756
X1628673Y0137756
X1640082Y0123583
X1640082Y0130670
X1632082Y0123583
X1632082Y0130670
X1659895Y0136687
X1649493Y0129574
X1649493Y0124618
X1654485Y0129574
X1654485Y0124618
X1659895Y0131731
X1659895Y0122513
X1652835Y0222212
X1659536Y0206760
X1650923Y0188727
X1657556Y0184619
X1651056Y0191941
X1647406Y0151540
X1668226Y0185121
X1663588Y0185165
X1668271Y0180527
X1663588Y0180572
X1661888Y0152367
X1664887Y0136687
X1662986Y0146461
X1664887Y0131731
X1664887Y0122513
X1662391Y0135909
X1604677Y0253198
X1658998Y0281982
X1651422Y0265701
X1591570Y0249108
X1661525Y0266114
X1656509Y0265896
X1653057Y0281716
X1594190Y0244571
X1656750Y0256303
X1577463Y0228631
X1598583Y0228646
X1612169Y0230117
X1607579Y0227824
X1603324Y0230556
X1633971Y0258880
X1609886Y0244297
X1596197Y0293477
X1596691Y0287397
X1648240Y0270026
X1645740Y0270026
X1645740Y0267526
X1648240Y0267526
X1642940Y0270026
X1642940Y0267526
X1636546Y0264180
X1634046Y0264180
X1582951Y0248371
X1597540Y0232971
X1607666Y0246874
X1658200Y0315039
X1602309Y0242078
X1595622Y0226320
X1608185Y0238714
X1571369Y0265897
X1573869Y0265897
X1667271Y0270695
X1664574Y0248765
X1667074Y0248765
X1664633Y0236189
X1667133Y0236189
X1662382Y0224421
X1664082Y0228221
X1664082Y0231021
X1664771Y0270695
X1664771Y0268195
X1667271Y0268195
X1582951Y0252371
X1594548Y0238589
X1597006Y0290417
X1597433Y0253198
X1603950Y0238689
X1612185Y0238714
X1597514Y0236121
X1604724Y0247292
X1634263Y0293796
X1636763Y0293796
X1642277Y0288190
X1644777Y0285690
X1642277Y0285690
X1644777Y0288190
X1644825Y0248891
X1641173Y0228961
X1644880Y0226141
X1641173Y0226461
X1641173Y0223661
X1630717Y0228726
X1630717Y0231226
X1630717Y0226226
X1630717Y0223726
X1641173Y0231461
X1659803Y0290755
X1651803Y0290755
X1655803Y0290755
X1647577Y0288190
X1647577Y0285690
X1652750Y0256535
X1660750Y0256535
X1649825Y0248891
X1647325Y0248891
X1649142Y0231786
X1647623Y0236611
X1650123Y0236611
X1645123Y0236611
X1652835Y0224712
X1649142Y0229286
X1647680Y0226141
X1665884Y0281307
X1661780Y0279208
X1667874Y0293645
X1667874Y0288345
X1667874Y0290845
X1629553Y0329067
X1595109Y0342663
X1595069Y0337361
X1574775Y0344127
X1629514Y0331727
X1636561Y0343072
X1605966Y0343794
X1640197Y0374690
X1575935Y0382109
X1594466Y0350984
X1596253Y0375633
X1630691Y0347432
X1641615Y0379600
X1638340Y0379536
X1663650Y0353283
X1666860Y0353661
X1654771Y0352088
X1602138Y0351047
X1626147Y0351033
X1596534Y0379760
X1648835Y0390500
X1645685Y0381500
X1599527Y0396718
X1578420Y0338309
X1578587Y0341787
X1640030Y0335550
X1629302Y0334402
X1607947Y0332326
X1628636Y0422088
X1574775Y0333549
X1571625Y0344131
X1668979Y0339559
X1666959Y0382047
X1667260Y0403500
X1663780Y0384410
X1663618Y0393858
X1665260Y0398583
X1576940Y0412255
X1584240Y0419341
X1576940Y0415655
X1584240Y0394395
X1576940Y0401482
X1584240Y0390995
X1584240Y0405168
X1576940Y0398082
X1584240Y0408568
X1574540Y0417500
X1579340Y0417500
X1574540Y0410413
X1574540Y0403327
X1574540Y0396240
X1579340Y0410413
X1579340Y0403327
X1579340Y0396240
X1574540Y0389154
X1571625Y0333549
X1574845Y0338843
X1581840Y0417499
X1586640Y0417499
X1586640Y0403326
X1586640Y0396240
X1581840Y0396240
X1586640Y0410413
X1581840Y0410413
X1581840Y0403326
X1581840Y0389153
X1586640Y0389153
X1593290Y0339876
X1599527Y0412718
X1599527Y0404718
X1599527Y0400718
X1599527Y0408718
X1599527Y0392718
X1596714Y0383003
X1599127Y0375587
X1598223Y0351003
X1603664Y0342596
X1608240Y0329000
X1636271Y0403307
X1636271Y0410394
X1636468Y0345595
X1630703Y0350655
X1635987Y0335616
X1632230Y0330400
X1655335Y0381500
X1645685Y0390500
X1663760Y0403307
X1663760Y0410394
X1625772Y0438323
X1647604Y0467367
X1666271Y0463618
X1645826Y0446606
X1646209Y0442606
X1625938Y0445873
X1667067Y0454177
X1664567Y0454177
X1667067Y0451677
X1664567Y0451677
X1666271Y0460218
X1635185Y0446595
X1635170Y0442856
X1663713Y0435669
X1663713Y0430469
X1663713Y0433069
X1666513Y0438269
X1666513Y0440869
X1666513Y0435669
X1666513Y0430469
X1666513Y0433069
X1663713Y0438269
X1663713Y0440869
X1647133Y0463479
X1591443Y0465332
X1621596Y0456386
X1653490Y0458572
X1649773Y0449961
X1636271Y0453881
X1635265Y0467337
X1649789Y0440489
X1633225Y0458455
X1635265Y0481510
X1650087Y0444841
X1627965Y0518558
X1627965Y0477824
X1632439Y0452265
X1650044Y0435158
X1627965Y0491997
X1635265Y0484910
X1635265Y0511471
X1627965Y0474424
X1635265Y0514871
X1635265Y0470737
X1627965Y0521958
X1627965Y0488597
X1584240Y0422741
X1576940Y0426428
X1576940Y0479868
X1576940Y0490641
X1576940Y0494041
X1584240Y0436915
X1584240Y0513515
X1584240Y0469381
X1584240Y0486954
X1576940Y0429828
X1584240Y0516915
X1584240Y0472781
X1576940Y0440602
X1576940Y0476468
X1584240Y0433515
X1576940Y0520602
X1584240Y0483554
X1576940Y0444002
X1620385Y0465874
X1623955Y0442956
X1663576Y0472579
X1663576Y0486752
X1663576Y0479665
X1645607Y0475262
X1655776Y0472579
X1645607Y0482666
X1655776Y0479665
X1655776Y0486752
X1630365Y0472579
X1632865Y0472579
X1637665Y0472579
X1632865Y0486752
X1630365Y0486752
X1637665Y0486752
X1637665Y0479665
X1632865Y0479666
X1630365Y0479666
X1625565Y0472579
X1625565Y0486752
X1625565Y0479666
X1586640Y0474626
X1581840Y0474626
X1586640Y0481712
X1581840Y0481712
X1579340Y0481712
X1574540Y0481713
X1579340Y0474626
X1574540Y0474626
X1574540Y0467539
X1574540Y0445847
X1579340Y0445847
X1574540Y0431673
X1579340Y0438760
X1579340Y0431673
X1574540Y0438760
X1574540Y0424586
X1579340Y0424586
X1586640Y0424586
X1581840Y0424586
X1581840Y0467539
X1586640Y0467539
X1581840Y0431673
X1586640Y0431673
X1586640Y0438760
X1581840Y0438760
X1625938Y0449873
X1625018Y0435029
X1626260Y0427017
X1625952Y0431029
X1637665Y0465492
X1632865Y0465492
X1637489Y0462264
X1637665Y0451319
X1637665Y0458406
X1637205Y0430098
X1637205Y0432598
X1637205Y0435098
X1637205Y0437598
X1637205Y0440098
X1655639Y0452018
X1655433Y0439963
X1655392Y0437072
X1655576Y0433570
X1655555Y0430760
X1655742Y0460250
X1655776Y0465492
X1645465Y0466027
X1653507Y0470136
X1655697Y0454744
X1655677Y0443180
X1663576Y0465492
X1663576Y0458406
X1574540Y0518760
X1574540Y0511673
X1579340Y0518760
X1574540Y0495886
X1579340Y0495886
X1574540Y0488799
X1579340Y0488799
X1586640Y0518760
X1586640Y0511673
X1581840Y0511673
X1581840Y0518760
X1586640Y0488799
X1581840Y0488799
X1625565Y0516713
X1625565Y0493839
X1637665Y0509626
X1637665Y0516713
X1630365Y0516713
X1632865Y0516713
X1632865Y0509626
X1637665Y0493839
X1630365Y0493839
X1655776Y0516713
X1655776Y0509626
X1645465Y0509626
X1646080Y0522134
X1646158Y0514608
X1655776Y0493839
X1645423Y0495088
X1645607Y0489435
X1663576Y0509626
X1663576Y0516713
X1663576Y0493839
X1592635Y0455911
X1596760Y0530000
X1614538Y0618288
X1571755Y0577937
X1595300Y0558800
X1595364Y0562800
X1618538Y0618288
X1575934Y0558917
X1575934Y0561420
X1616622Y0542712
X1595260Y0547075
X1595460Y0549800
X1635265Y0525644
X1635265Y0589857
X1627965Y0532731
X1635265Y0604030
X1627965Y0611117
X1635265Y0561510
X1635265Y0593257
X1635265Y0529044
X1627965Y0600344
X1627965Y0568597
X1627965Y0571997
X1627965Y0586171
X1627965Y0582771
X1635265Y0579084
X1627965Y0614517
X1635265Y0607430
X1635265Y0575684
X1627965Y0596944
X1635265Y0564910
X1627965Y0536131
X1580354Y0616317
X1577862Y0554121
X1579260Y0604567
X1584240Y0527688
X1574760Y0606929
X1579760Y0595500
X1576940Y0538175
X1580418Y0610072
X1575001Y0612592
X1574720Y0618400
X1584240Y0531088
X1576940Y0524002
X1576940Y0534775
X1616622Y0546712
X1594760Y0568000
X1578114Y0607563
X1578679Y0613047
X1579753Y0599100
X1574540Y0595118
X1574540Y0602205
X1575000Y0575414
X1575000Y0572914
X1575000Y0570414
X1575000Y0567914
X1575000Y0565414
X1574540Y0554193
X1574540Y0547106
X1574540Y0532933
X1574540Y0525847
X1579340Y0525846
X1579340Y0532933
X1579340Y0540020
X1574540Y0540020
X1583720Y0560500
X1595760Y0555000
X1595185Y0543925
X1581840Y0525846
X1581840Y0532933
X1586640Y0532933
X1586640Y0525846
X1625565Y0580926
X1625565Y0573839
X1625565Y0588013
X1625565Y0566752
X1625565Y0530886
X1625565Y0537973
X1625565Y0523800
X1625565Y0616359
X1625565Y0609272
X1625565Y0595099
X1625565Y0602186
X1630365Y0537973
X1637665Y0537973
X1632865Y0530886
X1637665Y0530886
X1630365Y0530886
X1637665Y0523799
X1632865Y0523800
X1630365Y0523800
X1637665Y0609272
X1637665Y0616358
X1630365Y0609272
X1632865Y0609272
X1630365Y0616359
X1630365Y0595099
X1632865Y0595099
X1637665Y0595099
X1637665Y0602185
X1630365Y0602186
X1632865Y0602185
X1630365Y0573839
X1637665Y0573839
X1632865Y0588012
X1630365Y0588013
X1637665Y0588012
X1637665Y0580926
X1632865Y0580926
X1630365Y0580926
X1632865Y0573839
X1632865Y0559665
X1632865Y0566752
X1630365Y0566752
X1637665Y0566752
X1637665Y0559665
X1655840Y0608117
X1645592Y0616358
X1655776Y0573839
X1655626Y0579978
X1645493Y0574338
X1655776Y0566752
X1655776Y0559665
X1645846Y0565574
X1645465Y0559665
X1654637Y0532756
X1654716Y0525483
X1652236Y0537973
X1646723Y0529136
X1646562Y0535677
X1663576Y0573839
X1663576Y0588012
X1663576Y0580925
X1663576Y0566752
X1663576Y0559665
X1663576Y0530886
X1663576Y0537973
X1663576Y0523799
X1663576Y0609272
X1663576Y0616358
X1663576Y0595099
X1663576Y0602185
X1596260Y0540500
X1620600Y0705900
X1617362Y0656321
X1621362Y0656321
X1611316Y0685800
X1612800Y0705900
X1569434Y0677111
X1619950Y0678519
X1616260Y0678462
X1613362Y0656321
X1627224Y0643252
X1577077Y0631712
X1576297Y0627600
X1628200Y0711417
X1572141Y0662981
X1575192Y0707592
X1571888Y0649380
X1574880Y0645891
X1637526Y0699930
X1624148Y0708258
X1637472Y0717830
X1575942Y0705043
X1570331Y0691851
X1575950Y0662981
X1569926Y0668885
X1574222Y0629872
X1614338Y0636842
X1613110Y0678462
X1617843Y0665140
X1620244Y0638125
X1615913Y0692245
X1578000Y0678776
X1620500Y0723200
X1606709Y0819165
X1606190Y0803774
X1609500Y0776100
X1620100Y0738300
X1657042Y0773604
X1656112Y0768669
X1611327Y0735973
X1612573Y0761427
X1611627Y0780327
X1611027Y0722427
X1616683Y0744517
X1611873Y0795127
X1628027Y0801427
X1629927Y0787327
X1630327Y0774627
X1624000Y0760900
X1628343Y0747288
X1635283Y0728117
X1628813Y0727045
X1631031Y0732430
X1629969Y0740826
X1631187Y0750630
X1627455Y0759489
X1620359Y0774830
X1619612Y0783152
X1620755Y0787530
X1619569Y0796035
X1620072Y0801630
X1620479Y0815730
X1613235Y0808466
X1654572Y0771702
X1644718Y0909263
X1635176Y0886761
X1644552Y0871353
X1635000Y0919263
X1647763Y0919268
X1648375Y0886766
X1647402Y0881460
X1613117Y0828117
X1644304Y0891353
X1616255Y0824405
X1619859Y0839519
X1644325Y0942120
X1637771Y0952120
X1647470Y0952125
X1653414Y0990590
X1650205Y0925911
X1648387Y0945554
X1652944Y0993796
X1647565Y0981432
X1651443Y0981515
X1645128Y0929263
X1645342Y0962120
X1649571Y0983857
X1657091Y0990823
X1623638Y1396583
X1648118Y1348187
X1663758Y1372385
X1660358Y1372385
X1611398Y1372385
X1648118Y1396583
X1651518Y1396583
X1660358Y1384297
X1627038Y1348187
X1614798Y1384297
X1651518Y1408495
X1623638Y1348187
X1635878Y1372385
X1627038Y1396583
X1614798Y1372385
X1648118Y1408495
X1651518Y1348187
X1648118Y1360099
X1639278Y1372385
X1639278Y1384297
X1627038Y1360099
X1623638Y1408495
X1635878Y1384297
X1651518Y1360099
X1663758Y1384297
X1623638Y1360099
X1627038Y1408495
X1611398Y1384297
X1663758Y1408495
X1623638Y1384297
X1660358Y1360099
X1651518Y1384297
X1611398Y1360099
X1639278Y1408495
X1627038Y1384297
X1635878Y1360099
X1660358Y1408495
X1648118Y1384297
X1663758Y1360099
X1614798Y1360099
X1635878Y1408495
X1639278Y1360099
X1574930Y1384297
X1583770Y1360099
X1587170Y1384297
X1587170Y1408495
X1571530Y1384297
X1571530Y1360099
X1583770Y1408495
X1587170Y1360099
X1574930Y1408495
X1574930Y1360099
X1571530Y1408495
X1583770Y1384297
X1635878Y1348187
X1651518Y1372385
X1660358Y1396583
X1611398Y1348187
X1660358Y1348187
X1623638Y1372385
X1635878Y1396583
X1571530Y1372385
X1574930Y1372385
X1574930Y1396583
X1587170Y1396583
X1583770Y1348187
X1582992Y1357603
X1582992Y1362595
X1587948Y1357603
X1587948Y1362595
X1587948Y1374881
X1587948Y1381801
X1587948Y1369889
X1582992Y1374881
X1582992Y1381801
X1582992Y1369889
X1587948Y1386793
X1587948Y1394087
X1587948Y1399079
X1582992Y1386793
X1582992Y1394087
X1582992Y1399079
X1587948Y1410991
X1587948Y1405999
X1582992Y1410991
X1582992Y1405999
X1575708Y1350683
X1570752Y1345597
X1570752Y1350683
X1575708Y1357603
X1575708Y1362595
X1570752Y1362595
X1570752Y1357603
X1570752Y1374881
X1570752Y1381801
X1570752Y1369889
X1575708Y1369889
X1575708Y1374881
X1575708Y1381801
X1570752Y1399079
X1570752Y1393993
X1570752Y1386793
X1575708Y1393993
X1575708Y1399079
X1575708Y1386793
X1570752Y1410991
X1570752Y1405999
X1575708Y1410991
X1575708Y1405999
X1582992Y1350683
X1582992Y1345691
X1587948Y1345691
X1587948Y1350683
X1575708Y1345597
X1664536Y1345691
X1664536Y1350683
X1664536Y1362595
X1664536Y1357603
X1664536Y1381801
X1664536Y1369889
X1664536Y1374881
X1664536Y1386793
X1664536Y1399079
X1664536Y1394087
X1664536Y1410991
X1664536Y1405999
X1640056Y1410991
X1640056Y1405999
X1659580Y1345691
X1659580Y1350683
X1652296Y1345691
X1652296Y1350683
X1647340Y1345691
X1647340Y1350683
X1659580Y1357603
X1659580Y1362595
X1652296Y1362595
X1652296Y1357603
X1647340Y1362595
X1647340Y1357603
X1659580Y1381801
X1659580Y1369889
X1659580Y1374881
X1652296Y1369889
X1652296Y1374881
X1652296Y1381801
X1647340Y1369889
X1647340Y1374881
X1647340Y1381801
X1659580Y1386793
X1659580Y1399079
X1659580Y1394087
X1652296Y1394087
X1652296Y1399079
X1652296Y1386793
X1647340Y1399079
X1647340Y1394087
X1647340Y1386793
X1659580Y1410991
X1659580Y1405999
X1652296Y1410991
X1652296Y1405999
X1647340Y1410991
X1647340Y1405999
X1615576Y1369889
X1615576Y1374881
X1615576Y1381801
X1627816Y1393993
X1627816Y1399079
X1627816Y1386793
X1622860Y1399079
X1622860Y1393993
X1622860Y1386793
X1615576Y1386793
X1627816Y1410991
X1627816Y1405999
X1622860Y1410991
X1622860Y1405999
X1635100Y1350683
X1635100Y1345691
X1640056Y1350683
X1640056Y1345691
X1635100Y1357603
X1635100Y1362595
X1640056Y1362595
X1640056Y1357603
X1635100Y1381801
X1635100Y1374881
X1635100Y1369889
X1640056Y1381801
X1640056Y1374881
X1640056Y1369889
X1635100Y1386793
X1635100Y1399079
X1635100Y1394087
X1640056Y1386793
X1640056Y1394087
X1640056Y1399079
X1635100Y1410991
X1635100Y1405999
X1610620Y1350683
X1610620Y1345691
X1610620Y1362595
X1610620Y1357603
X1610620Y1369889
X1610620Y1374881
X1610620Y1381801
X1610620Y1386793
X1627816Y1345691
X1627816Y1350683
X1622860Y1345691
X1622860Y1350683
X1615576Y1350683
X1615576Y1345691
X1627816Y1362595
X1627816Y1357603
X1622860Y1362595
X1622860Y1357603
X1615576Y1362595
X1615576Y1357603
X1627816Y1374881
X1627816Y1369795
X1627816Y1381801
X1622860Y1374881
X1622860Y1369795
X1622860Y1381801
X1571530Y1348187
X1583770Y1396583
X1587170Y1348187
X1574930Y1348187
X1614798Y1348187
X1583770Y1372385
X1663758Y1396583
X1587170Y1372385
X1571530Y1396583
X1639278Y1396583
X1663758Y1348187
X1639278Y1348187
X1648118Y1372385
X1627038Y1372385
X1597457Y1460662
X1601968Y1453442
X1596790Y1442557
X1593019Y1457557
X1600333Y1449068
X1596038Y1492000
X1600008Y1488492
X1599726Y1474990
X1597039Y1475100
X1608500Y1506000
X1601500Y1514500
X1604000Y1519000
X1592643Y1460707
X1591333Y1501980
X1591925Y1512075
X1591775Y1473090
X1608500Y1515000
X1596836Y1446488
X1605430Y1468023
X1600333Y1440504
X1597457Y1452556
X1603363Y1460570
X1606745Y1474242
X1597225Y1437014
X1614200Y1519500
X1592020Y1433061
X1591586Y1505130
X1591610Y1469940
X1604000Y1516000
X1598000Y1486000
X1602580Y1483108
X1598500Y1472500
X1657983Y1480867
X1649322Y1481267
X1649322Y1471805
X1657983Y1470244
X1657983Y1476136
X1649322Y1476536
X1649322Y1461182
X1657983Y1465513
X1649322Y1465913
X1649322Y1456451
X1657983Y1460782
X1657983Y1516307
X1657983Y1506845
X1649322Y1507245
X1649322Y1511976
X1657983Y1511576
X1649322Y1502514
X1657983Y1500952
X1657983Y1485598
X1657983Y1491490
X1649322Y1491890
X1657983Y1496221
X1649322Y1496621
X1649322Y1487159
X1666645Y1496621
X1666645Y1491890
X1666645Y1487159
X1666645Y1481267
X1666645Y1476536
X1666645Y1471805
X1666645Y1461182
X1666645Y1456451
X1666645Y1465913
X1666645Y1502514
X1666645Y1507245
X1666645Y1511976
X1598574Y1543373
X1640581Y1551907
X1613790Y1523334
X1609348Y1527334
X1613790Y1531334
X1609348Y1535334
X1590748Y1523377
X1600732Y1539334
X1600700Y1534300
X1618600Y1532000
X1614360Y1542860
X1618800Y1528558
X1657983Y1563144
X1649322Y1563544
X1649322Y1558813
X1657983Y1618669
X1657983Y1613938
X1649322Y1614338
X1649322Y1604876
X1657983Y1603315
X1657983Y1598584
X1649322Y1598984
X1657983Y1609207
X1649322Y1609607
X1649322Y1589522
X1657983Y1587960
X1657983Y1593853
X1649322Y1594253
X1657983Y1583229
X1649322Y1583629
X1657983Y1578498
X1649322Y1578898
X1657983Y1567875
X1649322Y1568275
X1649322Y1574167
X1657983Y1572606
X1666645Y1614338
X1666645Y1609607
X1666645Y1598984
X1666645Y1604876
X1666645Y1594253
X1666645Y1589522
X1666645Y1583629
X1666645Y1578898
X1666645Y1574167
X1666645Y1568275
X1666645Y1563544
X1666645Y1558813
X1572000Y1644980
X1652000Y1644980
X1768422Y1632245
X1762041Y1631511
X1768422Y1640303
X1760422Y1640303
X1672000Y1644980
X1692000Y1644980
X1712000Y1644980
X1732000Y1644980
X1752000Y1644980
X1764422Y1640303
X1756422Y1640303
X1766313Y1580198
X1765040Y1599511
X1759947Y1599029
X1758390Y1577905
X1761072Y1590719
X1750685Y1621654
X1765294Y1575434
X1758583Y1581027
X1675306Y1618669
X1675306Y1613938
X1675306Y1603315
X1675306Y1598584
X1675306Y1609207
X1675306Y1587960
X1675306Y1593853
X1675306Y1583229
X1675306Y1567875
X1675306Y1572606
X1675306Y1578498
X1675306Y1563144
X1692629Y1578498
X1692629Y1567875
X1683968Y1578898
X1683968Y1574167
X1683968Y1568275
X1692629Y1572606
X1692629Y1563144
X1683968Y1563544
X1683968Y1558813
X1692629Y1618669
X1692629Y1613938
X1683968Y1614338
X1683968Y1604876
X1683968Y1609607
X1692629Y1603315
X1692629Y1598584
X1692629Y1609207
X1683968Y1598984
X1692629Y1587960
X1692629Y1593853
X1692629Y1583229
X1683968Y1594253
X1683968Y1589522
X1683968Y1583629
X1701290Y1578898
X1701290Y1574167
X1701290Y1568275
X1701290Y1563544
X1701290Y1558813
X1701290Y1614338
X1701290Y1598984
X1701290Y1604876
X1701290Y1609607
X1701290Y1594253
X1701290Y1589522
X1701290Y1583629
X1709952Y1613938
X1718613Y1614338
X1709952Y1618669
X1709952Y1603315
X1709952Y1598584
X1709952Y1609207
X1718613Y1604876
X1718613Y1598984
X1718613Y1609607
X1718613Y1594253
X1709952Y1587960
X1709952Y1593853
X1718613Y1583629
X1709952Y1583229
X1718613Y1589522
X1718613Y1574167
X1718613Y1578898
X1709952Y1572606
X1709952Y1578498
X1718613Y1568275
X1709952Y1567875
X1718613Y1558813
X1718613Y1563544
X1709952Y1563144
X1767142Y1588219
X1759092Y1588137
X1750685Y1618504
X1675306Y1500952
X1675306Y1496221
X1675306Y1485598
X1675306Y1491490
X1675306Y1480867
X1675306Y1470244
X1675306Y1476136
X1675306Y1460782
X1675306Y1465513
X1675306Y1516307
X1675306Y1506845
X1675306Y1511576
X1692629Y1480867
X1692629Y1470244
X1692629Y1476136
X1683968Y1481267
X1683968Y1476536
X1683968Y1471805
X1692629Y1460782
X1692629Y1465513
X1683968Y1461182
X1683968Y1456451
X1683968Y1465913
X1692629Y1516307
X1683968Y1507245
X1692629Y1511576
X1692629Y1500952
X1692629Y1506845
X1683968Y1511976
X1683968Y1502514
X1692629Y1496221
X1692629Y1485598
X1692629Y1491490
X1683968Y1496621
X1683968Y1491890
X1683968Y1487159
X1701290Y1481267
X1701290Y1476536
X1701290Y1471805
X1701290Y1461182
X1701290Y1456451
X1701290Y1465913
X1701290Y1511976
X1701290Y1502514
X1701290Y1507245
X1701290Y1496621
X1701290Y1491890
X1701290Y1487159
X1718613Y1507246
X1709952Y1511576
X1709952Y1500952
X1709952Y1506845
X1718613Y1496622
X1718613Y1487160
X1718613Y1491891
X1709952Y1496221
X1709952Y1485598
X1709952Y1491490
X1709952Y1480867
X1709952Y1470244
X1709952Y1476136
X1718613Y1481268
X1718613Y1471806
X1718613Y1476537
X1718613Y1461183
X1718613Y1456452
X1718613Y1465914
X1709952Y1460782
X1709952Y1465513
X1709952Y1516307
X1718613Y1511977
X1718613Y1502515
X1697078Y1348187
X1675998Y1348187
X1672598Y1348187
X1737198Y1372385
X1688238Y1372385
X1733798Y1372385
X1684838Y1372385
X1697078Y1396583
X1724958Y1396583
X1724958Y1348187
X1709318Y1372385
X1672598Y1360099
X1700478Y1408495
X1700478Y1396583
X1721558Y1396583
X1724958Y1408495
X1721558Y1360099
X1700478Y1348187
X1672598Y1396583
X1700478Y1360099
X1721558Y1348187
X1721558Y1408495
X1672598Y1408495
X1712718Y1384297
X1712718Y1372385
X1675998Y1360099
X1675998Y1396583
X1709318Y1384297
X1733798Y1384297
X1697078Y1408495
X1737198Y1384297
X1688238Y1384297
X1684838Y1384297
X1697078Y1360099
X1724958Y1360099
X1675998Y1408495
X1709318Y1408495
X1737198Y1360099
X1675998Y1384297
X1721558Y1384297
X1724958Y1384297
X1684838Y1408495
X1733798Y1408495
X1700478Y1384297
X1709318Y1360099
X1737198Y1408495
X1733798Y1360099
X1684838Y1360099
X1697078Y1384297
X1712718Y1360099
X1712718Y1408495
X1672598Y1384297
X1688238Y1408495
X1688238Y1360099
X1709318Y1396583
X1733798Y1396583
X1712718Y1348187
X1684838Y1348187
X1700478Y1372385
X1724958Y1372385
X1688238Y1396583
X1709318Y1348187
X1688238Y1348187
X1737976Y1381801
X1733020Y1386793
X1733020Y1394087
X1733020Y1399079
X1737976Y1386793
X1737976Y1394087
X1737976Y1399079
X1733020Y1410991
X1733020Y1405999
X1737976Y1410991
X1737976Y1405999
X1725736Y1369889
X1725736Y1374881
X1725736Y1381801
X1720780Y1374881
X1720780Y1381801
X1720780Y1369889
X1713496Y1381801
X1713496Y1369889
X1713496Y1374881
X1725736Y1393993
X1725736Y1399079
X1725736Y1386793
X1720780Y1399079
X1720780Y1393993
X1720780Y1386793
X1713496Y1386793
X1713496Y1394087
X1713496Y1399079
X1725736Y1410991
X1725736Y1405999
X1720780Y1410991
X1720780Y1405999
X1713496Y1410991
X1713496Y1405999
X1733020Y1350683
X1733020Y1345691
X1737976Y1345691
X1737976Y1350683
X1733020Y1357603
X1733020Y1362595
X1737976Y1357603
X1737976Y1362595
X1733020Y1374881
X1733020Y1381801
X1733020Y1369889
X1737976Y1374881
X1737976Y1369889
X1708540Y1381801
X1708540Y1369889
X1708540Y1374881
X1701256Y1374881
X1701256Y1381801
X1701256Y1369889
X1696300Y1381801
X1696300Y1369889
X1696300Y1374881
X1708540Y1386793
X1708540Y1394087
X1708540Y1399079
X1701256Y1399079
X1701256Y1394087
X1701256Y1386793
X1696300Y1399079
X1696300Y1394087
X1696300Y1386793
X1708540Y1410991
X1708540Y1405999
X1701256Y1410991
X1701256Y1405999
X1696300Y1410991
X1696300Y1405999
X1725736Y1345597
X1725736Y1350683
X1720780Y1345597
X1720780Y1350683
X1713496Y1345691
X1713496Y1350683
X1725736Y1362595
X1725736Y1357603
X1720780Y1362595
X1720780Y1357603
X1713496Y1362595
X1713496Y1357603
X1684060Y1345691
X1684060Y1350683
X1689016Y1350683
X1689016Y1345691
X1684060Y1362595
X1684060Y1357603
X1689016Y1357603
X1689016Y1362595
X1684060Y1374881
X1684060Y1381801
X1684060Y1369889
X1689016Y1374881
X1689016Y1381801
X1689016Y1369889
X1684060Y1386793
X1684060Y1399079
X1684060Y1394087
X1689016Y1386793
X1689016Y1399079
X1689016Y1394087
X1684060Y1410991
X1684060Y1405999
X1689016Y1410991
X1689016Y1405999
X1708540Y1350683
X1708540Y1345691
X1701256Y1345691
X1701256Y1350683
X1696300Y1345691
X1696300Y1350683
X1708540Y1357603
X1708540Y1362595
X1701256Y1362595
X1701256Y1357603
X1696300Y1362595
X1696300Y1357603
X1676776Y1350683
X1676776Y1345691
X1671820Y1350683
X1671820Y1345691
X1676776Y1362595
X1676776Y1357603
X1671820Y1362595
X1671820Y1357603
X1676776Y1381801
X1676776Y1374881
X1676776Y1369889
X1671820Y1369889
X1671820Y1381801
X1671820Y1374881
X1676776Y1394087
X1676776Y1399079
X1676776Y1386793
X1671820Y1399079
X1671820Y1394087
X1671820Y1386793
X1676776Y1410991
X1676776Y1405999
X1671820Y1410991
X1671820Y1405999
X1672598Y1372385
X1684838Y1396583
X1737198Y1348187
X1697078Y1372385
X1721558Y1372385
X1712718Y1396583
X1737198Y1396583
X1733798Y1348187
X1675998Y1372385
X1712966Y1229841
X1710825Y1231688
X1729322Y1226016
X1731533Y1228226
X1726475Y1223170
X1712715Y1188500
X1708015Y1142700
X1712526Y1171950
X1711333Y1146609
X1706450Y1173065
X1713239Y1176038
X1725008Y1134636
X1732881Y1134729
X1723805Y1142666
X1725680Y1157544
X1732137Y1157404
X1729210Y1167768
X1724191Y1167768
X1737482Y1180235
X1719385Y1180175
X1737689Y1185238
X1719692Y1187215
X1712542Y1196600
X1718625Y1199814
X1733052Y1187310
X1728343Y1185205
X1737662Y1200969
X1723200Y1219895
X1725658Y1201043
X1721662Y1201043
X1720536Y1217228
X1729628Y1201043
X1733662Y1201039
X1729008Y1134729
X1721008Y1134729
X1710511Y1138130
X1737393Y1170767
X1728333Y1178240
X1737781Y1208993
X1703400Y1174400
X1739917Y1150087
X1717626Y1134729
X1739508Y1137129
X1720960Y1148000
X1708889Y1189221
X1711783Y1193848
X1721660Y1193019
X1725660Y1193019
X1723796Y1160168
X1740785Y1219254
X1731619Y1210089
X1735989Y1214458
X1733695Y1212164
X1737660Y1193019
X1729660Y1193019
X1733660Y1193019
X1737393Y1162817
X1729207Y1159455
X1739917Y1146937
X1726963Y1132319
X1730675Y1132361
X1766999Y1130822
X1742029Y1116251
X1744529Y1116251
X1768844Y1027248
X1768844Y1023694
X1764744Y1097879
X1764744Y1101930
X1743224Y1119055
X1766899Y1121122
X1765664Y0923724
X1746600Y0935100
X1748677Y0993986
X1753860Y0997271
X1758881Y0995633
X1745824Y0987058
X1760201Y0992475
X1762486Y0990260
X1749314Y0987904
X1751854Y0991297
X1759569Y1021944
X1769004Y1019395
X1751200Y0931100
X1763818Y0926241
X1756192Y0996132
X1748081Y0984379
X1762898Y0992883
X1749267Y0918413
X1746884Y0884649
X1741800Y0917900
X1746897Y0879199
X1754906Y0824333
X1750915Y0902055
X1744900Y0900160
X1747900Y0900160
X1750751Y0910785
X1747937Y0912517
X1744937Y0912517
X1757402Y0825111
X1761953Y0865160
X1754906Y0820737
X1757402Y0820155
X1692379Y0622912
X1693000Y0626912
X1761953Y0706827
X1758957Y0543036
X1698716Y0550065
X1750879Y0541940
X1692028Y0550137
X1756089Y0542952
X1689236Y0550137
X1689920Y0539315
X1702655Y0532725
X1702655Y0568591
X1702655Y0582765
X1692253Y0579052
X1692253Y0564879
X1702655Y0614511
X1702655Y0571991
X1692253Y0589825
X1702655Y0586165
X1702655Y0596938
X1710174Y0553101
X1689757Y0608177
X1689757Y0594003
X1689757Y0603221
X1689757Y0579830
X1689757Y0574874
X1689757Y0589047
X1689757Y0560701
X1689757Y0565657
X1689757Y0529791
X1689757Y0524835
X1700159Y0531947
X1694749Y0529791
X1694749Y0524835
X1705151Y0531947
X1705151Y0536903
X1700159Y0536903
X1700159Y0522730
X1705151Y0522730
X1705151Y0610333
X1700159Y0615289
X1694749Y0608177
X1700159Y0610333
X1705151Y0615289
X1694749Y0594003
X1700159Y0596160
X1705151Y0596160
X1705151Y0601116
X1700159Y0601116
X1694749Y0603221
X1694749Y0574874
X1700159Y0581987
X1700159Y0586943
X1694749Y0589047
X1705151Y0581987
X1705151Y0586943
X1694749Y0579830
X1694749Y0560701
X1694749Y0565657
X1700159Y0567813
X1698839Y0564843
X1705151Y0567813
X1700159Y0572769
X1705151Y0572769
X1753474Y0542699
X1692253Y0603999
X1702655Y0600338
X1692253Y0593225
X1692253Y0575652
X1692253Y0607399
X1692253Y0561479
X1692253Y0525613
X1702655Y0611111
X1692253Y0529013
X1702655Y0536125
X1738824Y0461034
X1724923Y0449045
X1724580Y0454214
X1738824Y0456034
X1724627Y0459330
X1716310Y0454334
X1756391Y0487382
X1764906Y0474382
X1756954Y0477318
X1756553Y0466409
X1734952Y0476717
X1724930Y0473571
X1724930Y0481071
X1724930Y0478571
X1724930Y0476071
X1768575Y0475560
X1731502Y0477053
X1729002Y0477053
X1737646Y0479713
X1737646Y0477213
X1734952Y0479217
X1730014Y0462060
X1733014Y0462060
X1764903Y0470382
X1756894Y0472020
X1766837Y0443893
X1756844Y0443893
X1766837Y0441093
X1766837Y0438293
X1747179Y0442118
X1756844Y0441093
X1747179Y0439318
X1756844Y0438293
X1739179Y0442118
X1728915Y0426689
X1739179Y0439318
X1729302Y0435518
X1729302Y0432718
X1754470Y0424067
X1756970Y0424067
X1751970Y0424067
X1749470Y0424067
X1728915Y0424089
X1758401Y0484882
X1768586Y0467560
X1748092Y0485580
X1745592Y0485580
X1743092Y0485580
X1744806Y0470001
X1747306Y0470001
X1745231Y0489036
X1747467Y0495636
X1747467Y0492836
X1730404Y0447209
X1727404Y0447209
X1730014Y0450091
X1733014Y0450091
X1702655Y0518552
X1692253Y0470706
X1702655Y0521952
X1692253Y0481479
X1702655Y0488591
X1692253Y0484879
X1692253Y0514839
X1702655Y0474418
X1692253Y0467306
X1705151Y0473640
X1700159Y0473640
X1694749Y0485657
X1700159Y0478596
X1694749Y0480701
X1705151Y0478596
X1689757Y0485657
X1689757Y0480701
X1765006Y0478382
X1768575Y0479560
X1764912Y0482382
X1673717Y0445787
X1669767Y0445908
X1689757Y0471484
X1689757Y0466528
X1694749Y0471484
X1694749Y0466528
X1729302Y0442518
X1716310Y0458334
X1718710Y0447486
X1740542Y0465288
X1740542Y0468088
X1737703Y0472189
X1736214Y0450091
X1738824Y0452740
X1739179Y0446318
X1739179Y0449118
X1729302Y0439718
X1747359Y0462309
X1747359Y0458309
X1747359Y0454309
X1747179Y0446318
X1747179Y0449118
X1756844Y0455641
X1756844Y0452841
X1756844Y0450041
X1765097Y0466409
X1766837Y0455641
X1766837Y0452841
X1766837Y0450041
X1765093Y0423944
X1767893Y0423944
X1689757Y0510661
X1689757Y0515617
X1700159Y0517774
X1694749Y0515617
X1694749Y0510661
X1705151Y0517774
X1705151Y0492769
X1700159Y0492769
X1700159Y0487813
X1705151Y0487813
X1724930Y0496118
X1724930Y0493618
X1724930Y0488618
X1724930Y0491118
X1733147Y0496258
X1733147Y0493758
X1730538Y0491870
X1728038Y0491870
X1736592Y0490070
X1736592Y0487570
X1765083Y0487382
X1702655Y0477818
X1692253Y0511439
X1702655Y0491991
X1716755Y0326179
X1729751Y0377173
X1691182Y0357016
X1686408Y0332584
X1670323Y0353534
X1673723Y0353881
X1744180Y0383966
X1741420Y0391569
X1680518Y0397912
X1680518Y0381912
X1680518Y0377912
X1715590Y0331719
X1715930Y0340969
X1712226Y0344028
X1737786Y0377173
X1737746Y0385123
X1730746Y0385123
X1725154Y0406060
X1741746Y0377173
X1725746Y0385123
X1720571Y0385644
X1718318Y0399918
X1754705Y0413611
X1757205Y0413611
X1752205Y0413611
X1749705Y0413611
X1728915Y0418889
X1728915Y0421489
X1728915Y0416289
X1728915Y0411089
X1728915Y0413689
X1754624Y0398278
X1757124Y0398278
X1755351Y0401981
X1752851Y0401981
X1753187Y0407039
X1750187Y0406739
X1753187Y0409539
X1750187Y0409539
X1728915Y0408489
X1728915Y0405889
X1729508Y0403300
X1718851Y0391533
X1755433Y0379028
X1765497Y0379591
X1750135Y0379088
X1744524Y0379429
X1677810Y0324466
X1752497Y0371076
X1721423Y0412106
X1725415Y0421489
X1725415Y0418889
X1725415Y0416289
X1762997Y0377581
X1739847Y0401066
X1733746Y0385123
X1715228Y0387966
X1748497Y0371060
X1721746Y0377173
X1688593Y0353470
X1673203Y0328867
X1683523Y0324518
X1670260Y0386500
X1692676Y0348015
X1687424Y0347937
X1670260Y0377912
X1669260Y0391496
X1670348Y0397912
X1669260Y0409000
X1763200Y0386317
X1763200Y0383817
X1763200Y0388817
X1765913Y0389402
X1673203Y0332017
X1674226Y0324139
X1677933Y0418838
X1680518Y0401924
X1680518Y0405924
X1680518Y0409924
X1680518Y0389912
X1680518Y0393924
X1680518Y0385912
X1691743Y0353506
X1678072Y0342319
X1687164Y0336324
X1712734Y0340534
X1715705Y0328692
X1733071Y0396866
X1728478Y0396866
X1732494Y0402867
X1735811Y0409032
X1739847Y0409016
X1728433Y0392183
X1733027Y0392228
X1734826Y0376499
X1723964Y0370935
X1725746Y0377173
X1748252Y0395248
X1747561Y0385161
X1756497Y0370976
X1744524Y0370010
X1765153Y0413611
X1763704Y0401949
X1767633Y0407104
X1767633Y0409904
X1766204Y0398949
X1765497Y0370899
X1760497Y0371070
X1767953Y0413611
X1703895Y0256394
X1763887Y0266114
X1758871Y0265896
X1761360Y0281982
X1693932Y0249108
X1753784Y0265701
X1755419Y0281716
X1696552Y0244571
X1679825Y0228631
X1759112Y0256303
X1700945Y0228646
X1736333Y0258880
X1714531Y0230117
X1709941Y0228747
X1705686Y0230556
X1703609Y0287320
X1700223Y0292141
X1698292Y0303962
X1686115Y0311740
X1712248Y0244297
X1750602Y0270026
X1748102Y0270026
X1745302Y0270026
X1748102Y0267526
X1745302Y0267526
X1750602Y0267526
X1738908Y0264180
X1736408Y0264180
X1685313Y0248371
X1710028Y0246874
X1699902Y0232971
X1704671Y0242078
X1697984Y0226320
X1710547Y0238714
X1686339Y0314890
X1669574Y0248765
X1669633Y0236189
X1670071Y0270695
X1670071Y0268195
X1673731Y0265897
X1676231Y0265897
X1767133Y0268195
X1767133Y0270695
X1766936Y0248765
X1766995Y0236189
X1766444Y0228221
X1766444Y0231021
X1764744Y0224421
X1670374Y0293645
X1670374Y0288345
X1670374Y0290845
X1691117Y0321649
X1681273Y0316731
X1685313Y0252371
X1714547Y0238714
X1695142Y0303839
X1701495Y0289735
X1699795Y0253198
X1706312Y0238689
X1696910Y0238589
X1699876Y0236121
X1707086Y0247292
X1736625Y0293796
X1739125Y0293796
X1743535Y0223661
X1733079Y0228726
X1733079Y0231226
X1733079Y0226226
X1733079Y0223726
X1750042Y0226141
X1754165Y0290755
X1758165Y0290755
X1747139Y0285690
X1744639Y0285690
X1749939Y0285690
X1744639Y0288190
X1747139Y0288190
X1749939Y0288190
X1755112Y0256535
X1752187Y0248891
X1749687Y0248891
X1747187Y0248891
X1747485Y0236611
X1751504Y0231786
X1749985Y0236611
X1752485Y0236611
X1751504Y0229286
X1743535Y0231461
X1743535Y0228961
X1755197Y0224712
X1747242Y0226141
X1743535Y0226461
X1762165Y0290755
X1768246Y0281307
X1764142Y0279208
X1763112Y0256535
X1688848Y0124879
X1693870Y0124663
X1670795Y0152373
X1683782Y0124283
X1767202Y0192300
X1674747Y0178560
X1674810Y0172665
X1698851Y0125107
X1671695Y0143518
X1695214Y0138838
X1683637Y0186778
X1679440Y0157370
X1701365Y0148717
X1707465Y0143762
X1683556Y0208864
X1675016Y0212455
X1674950Y0207037
X1674927Y0200864
X1683524Y0192665
X1669352Y0171523
X1674157Y0190185
X1762102Y0168697
X1758868Y0215632
X1743535Y0215713
X1758868Y0213132
X1743535Y0210713
X1743535Y0213213
X1743535Y0208213
X1750407Y0208695
X1747607Y0208695
X1750107Y0211695
X1755165Y0213859
X1755165Y0211359
X1747607Y0211695
X1733079Y0212978
X1733079Y0215478
X1733079Y0210478
X1733079Y0207978
X1753746Y0184012
X1751129Y0184221
X1754132Y0181366
X1750921Y0181426
X1756927Y0181009
X1674637Y0183834
X1759429Y0172190
X1758848Y0177616
X1673945Y0152562
X1679197Y0219379
X1691405Y0218085
X1688605Y0218085
X1697918Y0221970
X1697918Y0219470
X1697918Y0216970
X1695205Y0216385
X1683556Y0204864
X1763190Y0191941
X1675623Y0186629
X1683524Y0176665
X1683524Y0168665
X1682189Y0161306
X1700324Y0142862
X1706734Y0135915
X1751924Y0170493
X1751924Y0167993
X1751924Y0165393
X1751924Y0162793
X1744824Y0162368
X1742224Y0162368
X1714034Y0128828
X1706734Y0132515
X1710931Y0202048
X1708267Y0206806
X1705767Y0206806
X1703994Y0210509
X1706494Y0210509
X1707931Y0201748
X1711413Y0195176
X1707931Y0199248
X1703913Y0195176
X1706413Y0195176
X1710931Y0199248
X1708913Y0195176
X1714034Y0125428
X1672317Y0221642
X1767829Y0221708
X1765329Y0221708
X1767699Y0206767
X1765199Y0206767
X1764753Y0132509
X1671994Y0192421
X1693485Y0198883
X1688866Y0195176
X1691366Y0195176
X1683524Y0180665
X1683524Y0172665
X1687738Y0134579
X1693591Y0133298
X1686171Y0130898
X1693866Y0195176
X1696666Y0195176
X1705118Y0150847
X1704334Y0137757
X1709134Y0137757
X1702230Y0141228
X1700324Y0146012
X1704334Y0130670
X1704334Y0123584
X1709134Y0130670
X1709134Y0123584
X1683556Y0216864
X1683556Y0221864
X1688726Y0203393
X1693485Y0201683
X1691226Y0203393
X1683556Y0212864
X1683556Y0200864
X1712866Y0213539
X1716334Y0137756
X1725806Y0137756
X1711634Y0130670
X1711634Y0123583
X1716334Y0123583
X1716334Y0130670
X1725811Y0130670
X1724758Y0124576
X1694914Y0206838
X1697414Y0206838
X1730647Y0137756
X1734444Y0123583
X1734444Y0130670
X1753285Y0188727
X1753418Y0191941
X1742444Y0137756
X1756847Y0129574
X1756847Y0124618
X1751855Y0124618
X1751855Y0129574
X1742444Y0123583
X1742444Y0130670
X1755197Y0222212
X1761898Y0206760
X1765950Y0185165
X1759918Y0184619
X1765950Y0180572
X1767249Y0136687
X1762257Y0136687
X1767249Y0131731
X1767249Y0122513
X1762257Y0131731
X1762257Y0122513
X1754351Y0125396
X1764753Y0135909
X1754351Y0128796
X1689291Y0110784
X1694291Y0110784
X1709184Y0095111
X1768991Y0100625
X1762010Y0097475
X1724334Y0095236
X1675291Y0103621
X1671002Y0112083
X1734217Y0099961
X1734267Y0095236
X1713553Y0106561
X1688011Y0086012
X1682330Y0060438
X1684104Y0094279
X1679470Y0060513
X1680155Y0094351
X1745202Y0107649
X1683152Y0086046
X1679598Y0085731
X1745202Y0104249
X1729896Y0090615
X1767552Y0072615
X1724584Y0090650
X1767552Y0076587
X1700590Y0102495
X1683348Y0119594
X1683348Y0116594
X1688011Y0094374
X1677238Y0088801
X1713788Y0097667
X1706734Y0121742
X1743175Y0092874
X1743131Y0077739
X1743131Y0080339
X1743131Y0075139
X1743131Y0082939
X1743131Y0085539
X1713394Y0103411
X1706734Y0118342
X1761941Y0106186
X1755006Y0103783
X1695317Y0119594
X1695317Y0116594
X1751456Y0098551
X1704934Y0097667
X1673108Y0080581
X1673095Y0068581
X1676870Y0055513
X1714034Y0114655
X1714034Y0111255
X1754351Y0114623
X1764753Y0118335
X1675817Y0117261
X1677213Y0091951
X1691566Y0102249
X1687566Y0102249
X1685997Y0110784
X1683348Y0113394
X1695566Y0102249
X1680020Y0055513
X1685184Y0060922
X1704334Y0116497
X1709134Y0116497
X1700590Y0106495
X1701583Y0109172
X1698583Y0109172
X1706664Y0044774
X1706664Y0024774
X1724586Y0116496
X1724586Y0109410
X1724334Y0102323
X1711634Y0109410
X1711634Y0116497
X1716334Y0102323
X1716334Y0109410
X1716334Y0116496
X1724796Y0085584
X1724796Y0075184
X1724796Y0080384
X1724796Y0077784
X1724796Y0082984
X1713985Y0053598
X1734444Y0109410
X1734444Y0116496
X1734310Y0103037
X1727350Y0092849
X1733985Y0053598
X1756847Y0110445
X1756847Y0115401
X1751855Y0115401
X1751855Y0110445
X1742444Y0109410
X1742444Y0116496
X1742444Y0102323
X1751727Y0094017
X1747727Y0094017
X1751456Y0101701
X1755727Y0094017
X1752091Y0044773
X1752091Y0024773
X1762257Y0117557
X1759736Y0094017
X1764804Y0080140
X1764804Y0076140
X1764804Y0084140
X1759006Y0103783
X1767249Y0117557
X1764753Y0121735
X1754351Y0111223
X1736405Y-0072678
X1736405Y-0069278
X1733909Y-0073456
X1733909Y-0068500
X1739311Y-0075885
X1739311Y-0065585
X1745604Y-0077094
X1742351Y-0077080
X1745604Y-0066780
X1742351Y-0066780
X1745592Y-0069470
X1745589Y-0064265
X1742336Y-0064265
X1745589Y-0074579
X1742336Y-0074565
X1745592Y-0071970
X1669319Y0003001
X1689319Y0003001
X1705303Y0004470
X1752778Y0005374
X1765559Y0003001
X1801761Y-0040488
X1801761Y-0030488
X1736405Y-0082678
X1736405Y-0079278
X1801761Y-0043888
X1801761Y-0033888
X1799265Y-0034666
X1799265Y-0029710
X1799265Y-0039710
X1799265Y-0044666
X1733909Y-0078500
X1733909Y-0083456
X1739311Y-0086371
X1745592Y-0082584
X1745604Y-0085262
X1742351Y-0085262
X1745589Y-0087777
X1742336Y-0087777
X1745592Y-0079984
X1804667Y-0047581
X1804667Y-0037095
X1804667Y-0026795
X1810948Y-0043794
X1810960Y-0046472
X1807707Y-0046486
X1810945Y-0048987
X1807692Y-0049001
X1810960Y-0038304
X1810948Y-0041194
X1807707Y-0038290
X1810960Y-0027990
X1807707Y-0027990
X1810948Y-0030680
X1810945Y-0025475
X1807692Y-0025475
X1810945Y-0035789
X1807692Y-0035775
X1810948Y-0033180
X1836543Y0004470
X1825559Y0003001
X1790664Y0071908
X1777653Y0103621
X1773364Y0112083
X1790712Y0081713
X1781832Y0060513
X1782517Y0094351
X1785246Y0060660
X1786466Y0094279
X1781960Y0085731
X1786466Y0085923
X1791088Y0077296
X1790373Y0094663
X1779600Y0088801
X1775470Y0080581
X1775457Y0068581
X1779232Y0055513
X1770173Y0103621
X1778179Y0117261
X1779575Y0091951
X1782382Y0055513
X1788884Y0059871
X1837904Y0104774
X1837904Y0084774
X1837904Y0064774
X1837904Y0044774
X1837904Y0024774
X1791570Y0074535
X1777109Y0178560
X1777172Y0172665
X1785999Y0186778
X1785918Y0208864
X1777312Y0207037
X1777289Y0200864
X1777378Y0212455
X1785886Y0196665
X1785779Y0192665
X1776999Y0183834
X1776519Y0190185
X1771244Y0192490
X1771714Y0171523
X1781559Y0219379
X1785918Y0204864
X1777985Y0186629
X1785886Y0176665
X1785886Y0168665
X1774679Y0221642
X1770329Y0221708
X1770199Y0206767
X1770588Y0185121
X1774356Y0192421
X1770633Y0180527
X1785918Y0221864
X1785918Y0216864
X1785918Y0212864
X1785918Y0200864
X1785886Y0180665
X1785886Y0172665
X1837904Y0204774
X1837904Y0184774
X1837904Y0164774
X1837904Y0144774
X1837904Y0124774
X1782187Y0228631
X1805196Y0300952
X1804758Y0294429
X1787674Y0303130
X1793524Y0303343
X1769633Y0268195
X1772433Y0270695
X1772433Y0268195
X1769633Y0270695
X1769436Y0248765
X1771936Y0248765
X1769495Y0236189
X1771995Y0236189
X1776093Y0265897
X1778593Y0265897
X1772736Y0288345
X1772736Y0290845
X1770236Y0288345
X1770236Y0290845
X1770236Y0293645
X1772736Y0293645
X1790533Y0303750
X1837904Y0304774
X1837904Y0284774
X1837904Y0264774
X1837904Y0244774
X1837904Y0224774
X1804993Y0297591
X1805497Y0408104
X1802697Y0408104
X1799897Y0408104
X1805214Y0420375
X1802414Y0420375
X1799614Y0420375
X1777681Y0384651
X1777681Y0382151
X1777681Y0387151
X1769713Y0387702
X1772513Y0387702
X1773278Y0402642
X1770778Y0402642
X1783146Y0420393
X1785646Y0420393
X1780646Y0420393
X1780528Y0408240
X1785528Y0408240
X1783028Y0408240
X1778103Y0396661
X1778103Y0401661
X1778103Y0399161
X1790136Y0396661
X1790136Y0401661
X1790136Y0399161
X1772953Y0413611
X1770453Y0413611
X1830094Y0333210
X1837728Y0324733
X1822983Y0406053
X1822983Y0386053
X1822983Y0366053
X1822983Y0346053
X1809358Y0442114
X1809338Y0447121
X1792527Y0452799
X1786170Y0448931
X1803530Y0431112
X1803700Y0440101
X1797907Y0452987
X1809346Y0452601
X1803335Y0452718
X1809095Y0435101
X1777061Y0475560
X1790061Y0474513
X1776561Y0467560
X1770135Y0490711
X1783384Y0443721
X1786184Y0443721
X1783384Y0440921
X1786184Y0440921
X1783384Y0438121
X1783384Y0435321
X1786184Y0438121
X1786184Y0435321
X1800933Y0461607
X1796136Y0471334
X1796933Y0461607
X1804933Y0461607
X1786693Y0459170
X1793475Y0424939
X1793475Y0427439
X1822983Y0486053
X1783014Y0474513
X1783107Y0426740
X1783107Y0424240
X1770393Y0423944
X1772893Y0423944
X1822983Y0466053
X1817439Y0447101
X1822983Y0446053
X1822983Y0426053
X1803570Y0436164
X1804984Y0433975
X1790014Y0468607
X1786713Y0455039
X1822983Y0506053
X1784602Y0564092
X1822983Y0606053
X1822983Y0586053
X1822983Y0566053
X1822983Y0546053
X1822983Y0526053
X1822983Y0706053
X1822983Y0686053
X1822983Y0666053
X1822983Y0646053
X1822983Y0626053
X1798705Y0718793
X1793149Y0662810
X1791041Y0818795
X1822983Y0786053
X1822983Y0766053
X1822983Y0746053
X1822983Y0726053
X1772768Y0818696
X1822983Y0806053
X1819900Y0906900
X1779404Y0826570
X1778047Y0916120
X1802000Y0892447
X1780016Y0874400
X1788396Y0895066
X1780665Y0902796
X1773614Y0895275
X1781000Y0888087
X1782600Y0874500
X1773600Y0888100
X1788300Y0902800
X1773600Y0902800
X1788400Y0888100
X1778801Y0836469
X1791302Y0829031
X1822983Y0906053
X1822983Y0886053
X1822983Y0866053
X1822983Y0846053
X1822983Y0826053
X1769064Y0923724
X1808014Y0984832
X1802363Y0989660
X1786863Y0985060
X1807663Y0963860
X1801963Y0969160
X1805463Y0969260
X1807663Y0966660
X1779143Y0995203
X1793474Y0930374
X1797365Y0930761
X1789537Y0930498
X1773810Y0990821
X1774476Y0995049
X1793470Y1018762
X1799646Y1018999
X1805188Y1019078
X1811468Y1021084
X1774863Y1019237
X1780802Y1019474
X1786740Y1019237
X1789363Y0969160
X1775904Y0924546
X1773789Y0930663
X1773789Y0927663
X1779363Y0979660
X1785663Y0979660
X1782563Y0979660
X1780158Y0956095
X1782958Y0956095
X1782958Y0953295
X1785758Y0953295
X1785758Y0956095
X1780158Y0953295
X1784306Y0924601
X1786256Y0930626
X1786256Y0927626
X1770680Y0926322
X1831914Y0992877
X1823074Y0992833
X1805863Y0980760
X1792263Y0962960
X1784763Y0964660
X1781263Y0964660
X1797963Y0968760
X1794163Y0968760
X1793563Y0982360
X1798163Y0982360
X1816322Y0977215
X1831511Y0978888
X1772599Y0993053
X1837937Y1013244
X1837937Y0993244
X1837937Y0973244
X1830472Y0960970
X1822983Y0946053
X1822983Y0926053
X1824706Y1093150
X1810310Y1104819
X1828272Y1095968
X1824706Y1106145
X1824706Y1100185
X1793221Y1121122
X1798306Y1114589
X1800906Y1114589
X1803506Y1114589
X1806206Y1114589
X1775366Y1111038
X1777966Y1111038
X1783166Y1111038
X1780566Y1111038
X1790521Y1121122
X1787921Y1121122
X1785321Y1121122
X1775462Y1108413
X1778062Y1108413
X1783262Y1108413
X1780662Y1108413
X1810346Y1082250
X1816756Y1101145
X1816235Y1083970
X1816756Y1094145
X1816756Y1089145
X1795819Y1088553
X1801961Y1081717
X1807844Y1027248
X1807844Y1023694
X1792844Y1027248
X1798844Y1027248
X1795844Y1023694
X1801844Y1023694
X1803351Y1027471
X1789844Y1023694
X1774844Y1027248
X1780844Y1027248
X1786844Y1027248
X1783844Y1023694
X1774844Y1023694
X1810349Y1031264
X1779033Y1023432
X1771773Y1028829
X1812538Y1026859
X1790736Y1074590
X1790736Y1072090
X1781198Y1072207
X1778598Y1072207
X1783798Y1072207
X1783798Y1074707
X1778598Y1074707
X1781198Y1074707
X1775998Y1072207
X1775998Y1074707
X1795936Y1074590
X1793336Y1074590
X1798536Y1074590
X1798536Y1072090
X1793336Y1072090
X1795936Y1072090
X1790572Y1085152
X1790639Y1082585
X1775126Y1092351
X1775126Y1089851
X1780326Y1092351
X1777726Y1092351
X1782926Y1092351
X1782926Y1089851
X1777726Y1089851
X1780326Y1089851
X1830915Y1109146
X1816756Y1097145
X1800813Y1103246
X1824949Y1077145
X1824706Y1085145
X1812296Y1075688
X1825832Y1097589
X1774799Y1121122
X1772099Y1121122
X1769499Y1121122
X1792863Y1103246
X1805013Y1096470
X1799012Y1095893
X1792847Y1099210
X1805013Y1091877
X1837937Y1113244
X1837937Y1093244
X1824733Y1102830
X1824706Y1089145
X1824706Y1081145
X1837937Y1073244
X1837937Y1053244
X1837937Y1033244
X1817628Y1114589
X1815028Y1114589
X1820228Y1114589
X1822928Y1114589
X1809651Y1096426
X1809696Y1091832
X1834665Y1213239
X1809535Y1144912
X1807035Y1144912
X1784302Y1147822
X1781802Y1147822
X1809535Y1136912
X1807035Y1136912
X1807232Y1133356
X1804532Y1133356
X1793221Y1130822
X1784374Y1139822
X1785321Y1130822
X1787921Y1130822
X1781874Y1139822
X1790521Y1130822
X1806602Y1124328
X1803902Y1124328
X1801302Y1124328
X1798702Y1124328
X1802670Y1210905
X1783278Y1208140
X1807243Y1219955
X1800489Y1220598
X1812130Y1205349
X1806835Y1214668
X1814741Y1217093
X1822594Y1215324
X1769599Y1130822
X1772199Y1130822
X1782581Y1213800
X1782581Y1216600
X1782581Y1219400
X1782581Y1222200
X1779581Y1213800
X1779581Y1216600
X1779581Y1219400
X1779581Y1222200
X1777399Y1139822
X1774899Y1139822
X1774899Y1130822
X1801147Y1208555
X1801285Y1213373
X1796607Y1200108
X1837937Y1213244
X1837937Y1193244
X1837937Y1173244
X1837937Y1153244
X1837937Y1133244
X1822594Y1211054
X1815865Y1133356
X1813885Y1136912
X1820328Y1124289
X1815128Y1124289
X1817728Y1124289
X1823028Y1124289
X1816385Y1144912
X1813885Y1144912
X1816385Y1136912
X1774899Y1147822
X1777399Y1147822
X1811482Y1226423
X1805126Y1225745
X1810018Y1298744
X1812818Y1298744
X1815618Y1295944
X1815618Y1298744
X1812818Y1295944
X1810018Y1295944
X1794845Y1263544
X1797345Y1263544
X1799845Y1263544
X1797345Y1261044
X1794845Y1261044
X1799845Y1261044
X1780397Y1251269
X1780397Y1248769
X1780397Y1234969
X1785961Y1224892
X1782581Y1225000
X1779581Y1225000
X1802844Y1227695
X1791099Y1260421
X1780397Y1244369
X1780397Y1241869
X1780397Y1228069
X1780397Y1230569
X1780397Y1237469
X1837937Y1313244
X1837937Y1293244
X1837937Y1273244
X1837937Y1253244
X1809897Y1246685
X1809897Y1244185
X1809897Y1239785
X1809897Y1232885
X1809897Y1230385
X1809897Y1237285
X1837937Y1333244
X1837937Y1393244
X1837937Y1373244
X1837937Y1353244
X1812202Y1432624
X1772188Y1428369
X1802813Y1464015
X1795374Y1444543
X1783178Y1437550
X1787745Y1437765
X1786091Y1443715
X1778227Y1438099
X1809342Y1476733
X1806428Y1444543
X1803885Y1435046
X1803762Y1467236
X1778104Y1470289
X1786564Y1478858
X1793879Y1472952
X1779868Y1446668
X1793976Y1440762
X1807393Y1436345
X1774339Y1437975
X1807270Y1468535
X1774216Y1470165
X1837937Y1513244
X1837937Y1493244
X1837937Y1473244
X1837937Y1453244
X1837937Y1433244
X1837937Y1573244
X1837937Y1553244
X1837937Y1533244
X1777131Y1604357
X1773820Y1631238
X1772422Y1640303
X1772000Y1644980
X1792000Y1644980
X1812000Y1644980
X1832000Y1644980
X1837933Y1636171
X1776422Y1640303
M00
X0109882Y1622402
X0127205Y1622402
X0144528Y1622402
X0161850Y1622402
X0118543Y1616496
X0109882Y1612166
X0118543Y1611378
X0109882Y1607048
X0118543Y1601142
X0109882Y1596811
X0118543Y1596024
X0109882Y1591693
X0118543Y1585788
X0109882Y1581457
X0118543Y1580670
X0109882Y1576339
X0118543Y1570434
X0109882Y1566103
X0118543Y1565315
X0109882Y1560985
X0135866Y1616496
X0127205Y1612166
X0135866Y1611378
X0127205Y1607048
X0135866Y1601142
X0127205Y1596811
X0135866Y1596024
X0127205Y1591693
X0135866Y1585788
X0127205Y1581457
X0135866Y1580670
X0127205Y1576339
X0135866Y1570434
X0127205Y1566103
X0135866Y1565315
X0127205Y1560985
X0153189Y1616496
X0144528Y1612166
X0153189Y1611378
X0144528Y1607048
X0153189Y1601142
X0144528Y1596811
X0153189Y1596024
X0144528Y1591693
X0153189Y1585788
X0144528Y1581457
X0153189Y1580670
X0144528Y1576339
X0153189Y1570434
X0144528Y1566103
X0153189Y1565315
X0144528Y1560985
X0161850Y1612166
X0161850Y1607048
X0161850Y1596811
X0161850Y1591693
X0161850Y1581457
X0161850Y1576339
X0161850Y1566103
X0161850Y1560985
X0118543Y1514134
X0109882Y1509804
X0118543Y1509016
X0109882Y1504685
X0118543Y1498780
X0109882Y1494449
X0118543Y1493662
X0109882Y1489331
X0118543Y1483426
X0109882Y1479095
X0118543Y1478308
X0109882Y1473977
X0118543Y1468071
X0109882Y1463741
X0118543Y1462953
X0109882Y1458622
X0118543Y1452717
X0135866Y1514134
X0127205Y1509804
X0135866Y1509016
X0127205Y1504685
X0135866Y1498780
X0127205Y1494449
X0135866Y1493662
X0127205Y1489331
X0135866Y1483426
X0127205Y1479095
X0135866Y1478308
X0127205Y1473977
X0135866Y1468071
X0127205Y1463741
X0135866Y1462953
X0127205Y1458622
X0135866Y1452717
X0153189Y1514134
X0144528Y1509804
X0153189Y1509016
X0144528Y1504685
X0153189Y1498780
X0144528Y1494449
X0153189Y1493662
X0144528Y1489331
X0153189Y1483426
X0144528Y1479095
X0153189Y1478308
X0144528Y1473977
X0153189Y1468071
X0144528Y1463741
X0153189Y1462953
X0144528Y1458622
X0153189Y1452717
X0161850Y1509804
X0161850Y1504685
X0161850Y1494449
X0161850Y1489331
X0161850Y1479095
X0161850Y1473977
X0161850Y1463741
X0161850Y1458622
X0170512Y1514134
X0170512Y1509016
X0170512Y1498780
X0170512Y1493662
X0170512Y1483426
X0170512Y1478308
X0170512Y1468071
X0170512Y1462953
X0170512Y1452717
X0187835Y1514134
X0187835Y1509016
X0179173Y1509804
X0179173Y1504685
X0187835Y1498780
X0187835Y1493662
X0179173Y1494449
X0179173Y1489331
X0187835Y1483426
X0187835Y1478308
X0179173Y1479095
X0179173Y1473977
X0187835Y1468071
X0187835Y1462953
X0179173Y1463741
X0179173Y1458622
X0187835Y1452717
X0170512Y1616496
X0170512Y1611378
X0170512Y1601142
X0170512Y1596024
X0170512Y1585788
X0170512Y1580670
X0170512Y1570434
X0170512Y1565315
X0187835Y1616496
X0187835Y1611378
X0179173Y1612166
X0179173Y1607048
X0187835Y1601142
X0187835Y1596024
X0179173Y1596811
X0179173Y1591693
X0187835Y1585788
X0187835Y1580670
X0179173Y1581457
X0179173Y1576339
X0187835Y1570434
X0187835Y1565315
X0179173Y1566103
X0179173Y1560985
X0179173Y1622402
X0283110Y1622402
X0300433Y1622402
X0317756Y1622402
X0335078Y1622402
X0352401Y1622402
X0291771Y1616496
X0283110Y1612166
X0291771Y1611378
X0283110Y1607048
X0291771Y1601142
X0283110Y1596811
X0291771Y1596024
X0283110Y1591693
X0291771Y1585788
X0283110Y1581457
X0291771Y1580670
X0283110Y1576339
X0291771Y1570434
X0283110Y1566103
X0291771Y1565315
X0283110Y1560985
X0309094Y1616496
X0300433Y1612166
X0309094Y1611378
X0300433Y1607048
X0309094Y1601142
X0300433Y1596811
X0309094Y1596024
X0300433Y1591693
X0309094Y1585788
X0300433Y1581457
X0309094Y1580670
X0300433Y1576339
X0309094Y1570434
X0300433Y1566103
X0309094Y1565315
X0300433Y1560985
X0326417Y1616496
X0317756Y1612166
X0326417Y1611378
X0317756Y1607048
X0326417Y1601142
X0317756Y1596811
X0326417Y1596024
X0317756Y1591693
X0326417Y1585788
X0317756Y1581457
X0326417Y1580670
X0317756Y1576339
X0326417Y1570434
X0317756Y1566103
X0326417Y1565315
X0317756Y1560985
X0343740Y1616496
X0335078Y1612166
X0343740Y1611378
X0335078Y1607048
X0343740Y1601142
X0335078Y1596811
X0343740Y1596024
X0335078Y1591693
X0343740Y1585788
X0335078Y1581457
X0343740Y1580670
X0335078Y1576339
X0343740Y1570434
X0335078Y1566103
X0343740Y1565315
X0335078Y1560985
X0361063Y1616496
X0361063Y1611378
X0352401Y1612166
X0352401Y1607048
X0361063Y1601142
X0361063Y1596024
X0352401Y1596811
X0352401Y1591693
X0361063Y1585788
X0361063Y1580670
X0352401Y1581457
X0352401Y1576339
X0361063Y1570434
X0361063Y1565315
X0352401Y1566103
X0352401Y1560985
X0291771Y1514134
X0283110Y1509804
X0291771Y1509016
X0283110Y1504685
X0291771Y1498780
X0283110Y1494449
X0291771Y1493662
X0283110Y1489331
X0291771Y1483426
X0283110Y1479095
X0291771Y1478308
X0283110Y1473977
X0291771Y1468071
X0283110Y1463741
X0291771Y1462953
X0283110Y1458622
X0291771Y1452717
X0309094Y1514134
X0300433Y1509804
X0309094Y1509016
X0300433Y1504685
X0309094Y1498780
X0300433Y1494449
X0309094Y1493662
X0300433Y1489331
X0309094Y1483426
X0300433Y1479095
X0309094Y1478308
X0300433Y1473977
X0309094Y1468071
X0300433Y1463741
X0309094Y1462953
X0300433Y1458622
X0309094Y1452717
X0326417Y1514134
X0317756Y1509804
X0326417Y1509016
X0317756Y1504685
X0326417Y1498780
X0317756Y1494449
X0326417Y1493662
X0317756Y1489331
X0326417Y1483426
X0317756Y1479095
X0326417Y1478308
X0317756Y1473977
X0326417Y1468071
X0317756Y1463741
X0326417Y1462953
X0317756Y1458622
X0326417Y1452717
X0343740Y1514134
X0335078Y1509804
X0343740Y1509016
X0335078Y1504685
X0343740Y1498780
X0335078Y1494449
X0343740Y1493662
X0335078Y1489331
X0343740Y1483426
X0335078Y1479095
X0343740Y1478308
X0335078Y1473977
X0343740Y1468071
X0335078Y1463741
X0343740Y1462953
X0335078Y1458622
X0343740Y1452717
X0361063Y1514134
X0361063Y1509016
X0352401Y1509804
X0352401Y1504685
X0361063Y1498780
X0361063Y1493662
X0352401Y1494449
X0352401Y1489331
X0361063Y1483426
X0361063Y1478308
X0352401Y1479095
X0352401Y1473977
X0361063Y1468071
X0361063Y1462953
X0352401Y1463741
X0352401Y1458622
X0361063Y1452717
X0465000Y1514134
X0456339Y1509804
X0465000Y1509016
X0456339Y1504685
X0465000Y1498780
X0456339Y1494449
X0465000Y1493662
X0456339Y1489331
X0465000Y1483426
X0456339Y1479095
X0465000Y1478308
X0456339Y1473977
X0465000Y1468071
X0456339Y1463741
X0465000Y1462953
X0456339Y1458622
X0465000Y1452717
X0465000Y1616496
X0456339Y1612166
X0465000Y1611378
X0456339Y1607048
X0465000Y1601142
X0456339Y1596811
X0465000Y1596024
X0456339Y1591693
X0465000Y1585788
X0456339Y1581457
X0465000Y1580670
X0456339Y1576339
X0465000Y1570434
X0456339Y1566103
X0465000Y1565315
X0456339Y1560985
X0456339Y1622402
X0473662Y1622402
X0490985Y1622402
X0508307Y1622402
X0525630Y1622402
X0482323Y1616496
X0473662Y1612166
X0482323Y1611378
X0473662Y1607048
X0482323Y1601142
X0473662Y1596811
X0482323Y1596024
X0473662Y1591693
X0482323Y1585788
X0473662Y1581457
X0482323Y1580670
X0473662Y1576339
X0482323Y1570434
X0473662Y1566103
X0482323Y1565315
X0473662Y1560985
X0499646Y1616496
X0490985Y1612166
X0499646Y1611378
X0490985Y1607048
X0499646Y1601142
X0490985Y1596811
X0499646Y1596024
X0490985Y1591693
X0499646Y1585788
X0490985Y1581457
X0499646Y1580670
X0490985Y1576339
X0499646Y1570434
X0490985Y1566103
X0499646Y1565315
X0490985Y1560985
X0516969Y1616496
X0508307Y1612166
X0516969Y1611378
X0508307Y1607048
X0516969Y1601142
X0508307Y1596811
X0516969Y1596024
X0508307Y1591693
X0516969Y1585788
X0508307Y1581457
X0516969Y1580670
X0508307Y1576339
X0516969Y1570434
X0508307Y1566103
X0516969Y1565315
X0508307Y1560985
X0534292Y1616496
X0534292Y1611378
X0525630Y1612166
X0525630Y1607048
X0534292Y1601142
X0534292Y1596024
X0525630Y1596811
X0525630Y1591693
X0534292Y1585788
X0534292Y1580670
X0525630Y1581457
X0525630Y1576339
X0534292Y1570434
X0534292Y1565315
X0525630Y1566103
X0525630Y1560985
X0482323Y1514134
X0473662Y1509804
X0482323Y1509016
X0473662Y1504685
X0482323Y1498780
X0473662Y1494449
X0482323Y1493662
X0473662Y1489331
X0482323Y1483426
X0473662Y1479095
X0482323Y1478308
X0473662Y1473977
X0482323Y1468071
X0473662Y1463741
X0482323Y1462953
X0473662Y1458622
X0482323Y1452717
X0499646Y1514134
X0490985Y1509804
X0499646Y1509016
X0490985Y1504685
X0499646Y1498780
X0490985Y1494449
X0499646Y1493662
X0490985Y1489331
X0499646Y1483426
X0490985Y1479095
X0499646Y1478308
X0490985Y1473977
X0499646Y1468071
X0490985Y1463741
X0499646Y1462953
X0490985Y1458622
X0499646Y1452717
X0516969Y1514134
X0508307Y1509804
X0516969Y1509016
X0508307Y1504685
X0516969Y1498780
X0508307Y1494449
X0516969Y1493662
X0508307Y1489331
X0516969Y1483426
X0508307Y1479095
X0516969Y1478308
X0508307Y1473977
X0516969Y1468071
X0508307Y1463741
X0516969Y1462953
X0508307Y1458622
X0516969Y1452717
X0534292Y1514134
X0534292Y1509016
X0525630Y1509804
X0525630Y1504685
X0534292Y1498780
X0534292Y1493662
X0525630Y1494449
X0525630Y1489331
X0534292Y1483426
X0534292Y1478308
X0525630Y1479095
X0525630Y1473977
X0534292Y1468071
X0534292Y1462953
X0525630Y1463741
X0525630Y1458622
X0534292Y1452717
X0638228Y1514134
X0629567Y1509804
X0638228Y1509016
X0629567Y1504685
X0638228Y1498780
X0629567Y1494449
X0638228Y1493662
X0629567Y1489331
X0638228Y1483426
X0629567Y1479095
X0638228Y1478308
X0629567Y1473977
X0638228Y1468071
X0629567Y1463741
X0638228Y1462953
X0629567Y1458622
X0638228Y1452717
X0655551Y1514134
X0646890Y1509804
X0655551Y1509016
X0646890Y1504685
X0655551Y1498780
X0646890Y1494449
X0655551Y1493662
X0646890Y1489331
X0655551Y1483426
X0646890Y1479095
X0655551Y1478308
X0646890Y1473977
X0655551Y1468071
X0646890Y1463741
X0655551Y1462953
X0646890Y1458622
X0655551Y1452717
X0664213Y1509804
X0664213Y1504685
X0664213Y1494449
X0664213Y1489331
X0664213Y1479095
X0664213Y1473977
X0664213Y1463741
X0664213Y1458622
X0638228Y1616496
X0629567Y1612166
X0638228Y1611378
X0629567Y1607048
X0638228Y1601142
X0629567Y1596811
X0638228Y1596024
X0629567Y1591693
X0638228Y1585788
X0629567Y1581457
X0638228Y1580670
X0629567Y1576339
X0638228Y1570434
X0629567Y1566103
X0638228Y1565315
X0629567Y1560985
X0655551Y1616496
X0646890Y1612166
X0655551Y1611378
X0646890Y1607048
X0655551Y1601142
X0646890Y1596811
X0655551Y1596024
X0646890Y1591693
X0655551Y1585788
X0646890Y1581457
X0655551Y1580670
X0646890Y1576339
X0655551Y1570434
X0646890Y1566103
X0655551Y1565315
X0646890Y1560985
X0664213Y1612166
X0664213Y1607048
X0664213Y1596811
X0664213Y1591693
X0664213Y1581457
X0664213Y1576339
X0664213Y1566103
X0664213Y1560985
X0629567Y1622402
X0646890Y1622402
X0664213Y1622402
X0681535Y1622402
X0698858Y1622402
X0672874Y1616496
X0672874Y1611378
X0672874Y1601142
X0672874Y1596024
X0672874Y1585788
X0672874Y1580670
X0672874Y1570434
X0672874Y1565315
X0690197Y1616496
X0681535Y1612166
X0690197Y1611378
X0681535Y1607048
X0690197Y1601142
X0681535Y1596811
X0690197Y1596024
X0681535Y1591693
X0690197Y1585788
X0681535Y1581457
X0690197Y1580670
X0681535Y1576339
X0690197Y1570434
X0681535Y1566103
X0690197Y1565315
X0681535Y1560985
X0707520Y1616496
X0707520Y1611378
X0698858Y1612166
X0698858Y1607048
X0707520Y1601142
X0707520Y1596024
X0698858Y1596811
X0698858Y1591693
X0707520Y1585788
X0707520Y1580670
X0698858Y1581457
X0698858Y1576339
X0707520Y1570434
X0707520Y1565315
X0698858Y1566103
X0698858Y1560985
X0672874Y1514134
X0672874Y1509016
X0672874Y1498780
X0672874Y1493662
X0672874Y1483426
X0672874Y1478308
X0672874Y1468071
X0672874Y1462953
X0672874Y1452717
X0690197Y1514134
X0681535Y1509804
X0690197Y1509016
X0681535Y1504685
X0690197Y1498780
X0681535Y1494449
X0690197Y1493662
X0681535Y1489331
X0690197Y1483426
X0681535Y1479095
X0690197Y1478308
X0681535Y1473977
X0690197Y1468071
X0681535Y1463741
X0690197Y1462953
X0681535Y1458622
X0690197Y1452717
X0707520Y1514134
X0707520Y1509016
X0698858Y1509804
X0698858Y1504685
X0707520Y1498780
X0707520Y1493662
X0698858Y1494449
X0698858Y1489331
X0707520Y1483426
X0707520Y1478308
X0698858Y1479095
X0698858Y1473977
X0707520Y1468071
X0707520Y1462953
X0698858Y1463741
X0698858Y1458622
X0707520Y1452717
X1131850Y1622402
X1149173Y1622402
X1166496Y1622402
X1140511Y1616496
X1131850Y1612166
X1140511Y1611378
X1131850Y1607048
X1140511Y1601142
X1131850Y1596811
X1140511Y1596024
X1131850Y1591693
X1140511Y1585788
X1131850Y1581457
X1140511Y1580670
X1131850Y1576339
X1140511Y1570434
X1131850Y1566103
X1140511Y1565315
X1131850Y1560985
X1157834Y1616496
X1149173Y1612166
X1157834Y1611378
X1149173Y1607048
X1157834Y1601142
X1149173Y1596811
X1157834Y1596024
X1149173Y1591693
X1157834Y1585788
X1149173Y1581457
X1157834Y1580670
X1149173Y1576339
X1157834Y1570434
X1149173Y1566103
X1157834Y1565315
X1149173Y1560985
X1166496Y1612166
X1166496Y1607048
X1166496Y1596811
X1166496Y1591693
X1166496Y1581457
X1166496Y1576339
X1166496Y1566103
X1166496Y1560985
X1140511Y1514134
X1131850Y1509804
X1140511Y1509016
X1131850Y1504685
X1140511Y1498780
X1131850Y1494449
X1140511Y1493662
X1131850Y1489331
X1140511Y1483426
X1131850Y1479095
X1140511Y1478308
X1131850Y1473977
X1140511Y1468071
X1131850Y1463741
X1140511Y1462953
X1131850Y1458622
X1140511Y1452717
X1157834Y1514134
X1149173Y1509804
X1157834Y1509016
X1149173Y1504685
X1157834Y1498780
X1149173Y1494449
X1157834Y1493662
X1149173Y1489331
X1157834Y1483426
X1149173Y1479095
X1157834Y1478308
X1149173Y1473977
X1157834Y1468071
X1149173Y1463741
X1157834Y1462953
X1149173Y1458622
X1157834Y1452717
X1166496Y1509804
X1166496Y1504685
X1166496Y1494449
X1166496Y1489331
X1166496Y1479095
X1166496Y1473977
X1166496Y1463741
X1166496Y1458622
X1175157Y1514134
X1175157Y1509016
X1175157Y1498780
X1175157Y1493662
X1175157Y1483426
X1175157Y1478308
X1175157Y1468071
X1175157Y1462953
X1175157Y1452717
X1192480Y1514134
X1183818Y1509804
X1192480Y1509016
X1183818Y1504685
X1192480Y1498780
X1183818Y1494449
X1192480Y1493662
X1183818Y1489331
X1192480Y1483426
X1183818Y1479095
X1192480Y1478308
X1183818Y1473977
X1192480Y1468071
X1183818Y1463741
X1192480Y1462953
X1183818Y1458622
X1192480Y1452717
X1209803Y1514134
X1209803Y1509016
X1201141Y1509804
X1201141Y1504685
X1209803Y1498780
X1209803Y1493662
X1201141Y1494449
X1201141Y1489331
X1209803Y1483426
X1209803Y1478308
X1201141Y1479095
X1201141Y1473977
X1209803Y1468071
X1209803Y1462953
X1201141Y1463741
X1201141Y1458622
X1209803Y1452717
X1175157Y1616496
X1175157Y1611378
X1175157Y1601142
X1175157Y1596024
X1175157Y1585788
X1175157Y1580670
X1175157Y1570434
X1175157Y1565315
X1192480Y1616496
X1183818Y1612166
X1192480Y1611378
X1183818Y1607048
X1192480Y1601142
X1183818Y1596811
X1192480Y1596024
X1183818Y1591693
X1192480Y1585788
X1183818Y1581457
X1192480Y1580670
X1183818Y1576339
X1192480Y1570434
X1183818Y1566103
X1192480Y1565315
X1183818Y1560985
X1209803Y1616496
X1209803Y1611378
X1201141Y1612166
X1201141Y1607048
X1209803Y1601142
X1209803Y1596024
X1201141Y1596811
X1201141Y1591693
X1209803Y1585788
X1209803Y1580670
X1201141Y1581457
X1201141Y1576339
X1209803Y1570434
X1209803Y1565315
X1201141Y1566103
X1201141Y1560985
X1183818Y1622402
X1201141Y1622402
X1305079Y1622402
X1322402Y1622402
X1339725Y1622402
X1357047Y1622402
X1313740Y1616496
X1305079Y1612166
X1313740Y1611378
X1305079Y1607048
X1313740Y1601142
X1305079Y1596811
X1313740Y1596024
X1305079Y1591693
X1313740Y1585788
X1305079Y1581457
X1313740Y1580670
X1305079Y1576339
X1313740Y1570434
X1305079Y1566103
X1313740Y1565315
X1305079Y1560985
X1331063Y1616496
X1322402Y1612166
X1331063Y1611378
X1322402Y1607048
X1331063Y1601142
X1322402Y1596811
X1331063Y1596024
X1322402Y1591693
X1331063Y1585788
X1322402Y1581457
X1331063Y1580670
X1322402Y1576339
X1331063Y1570434
X1322402Y1566103
X1331063Y1565315
X1322402Y1560985
X1348386Y1616496
X1339725Y1612166
X1348386Y1611378
X1339725Y1607048
X1348386Y1601142
X1339725Y1596811
X1348386Y1596024
X1339725Y1591693
X1348386Y1585788
X1339725Y1581457
X1348386Y1580670
X1339725Y1576339
X1348386Y1570434
X1339725Y1566103
X1348386Y1565315
X1339725Y1560985
X1365709Y1616496
X1357047Y1612166
X1365709Y1611378
X1357047Y1607048
X1365709Y1601142
X1357047Y1596811
X1365709Y1596024
X1357047Y1591693
X1365709Y1585788
X1357047Y1581457
X1365709Y1580670
X1357047Y1576339
X1365709Y1570434
X1357047Y1566103
X1365709Y1565315
X1357047Y1560985
X1313740Y1514134
X1305079Y1509804
X1313740Y1509016
X1305079Y1504685
X1313740Y1498780
X1305079Y1494449
X1313740Y1493662
X1305079Y1489331
X1313740Y1483426
X1305079Y1479095
X1313740Y1478308
X1305079Y1473977
X1313740Y1468071
X1305079Y1463741
X1313740Y1462953
X1305079Y1458622
X1313740Y1452717
X1331063Y1514134
X1322402Y1509804
X1331063Y1509016
X1322402Y1504685
X1331063Y1498780
X1322402Y1494449
X1331063Y1493662
X1322402Y1489331
X1331063Y1483426
X1322402Y1479095
X1331063Y1478308
X1322402Y1473977
X1331063Y1468071
X1322402Y1463741
X1331063Y1462953
X1322402Y1458622
X1331063Y1452717
X1348386Y1514134
X1339725Y1509804
X1348386Y1509016
X1339725Y1504685
X1348386Y1498780
X1339725Y1494449
X1348386Y1493662
X1339725Y1489331
X1348386Y1483426
X1339725Y1479095
X1348386Y1478308
X1339725Y1473977
X1348386Y1468071
X1339725Y1463741
X1348386Y1462953
X1339725Y1458622
X1348386Y1452717
X1365709Y1514134
X1357047Y1509804
X1365709Y1509016
X1357047Y1504685
X1365709Y1498780
X1357047Y1494449
X1365709Y1493662
X1357047Y1489331
X1365709Y1483426
X1357047Y1479095
X1365709Y1478308
X1357047Y1473977
X1365709Y1468071
X1357047Y1463741
X1365709Y1462953
X1357047Y1458622
X1365709Y1452717
X1383032Y1514134
X1383032Y1509016
X1374370Y1509804
X1374370Y1504685
X1383032Y1498780
X1383032Y1493662
X1374370Y1494449
X1374370Y1489331
X1383032Y1483426
X1383032Y1478308
X1374370Y1479095
X1374370Y1473977
X1383032Y1468071
X1383032Y1462953
X1374370Y1463741
X1374370Y1458622
X1383032Y1452717
X1383032Y1616496
X1383032Y1611378
X1374370Y1612166
X1374370Y1607048
X1383032Y1601142
X1383032Y1596024
X1374370Y1596811
X1374370Y1591693
X1383032Y1585788
X1383032Y1580670
X1374370Y1581457
X1374370Y1576339
X1383032Y1570434
X1383032Y1565315
X1374370Y1566103
X1374370Y1560985
X1374370Y1622402
X1478307Y1622402
X1495630Y1622402
X1512953Y1622402
X1530275Y1622402
X1547598Y1622402
X1486968Y1616496
X1478307Y1612166
X1486968Y1611378
X1478307Y1607048
X1486968Y1601142
X1478307Y1596811
X1486968Y1596024
X1478307Y1591693
X1486968Y1585788
X1478307Y1581457
X1486968Y1580670
X1478307Y1576339
X1486968Y1570434
X1478307Y1566103
X1486968Y1565315
X1478307Y1560985
X1504291Y1616496
X1495630Y1612166
X1504291Y1611378
X1495630Y1607048
X1504291Y1601142
X1495630Y1596811
X1504291Y1596024
X1495630Y1591693
X1504291Y1585788
X1495630Y1581457
X1504291Y1580670
X1495630Y1576339
X1504291Y1570434
X1495630Y1566103
X1504291Y1565315
X1495630Y1560985
X1521614Y1616496
X1512953Y1612166
X1521614Y1611378
X1512953Y1607048
X1521614Y1601142
X1512953Y1596811
X1521614Y1596024
X1512953Y1591693
X1521614Y1585788
X1512953Y1581457
X1521614Y1580670
X1512953Y1576339
X1521614Y1570434
X1512953Y1566103
X1521614Y1565315
X1512953Y1560985
X1538937Y1616496
X1530275Y1612166
X1538937Y1611378
X1530275Y1607048
X1538937Y1601142
X1530275Y1596811
X1538937Y1596024
X1530275Y1591693
X1538937Y1585788
X1530275Y1581457
X1538937Y1580670
X1530275Y1576339
X1538937Y1570434
X1530275Y1566103
X1538937Y1565315
X1530275Y1560985
X1556260Y1616496
X1556260Y1611378
X1547598Y1612166
X1547598Y1607048
X1556260Y1601142
X1556260Y1596024
X1547598Y1596811
X1547598Y1591693
X1556260Y1585788
X1556260Y1580670
X1547598Y1581457
X1547598Y1576339
X1556260Y1570434
X1556260Y1565315
X1547598Y1566103
X1547598Y1560985
X1486968Y1514134
X1478307Y1509804
X1486968Y1509016
X1478307Y1504685
X1486968Y1498780
X1478307Y1494449
X1486968Y1493662
X1478307Y1489331
X1486968Y1483426
X1478307Y1479095
X1486968Y1478308
X1478307Y1473977
X1486968Y1468071
X1478307Y1463741
X1486968Y1462953
X1478307Y1458622
X1486968Y1452717
X1504291Y1514134
X1495630Y1509804
X1504291Y1509016
X1495630Y1504685
X1504291Y1498780
X1495630Y1494449
X1504291Y1493662
X1495630Y1489331
X1504291Y1483426
X1495630Y1479095
X1504291Y1478308
X1495630Y1473977
X1504291Y1468071
X1495630Y1463741
X1504291Y1462953
X1495630Y1458622
X1504291Y1452717
X1521614Y1514134
X1512953Y1509804
X1521614Y1509016
X1512953Y1504685
X1521614Y1498780
X1512953Y1494449
X1521614Y1493662
X1512953Y1489331
X1521614Y1483426
X1512953Y1479095
X1521614Y1478308
X1512953Y1473977
X1521614Y1468071
X1512953Y1463741
X1521614Y1462953
X1512953Y1458622
X1521614Y1452717
X1538937Y1514134
X1530275Y1509804
X1538937Y1509016
X1530275Y1504685
X1538937Y1498780
X1530275Y1494449
X1538937Y1493662
X1530275Y1489331
X1538937Y1483426
X1530275Y1479095
X1538937Y1478308
X1530275Y1473977
X1538937Y1468071
X1530275Y1463741
X1538937Y1462953
X1530275Y1458622
X1538937Y1452717
X1556260Y1514134
X1556260Y1509016
X1547598Y1509804
X1547598Y1504685
X1556260Y1498780
X1556260Y1493662
X1547598Y1494449
X1547598Y1489331
X1556260Y1483426
X1556260Y1478308
X1547598Y1479095
X1547598Y1473977
X1556260Y1468071
X1556260Y1462953
X1547598Y1463741
X1547598Y1458622
X1556260Y1452717
X1660196Y1514134
X1651535Y1509804
X1660196Y1509016
X1651535Y1504685
X1660196Y1498780
X1651535Y1494449
X1660196Y1493662
X1651535Y1489331
X1660196Y1483426
X1651535Y1479095
X1660196Y1478308
X1651535Y1473977
X1660196Y1468071
X1651535Y1463741
X1660196Y1462953
X1651535Y1458622
X1660196Y1452717
X1668858Y1509804
X1668858Y1504685
X1668858Y1494449
X1668858Y1489331
X1668858Y1479095
X1668858Y1473977
X1668858Y1463741
X1668858Y1458622
X1660196Y1616496
X1651535Y1612166
X1660196Y1611378
X1651535Y1607048
X1660196Y1601142
X1651535Y1596811
X1660196Y1596024
X1651535Y1591693
X1660196Y1585788
X1651535Y1581457
X1660196Y1580670
X1651535Y1576339
X1660196Y1570434
X1651535Y1566103
X1660196Y1565315
X1651535Y1560985
X1668858Y1612166
X1668858Y1607048
X1668858Y1596811
X1668858Y1591693
X1668858Y1581457
X1668858Y1576339
X1668858Y1566103
X1668858Y1560985
X1651535Y1622402
X1668858Y1622402
X1686181Y1622402
X1703503Y1622402
X1720826Y1622402
X1677519Y1616496
X1677519Y1611378
X1677519Y1601142
X1677519Y1596024
X1677519Y1585788
X1677519Y1580670
X1677519Y1570434
X1677519Y1565315
X1694842Y1616496
X1686181Y1612166
X1694842Y1611378
X1686181Y1607048
X1694842Y1601142
X1686181Y1596811
X1694842Y1596024
X1686181Y1591693
X1694842Y1585788
X1686181Y1581457
X1694842Y1580670
X1686181Y1576339
X1694842Y1570434
X1686181Y1566103
X1694842Y1565315
X1686181Y1560985
X1712165Y1616496
X1703503Y1612166
X1712165Y1611378
X1703503Y1607048
X1712165Y1601142
X1703503Y1596811
X1712165Y1596024
X1703503Y1591693
X1712165Y1585788
X1703503Y1581457
X1712165Y1580670
X1703503Y1576339
X1712165Y1570434
X1703503Y1566103
X1712165Y1565315
X1703503Y1560985
X1729488Y1616496
X1729488Y1611378
X1720826Y1612166
X1720826Y1607048
X1729488Y1601142
X1729488Y1596024
X1720826Y1596811
X1720826Y1591693
X1729488Y1585788
X1729488Y1580670
X1720826Y1581457
X1720826Y1576339
X1729488Y1570434
X1729488Y1565315
X1720826Y1566103
X1720826Y1560985
X1677519Y1514134
X1677519Y1509016
X1677519Y1498780
X1677519Y1493662
X1677519Y1483426
X1677519Y1478308
X1677519Y1468071
X1677519Y1462953
X1677519Y1452717
X1694842Y1514134
X1686181Y1509804
X1694842Y1509016
X1686181Y1504685
X1694842Y1498780
X1686181Y1494449
X1694842Y1493662
X1686181Y1489331
X1694842Y1483426
X1686181Y1479095
X1694842Y1478308
X1686181Y1473977
X1694842Y1468071
X1686181Y1463741
X1694842Y1462953
X1686181Y1458622
X1694842Y1452717
X1712165Y1514134
X1703503Y1509804
X1712165Y1509016
X1703503Y1504685
X1712165Y1498780
X1703503Y1494449
X1712165Y1493662
X1703503Y1489331
X1712165Y1483426
X1703503Y1479095
X1712165Y1478308
X1703503Y1473977
X1712165Y1468071
X1703503Y1463741
X1712165Y1462953
X1703503Y1458622
X1712165Y1452717
X1729488Y1514134
X1729488Y1509016
X1720826Y1509804
X1720826Y1504685
X1729488Y1498780
X1729488Y1493662
X1720826Y1494449
X1720826Y1489331
X1729488Y1483426
X1729488Y1478308
X1720826Y1479095
X1720826Y1473977
X1729488Y1468071
X1729488Y1462953
X1720826Y1463741
X1720826Y1458622
X1729488Y1452717
M00
X0118543Y1621615
X0109882Y1617284
X0118543Y1606260
X0109882Y1601930
X0118543Y1590906
X0109882Y1586575
X0118543Y1575552
X0109882Y1571221
X0118543Y1560197
X0109882Y1555867
X0135866Y1621615
X0127205Y1617284
X0135866Y1606260
X0127205Y1601930
X0135866Y1590906
X0127205Y1586575
X0135866Y1575552
X0127205Y1571221
X0135866Y1560197
X0127205Y1555867
X0153189Y1621615
X0144528Y1617284
X0153189Y1606260
X0144528Y1601930
X0153189Y1590906
X0144528Y1586575
X0153189Y1575552
X0144528Y1571221
X0153189Y1560197
X0144528Y1555867
X0161850Y1617284
X0161850Y1601930
X0161850Y1586575
X0161850Y1571221
X0161850Y1555867
X0118543Y1519252
X0109882Y1514922
X0118543Y1503898
X0109882Y1499567
X0118543Y1488544
X0109882Y1484213
X0118543Y1473189
X0109882Y1468859
X0118543Y1457835
X0109882Y1453504
X0135866Y1519252
X0127205Y1514922
X0135866Y1503898
X0127205Y1499567
X0135866Y1488544
X0127205Y1484213
X0135866Y1473189
X0127205Y1468859
X0135866Y1457835
X0127205Y1453504
X0153189Y1519252
X0144528Y1514922
X0153189Y1503898
X0144528Y1499567
X0153189Y1488544
X0144528Y1484213
X0153189Y1473189
X0144528Y1468859
X0153189Y1457835
X0144528Y1453504
X0161850Y1514922
X0161850Y1499567
X0161850Y1484213
X0161850Y1468859
X0161850Y1453504
X0170512Y1519252
X0170512Y1503898
X0170512Y1488544
X0170512Y1473189
X0170512Y1457835
X0187835Y1519252
X0179173Y1514922
X0187835Y1503898
X0179173Y1499567
X0187835Y1488544
X0179173Y1484213
X0187835Y1473189
X0179173Y1468859
X0187835Y1457835
X0179173Y1453504
X0170512Y1621615
X0170512Y1606260
X0170512Y1590906
X0170512Y1575552
X0170512Y1560197
X0187835Y1621615
X0179173Y1617284
X0187835Y1606260
X0179173Y1601930
X0187835Y1590906
X0179173Y1586575
X0187835Y1575552
X0179173Y1571221
X0187835Y1560197
X0179173Y1555867
X0291771Y1621615
X0283110Y1617284
X0291771Y1606260
X0283110Y1601930
X0291771Y1590906
X0283110Y1586575
X0291771Y1575552
X0283110Y1571221
X0291771Y1560197
X0283110Y1555867
X0309094Y1621615
X0300433Y1617284
X0309094Y1606260
X0300433Y1601930
X0309094Y1590906
X0300433Y1586575
X0309094Y1575552
X0300433Y1571221
X0309094Y1560197
X0300433Y1555867
X0326417Y1621615
X0317756Y1617284
X0326417Y1606260
X0317756Y1601930
X0326417Y1590906
X0317756Y1586575
X0326417Y1575552
X0317756Y1571221
X0326417Y1560197
X0317756Y1555867
X0343740Y1621615
X0335078Y1617284
X0343740Y1606260
X0335078Y1601930
X0343740Y1590906
X0335078Y1586575
X0343740Y1575552
X0335078Y1571221
X0343740Y1560197
X0335078Y1555867
X0361063Y1621615
X0352401Y1617284
X0361063Y1606260
X0352401Y1601930
X0361063Y1590906
X0352401Y1586575
X0361063Y1575552
X0352401Y1571221
X0361063Y1560197
X0352401Y1555867
X0291771Y1519252
X0283110Y1514922
X0291771Y1503898
X0283110Y1499567
X0291771Y1488544
X0283110Y1484213
X0291771Y1473189
X0283110Y1468859
X0291771Y1457835
X0283110Y1453504
X0309094Y1519252
X0300433Y1514922
X0309094Y1503898
X0300433Y1499567
X0309094Y1488544
X0300433Y1484213
X0309094Y1473189
X0300433Y1468859
X0309094Y1457835
X0300433Y1453504
X0326417Y1519252
X0317756Y1514922
X0326417Y1503898
X0317756Y1499567
X0326417Y1488544
X0317756Y1484213
X0326417Y1473189
X0317756Y1468859
X0326417Y1457835
X0317756Y1453504
X0343740Y1519252
X0335078Y1514922
X0343740Y1503898
X0335078Y1499567
X0343740Y1488544
X0335078Y1484213
X0343740Y1473189
X0335078Y1468859
X0343740Y1457835
X0335078Y1453504
X0361063Y1519252
X0352401Y1514922
X0361063Y1503898
X0352401Y1499567
X0361063Y1488544
X0352401Y1484213
X0361063Y1473189
X0352401Y1468859
X0361063Y1457835
X0352401Y1453504
X0465000Y1519252
X0456339Y1514922
X0465000Y1503898
X0456339Y1499567
X0465000Y1488544
X0456339Y1484213
X0465000Y1473189
X0456339Y1468859
X0465000Y1457835
X0456339Y1453504
X0465000Y1621615
X0456339Y1617284
X0465000Y1606260
X0456339Y1601930
X0465000Y1590906
X0456339Y1586575
X0465000Y1575552
X0456339Y1571221
X0465000Y1560197
X0456339Y1555867
X0482323Y1621615
X0473662Y1617284
X0482323Y1606260
X0473662Y1601930
X0482323Y1590906
X0473662Y1586575
X0482323Y1575552
X0473662Y1571221
X0482323Y1560197
X0473662Y1555867
X0499646Y1621615
X0490985Y1617284
X0499646Y1606260
X0490985Y1601930
X0499646Y1590906
X0490985Y1586575
X0499646Y1575552
X0490985Y1571221
X0499646Y1560197
X0490985Y1555867
X0516969Y1621615
X0508307Y1617284
X0516969Y1606260
X0508307Y1601930
X0516969Y1590906
X0508307Y1586575
X0516969Y1575552
X0508307Y1571221
X0516969Y1560197
X0508307Y1555867
X0534292Y1621615
X0525630Y1617284
X0534292Y1606260
X0525630Y1601930
X0534292Y1590906
X0525630Y1586575
X0534292Y1575552
X0525630Y1571221
X0534292Y1560197
X0525630Y1555867
X0482323Y1519252
X0473662Y1514922
X0482323Y1503898
X0473662Y1499567
X0482323Y1488544
X0473662Y1484213
X0482323Y1473189
X0473662Y1468859
X0482323Y1457835
X0473662Y1453504
X0499646Y1519252
X0490985Y1514922
X0499646Y1503898
X0490985Y1499567
X0499646Y1488544
X0490985Y1484213
X0499646Y1473189
X0490985Y1468859
X0499646Y1457835
X0490985Y1453504
X0516969Y1519252
X0508307Y1514922
X0516969Y1503898
X0508307Y1499567
X0516969Y1488544
X0508307Y1484213
X0516969Y1473189
X0508307Y1468859
X0516969Y1457835
X0508307Y1453504
X0534292Y1519252
X0525630Y1514922
X0534292Y1503898
X0525630Y1499567
X0534292Y1488544
X0525630Y1484213
X0534292Y1473189
X0525630Y1468859
X0534292Y1457835
X0525630Y1453504
X0638228Y1519252
X0629567Y1514922
X0638228Y1503898
X0629567Y1499567
X0638228Y1488544
X0629567Y1484213
X0638228Y1473189
X0629567Y1468859
X0638228Y1457835
X0629567Y1453504
X0655551Y1519252
X0646890Y1514922
X0655551Y1503898
X0646890Y1499567
X0655551Y1488544
X0646890Y1484213
X0655551Y1473189
X0646890Y1468859
X0655551Y1457835
X0646890Y1453504
X0664213Y1514922
X0664213Y1499567
X0664213Y1484213
X0664213Y1468859
X0664213Y1453504
X0638228Y1621615
X0629567Y1617284
X0638228Y1606260
X0629567Y1601930
X0638228Y1590906
X0629567Y1586575
X0638228Y1575552
X0629567Y1571221
X0638228Y1560197
X0629567Y1555867
X0655551Y1621615
X0646890Y1617284
X0655551Y1606260
X0646890Y1601930
X0655551Y1590906
X0646890Y1586575
X0655551Y1575552
X0646890Y1571221
X0655551Y1560197
X0646890Y1555867
X0664213Y1617284
X0664213Y1601930
X0664213Y1586575
X0664213Y1571221
X0664213Y1555867
X0672874Y1621615
X0672874Y1606260
X0672874Y1590906
X0672874Y1575552
X0672874Y1560197
X0690197Y1621615
X0681535Y1617284
X0690197Y1606260
X0681535Y1601930
X0690197Y1590906
X0681535Y1586575
X0690197Y1575552
X0681535Y1571221
X0690197Y1560197
X0681535Y1555867
X0707520Y1621615
X0698858Y1617284
X0707520Y1606260
X0698858Y1601930
X0707520Y1590906
X0698858Y1586575
X0707520Y1575552
X0698858Y1571221
X0707520Y1560197
X0698858Y1555867
X0672874Y1519252
X0672874Y1503898
X0672874Y1488544
X0672874Y1473189
X0672874Y1457835
X0690197Y1519252
X0681535Y1514922
X0690197Y1503898
X0681535Y1499567
X0690197Y1488544
X0681535Y1484213
X0690197Y1473189
X0681535Y1468859
X0690197Y1457835
X0681535Y1453504
X0707520Y1519252
X0698858Y1514922
X0707520Y1503898
X0698858Y1499567
X0707520Y1488544
X0698858Y1484213
X0707520Y1473189
X0698858Y1468859
X0707520Y1457835
X0698858Y1453504
X1140511Y1621615
X1131850Y1617284
X1140511Y1606260
X1131850Y1601930
X1140511Y1590906
X1131850Y1586575
X1140511Y1575552
X1131850Y1571221
X1140511Y1560197
X1131850Y1555867
X1157834Y1621615
X1149173Y1617284
X1157834Y1606260
X1149173Y1601930
X1157834Y1590906
X1149173Y1586575
X1157834Y1575552
X1149173Y1571221
X1157834Y1560197
X1149173Y1555867
X1166496Y1617284
X1166496Y1601930
X1166496Y1586575
X1166496Y1571221
X1166496Y1555867
X1140511Y1519252
X1131850Y1514922
X1140511Y1503898
X1131850Y1499567
X1140511Y1488544
X1131850Y1484213
X1140511Y1473189
X1131850Y1468859
X1140511Y1457835
X1131850Y1453504
X1157834Y1519252
X1149173Y1514922
X1157834Y1503898
X1149173Y1499567
X1157834Y1488544
X1149173Y1484213
X1157834Y1473189
X1149173Y1468859
X1157834Y1457835
X1149173Y1453504
X1166496Y1514922
X1166496Y1499567
X1166496Y1484213
X1166496Y1468859
X1166496Y1453504
X1175157Y1519252
X1175157Y1503898
X1175157Y1488544
X1175157Y1473189
X1175157Y1457835
X1192480Y1519252
X1183818Y1514922
X1192480Y1503898
X1183818Y1499567
X1192480Y1488544
X1183818Y1484213
X1192480Y1473189
X1183818Y1468859
X1192480Y1457835
X1183818Y1453504
X1209803Y1519252
X1201141Y1514922
X1209803Y1503898
X1201141Y1499567
X1209803Y1488544
X1201141Y1484213
X1209803Y1473189
X1201141Y1468859
X1209803Y1457835
X1201141Y1453504
X1175157Y1621615
X1175157Y1606260
X1175157Y1590906
X1175157Y1575552
X1175157Y1560197
X1192480Y1621615
X1183818Y1617284
X1192480Y1606260
X1183818Y1601930
X1192480Y1590906
X1183818Y1586575
X1192480Y1575552
X1183818Y1571221
X1192480Y1560197
X1183818Y1555867
X1209803Y1621615
X1201141Y1617284
X1209803Y1606260
X1201141Y1601930
X1209803Y1590906
X1201141Y1586575
X1209803Y1575552
X1201141Y1571221
X1209803Y1560197
X1201141Y1555867
X1313740Y1621615
X1305079Y1617284
X1313740Y1606260
X1305079Y1601930
X1313740Y1590906
X1305079Y1586575
X1313740Y1575552
X1305079Y1571221
X1313740Y1560197
X1305079Y1555867
X1331063Y1621615
X1322402Y1617284
X1331063Y1606260
X1322402Y1601930
X1331063Y1590906
X1322402Y1586575
X1331063Y1575552
X1322402Y1571221
X1331063Y1560197
X1322402Y1555867
X1348386Y1621615
X1339725Y1617284
X1348386Y1606260
X1339725Y1601930
X1348386Y1590906
X1339725Y1586575
X1348386Y1575552
X1339725Y1571221
X1348386Y1560197
X1339725Y1555867
X1365709Y1621615
X1357047Y1617284
X1365709Y1606260
X1357047Y1601930
X1365709Y1590906
X1357047Y1586575
X1365709Y1575552
X1357047Y1571221
X1365709Y1560197
X1357047Y1555867
X1313740Y1519252
X1305079Y1514922
X1313740Y1503898
X1305079Y1499567
X1313740Y1488544
X1305079Y1484213
X1313740Y1473189
X1305079Y1468859
X1313740Y1457835
X1305079Y1453504
X1331063Y1519252
X1322402Y1514922
X1331063Y1503898
X1322402Y1499567
X1331063Y1488544
X1322402Y1484213
X1331063Y1473189
X1322402Y1468859
X1331063Y1457835
X1322402Y1453504
X1348386Y1519252
X1339725Y1514922
X1348386Y1503898
X1339725Y1499567
X1348386Y1488544
X1339725Y1484213
X1348386Y1473189
X1339725Y1468859
X1348386Y1457835
X1339725Y1453504
X1365709Y1519252
X1357047Y1514922
X1365709Y1503898
X1357047Y1499567
X1365709Y1488544
X1357047Y1484213
X1365709Y1473189
X1357047Y1468859
X1365709Y1457835
X1357047Y1453504
X1383032Y1519252
X1374370Y1514922
X1383032Y1503898
X1374370Y1499567
X1383032Y1488544
X1374370Y1484213
X1383032Y1473189
X1374370Y1468859
X1383032Y1457835
X1374370Y1453504
X1383032Y1621615
X1374370Y1617284
X1383032Y1606260
X1374370Y1601930
X1383032Y1590906
X1374370Y1586575
X1383032Y1575552
X1374370Y1571221
X1383032Y1560197
X1374370Y1555867
X1486968Y1621615
X1478307Y1617284
X1486968Y1606260
X1478307Y1601930
X1486968Y1590906
X1478307Y1586575
X1486968Y1575552
X1478307Y1571221
X1486968Y1560197
X1478307Y1555867
X1504291Y1621615
X1495630Y1617284
X1504291Y1606260
X1495630Y1601930
X1504291Y1590906
X1495630Y1586575
X1504291Y1575552
X1495630Y1571221
X1504291Y1560197
X1495630Y1555867
X1521614Y1621615
X1512953Y1617284
X1521614Y1606260
X1512953Y1601930
X1521614Y1590906
X1512953Y1586575
X1521614Y1575552
X1512953Y1571221
X1521614Y1560197
X1512953Y1555867
X1538937Y1621615
X1530275Y1617284
X1538937Y1606260
X1530275Y1601930
X1538937Y1590906
X1530275Y1586575
X1538937Y1575552
X1530275Y1571221
X1538937Y1560197
X1530275Y1555867
X1556260Y1621615
X1547598Y1617284
X1556260Y1606260
X1547598Y1601930
X1556260Y1590906
X1547598Y1586575
X1556260Y1575552
X1547598Y1571221
X1556260Y1560197
X1547598Y1555867
X1486968Y1519252
X1478307Y1514922
X1486968Y1503898
X1478307Y1499567
X1486968Y1488544
X1478307Y1484213
X1486968Y1473189
X1478307Y1468859
X1486968Y1457835
X1478307Y1453504
X1504291Y1519252
X1495630Y1514922
X1504291Y1503898
X1495630Y1499567
X1504291Y1488544
X1495630Y1484213
X1504291Y1473189
X1495630Y1468859
X1504291Y1457835
X1495630Y1453504
X1521614Y1519252
X1512953Y1514922
X1521614Y1503898
X1512953Y1499567
X1521614Y1488544
X1512953Y1484213
X1521614Y1473189
X1512953Y1468859
X1521614Y1457835
X1512953Y1453504
X1538937Y1519252
X1530275Y1514922
X1538937Y1503898
X1530275Y1499567
X1538937Y1488544
X1530275Y1484213
X1538937Y1473189
X1530275Y1468859
X1538937Y1457835
X1530275Y1453504
X1556260Y1519252
X1547598Y1514922
X1556260Y1503898
X1547598Y1499567
X1556260Y1488544
X1547598Y1484213
X1556260Y1473189
X1547598Y1468859
X1556260Y1457835
X1547598Y1453504
X1660196Y1519252
X1651535Y1514922
X1660196Y1503898
X1651535Y1499567
X1660196Y1488544
X1651535Y1484213
X1660196Y1473189
X1651535Y1468859
X1660196Y1457835
X1651535Y1453504
X1668858Y1514922
X1668858Y1499567
X1668858Y1484213
X1668858Y1468859
X1668858Y1453504
X1660196Y1621615
X1651535Y1617284
X1660196Y1606260
X1651535Y1601930
X1660196Y1590906
X1651535Y1586575
X1660196Y1575552
X1651535Y1571221
X1660196Y1560197
X1651535Y1555867
X1668858Y1617284
X1668858Y1601930
X1668858Y1586575
X1668858Y1571221
X1668858Y1555867
X1677519Y1621615
X1677519Y1606260
X1677519Y1590906
X1677519Y1575552
X1677519Y1560197
X1694842Y1621615
X1686181Y1617284
X1694842Y1606260
X1686181Y1601930
X1694842Y1590906
X1686181Y1586575
X1694842Y1575552
X1686181Y1571221
X1694842Y1560197
X1686181Y1555867
X1712165Y1621615
X1703503Y1617284
X1712165Y1606260
X1703503Y1601930
X1712165Y1590906
X1703503Y1586575
X1712165Y1575552
X1703503Y1571221
X1712165Y1560197
X1703503Y1555867
X1729488Y1621615
X1720826Y1617284
X1729488Y1606260
X1720826Y1601930
X1729488Y1590906
X1720826Y1586575
X1729488Y1575552
X1720826Y1571221
X1729488Y1560197
X1720826Y1555867
X1677519Y1519252
X1677519Y1503898
X1677519Y1488544
X1677519Y1473189
X1677519Y1457835
X1694842Y1519252
X1686181Y1514922
X1694842Y1503898
X1686181Y1499567
X1694842Y1488544
X1686181Y1484213
X1694842Y1473189
X1686181Y1468859
X1694842Y1457835
X1686181Y1453504
X1712165Y1519252
X1703503Y1514922
X1712165Y1503898
X1703503Y1499567
X1712165Y1488544
X1703503Y1484213
X1712165Y1473189
X1703503Y1468859
X1712165Y1457835
X1703503Y1453504
X1729488Y1519252
X1720826Y1514922
X1729488Y1503898
X1720826Y1499567
X1729488Y1488544
X1720826Y1484213
X1729488Y1473189
X1720826Y1468859
X1729488Y1457835
X1720826Y1453504
M00
X0131031Y1263386
X0126843Y1273498
X0116731Y1277686
X0106619Y1273498
X0102431Y1263386
X0106619Y1253274
X0116731Y1249086
X0126843Y1253274
X0131031Y1066535
X0126843Y1076647
X0116731Y1080835
X0106619Y1076647
X0102431Y1066535
X0106619Y1056423
X0116731Y1052235
X0126843Y1056423
X0367252Y1263386
X0363064Y1273498
X0352952Y1277686
X0342840Y1273498
X0338652Y1263386
X0342840Y1253274
X0352952Y1249086
X0363064Y1253274
X0367252Y1066535
X0363064Y1076647
X0352952Y1080835
X0342840Y1076647
X0338652Y1066535
X0342840Y1056423
X0352952Y1052235
X0363064Y1056423
X0563706Y1273498
X0559518Y1263386
X0563706Y1253274
X0563706Y1076647
X0559518Y1066535
X0563706Y1056423
X0588118Y1066535
X0583930Y1076647
X0573818Y1080835
X0573818Y1052235
X0583930Y1056423
X0588118Y1263386
X0583930Y1273498
X0573818Y1277686
X0573818Y1249086
X0583930Y1253274
X0760433Y1500984
X0756274Y1490945
X0760433Y1480906
X0834277Y0388583
X0830118Y0398622
X0820079Y0402781
X0810040Y0398622
X0805881Y0388583
X0810040Y0378544
X0820079Y0374385
X0830118Y0378544
X0824338Y1066535
X0820150Y1076647
X0810038Y1080835
X0799926Y1076647
X0795738Y1066535
X0799926Y1056423
X0810038Y1052235
X0820150Y1056423
X0824338Y1263386
X0820150Y1273498
X0810038Y1277686
X0799926Y1273498
X0795738Y1263386
X0799926Y1253274
X0810038Y1249086
X0820150Y1253274
X0784670Y1490945
X0780511Y1500984
X0770472Y1505143
X0770472Y1476747
X0780511Y1480906
X1035064Y0388583
X1030905Y0398622
X1020866Y0402781
X1010827Y0398622
X1006668Y0388583
X1010827Y0378544
X1020866Y0374385
X1030905Y0378544
X1045205Y1066535
X1041017Y1076647
X1030905Y1080835
X1020793Y1076647
X1016605Y1066535
X1020793Y1056423
X1030905Y1052235
X1041017Y1056423
X1045205Y1263386
X1041017Y1273498
X1030905Y1277686
X1020793Y1273498
X1016605Y1263386
X1020793Y1253274
X1030905Y1249086
X1041017Y1253274
X1060433Y1500984
X1056274Y1490945
X1060433Y1480906
X1084670Y1490945
X1080511Y1500984
X1070472Y1505143
X1070472Y1476747
X1080511Y1480906
X1267125Y1080835
X1257013Y1076647
X1252825Y1066535
X1257013Y1056423
X1267125Y1052235
X1267125Y1277686
X1257013Y1273498
X1252825Y1263386
X1257013Y1253274
X1267125Y1249086
X1281425Y1263386
X1277237Y1273498
X1277237Y1253274
X1281425Y1066535
X1277237Y1076647
X1277237Y1056423
X1502291Y1263386
X1498103Y1273498
X1487991Y1277686
X1477879Y1273498
X1473691Y1263386
X1477879Y1253274
X1487991Y1249086
X1498103Y1253274
X1502291Y1066535
X1498103Y1076647
X1487991Y1080835
X1477879Y1076647
X1473691Y1066535
X1477879Y1056423
X1487991Y1052235
X1498103Y1056423
X1738512Y1263386
X1734324Y1273498
X1724212Y1277686
X1714100Y1273498
X1709912Y1263386
X1714100Y1253274
X1724212Y1249086
X1734324Y1253274
X1738512Y1066535
X1734324Y1076647
X1724212Y1080835
X1714100Y1076647
X1709912Y1066535
X1714100Y1056423
X1724212Y1052235
X1734324Y1056423
M00
X0923336Y0226772
X0923336Y0278740
X0895384Y0228740
X0895384Y0276772
M00
X0853012Y1612787
X0853012Y1602787
X0853012Y1592787
X0843012Y1612787
X0843012Y1602787
X0843012Y1592787
X0853012Y1622787
X0843012Y1622787
X0958012Y1622787
X0948012Y1622787
X0923012Y1622787
X0913012Y1622787
X0888012Y1622787
X0878012Y1622787
X0958012Y1612787
X0958012Y1602787
X0958012Y1592787
X0948012Y1612787
X0948012Y1602787
X0948012Y1592787
X0923012Y1612787
X0923012Y1602787
X0923012Y1592787
X0913012Y1612787
X0913012Y1602787
X0913012Y1592787
X0888012Y1612787
X0888012Y1602787
X0888012Y1592787
X0878012Y1612787
X0878012Y1602787
X0878012Y1592787
X1028012Y1612787
X1028012Y1602787
X1028012Y1592787
X1018012Y1612787
X1018012Y1602787
X1018012Y1592787
X0993012Y1612787
X0993012Y1602787
X0993012Y1592787
X0983012Y1612787
X0983012Y1602787
X0983012Y1592787
X1028012Y1622787
X1018012Y1622787
X0993012Y1622787
X0983012Y1622787
M00
X1030635Y0814546
X1030635Y0804546
X1030635Y0794546
X1030635Y0784546
X1030635Y0774546
X1030635Y0764546
X1030635Y0754546
X1030635Y0824546
M00
X0266841Y0421555
X0173829Y0455492
X0202844Y0455492
X0173829Y0583957
X0202844Y0583957
X0266841Y0550020
X0295856Y0550020
X0295856Y0421555
X0630915Y0455492
X0659930Y0455492
X0630915Y0583957
X0659930Y0583957
X0752942Y0550020
X0723927Y0550020
X0752942Y0421555
X0723927Y0421555
X1088002Y0583957
X1117017Y0583957
X1088002Y0455492
X1117017Y0455492
X1210029Y0421555
X1181014Y0421555
X1210029Y0550020
X1181014Y0550020
X1545089Y0583957
X1545089Y0455492
X1667116Y0421555
X1638101Y0421555
X1574104Y0455492
X1574104Y0583957
X1667116Y0550020
X1638101Y0550020
M00
X1236871Y1715189
X1250055Y1720189
X1250055Y1710189
X1235371Y1802909
X1248555Y1807909
X1248555Y1797909
X1236864Y1773377
X1250048Y1778377
X1250048Y1768377
X1236871Y1744208
X1250055Y1739208
X1250055Y1749208
X1747253Y1802909
X1734069Y1807909
X1734069Y1797909
X1747246Y1773377
X1734062Y1768377
X1734062Y1778377
X1747253Y1744208
X1734069Y1739208
X1734069Y1749208
X1747253Y1715189
X1734069Y1710189
X1734069Y1720189
M00
X0028819Y0081575
X0073307Y0061614
X0131181Y0081575
X0175669Y0061614
X0233543Y0081575
X0278032Y0061614
X0335906Y0081575
X0380394Y0061614
X0485886Y0081595
X0530394Y0061614
X0588248Y0081594
X0632756Y0061614
X0690611Y0081595
X0735118Y0061614
X0792973Y0081595
X0837480Y0061614
X0942973Y0081595
X0987480Y0061614
X1045335Y0081595
X1089843Y0061614
X1147697Y0081595
X1192205Y0061614
X1250060Y0081595
X1294567Y0061614
X1444567Y0061614
X1400060Y0081595
X1502441Y0081575
X1546929Y0061614
X1604784Y0081595
X1649291Y0061614
X1707146Y0081595
X1751654Y0061614
M00
X0013780Y1226024
X0079331Y1186654
X0390354Y1141024
X0536418Y1086654
X0854291Y1225118
X0993504Y1170748
X1304528Y1141024
X1450591Y1086654
X1761614Y1215000
X1827165Y1235630
M00
X0849441Y1367717
M00
X0062205Y0765197
X0023622Y1604724
X0074016Y0333464
X0102224Y0070866
X0433130Y0070866
X0463387Y0286221
X0463386Y0765197
X0409488Y1604724
X0661674Y0023622
X0785039Y1547638
X0920473Y0765196
X0890217Y0023622
X1055905Y1547637
X1118760Y0023622
X1347303Y0070866
X1377559Y0286220
X1377559Y0765197
X1431457Y1604724
X1575846Y0023622
X1766929Y0333464
X1795010Y0023622
X1778740Y0765197
X1817323Y1604724
M00
X0970071Y1365652
X0970071Y1409152
M00
X0735406Y-0026826
X0735406Y-0036826
X0710406Y-0026826
X0710406Y-0036826
X0735406Y-0036826
X0735406Y-0026826
X0710406Y-0036826
X0710406Y-0026826
X0855406Y-0066006
X0855406Y-0076006
X0830406Y-0066006
X0830406Y-0076006
X0855406Y-0076006
X0855406Y-0066006
X0830406Y-0076006
X0830406Y-0066006
X0964386Y-0075978
X0964386Y-0065978
X0964386Y-0065978
X0964386Y-0075978
X1063906Y-0086006
X0939542Y-0036798
X0939542Y-0026798
X0964542Y-0036798
X0964542Y-0026798
X0939542Y-0026798
X0939542Y-0036798
X0964542Y-0026798
X0964542Y-0036798
X0989386Y-0075978
X0989386Y-0065978
X0989386Y-0065978
X0989386Y-0075978
X1063906Y-0066006
X1063906Y-0076006
X1063906Y-0076006
X1018906Y-0026826
X1018906Y-0036826
X0993906Y-0026826
X0993906Y-0036826
X1018906Y-0046826
X1018906Y-0036826
X0993906Y-0046826
X0993906Y-0036826
X1088906Y-0066006
X1088906Y-0076006
X1217686Y-0085978
X1242686Y-0085978
X1088906Y-0076006
X1217686Y-0075978
X1217686Y-0065978
X1242686Y-0075978
X1242686Y-0065978
X1217686Y-0075978
X1242686Y-0075978
X1088906Y-0086006
X1223042Y-0036928
X1223042Y-0026928
X1248042Y-0036928
X1248042Y-0026928
X1223042Y-0036928
X1223042Y-0046928
X1248042Y-0036928
X1248042Y-0046928
X1345406Y-0066006
X1345406Y-0076006
X1320406Y-0066006
X1320406Y-0076006
X1345406Y-0076006
X1320406Y-0076006
X1305406Y-0026956
X1305406Y-0036956
X1280406Y-0026956
X1280406Y-0036956
X1305406Y-0046956
X1305406Y-0036956
X1280406Y-0046956
X1280406Y-0036956
X1345406Y-0086006
X1320406Y-0086006
X1474186Y-0075978
X1474186Y-0065978
X1499186Y-0075978
X1499186Y-0065978
X1599906Y-0086006
X1574906Y-0086006
X1474186Y-0075978
X1499186Y-0075978
X1509542Y-0037058
X1509542Y-0027058
X1534542Y-0037058
X1534542Y-0027058
X1564906Y-0027086
X1564906Y-0037086
X1564906Y-0047086
X1564906Y-0037086
X1509542Y-0037058
X1509542Y-0047058
X1534542Y-0037058
X1534542Y-0047058
X1599906Y-0066006
X1599906Y-0076006
X1574906Y-0066006
X1574906Y-0076006
X1599906Y-0076006
X1574906Y-0076006
X1474186Y-0085978
X1499186Y-0085978
X1589906Y-0027086
X1589906Y-0037086
X1589906Y-0047086
X1589906Y-0037086
X1728686Y-0075978
X1728686Y-0065978
X1753686Y-0075978
X1753686Y-0065978
X1728686Y-0075978
X1753686Y-0075978
X1728686Y-0085978
X1753686Y-0085978
X1794042Y-0037188
X1794042Y-0027188
X1819042Y-0037188
X1819042Y-0027188
X1794042Y-0037188
X1794042Y-0047188
X1819042Y-0037188
X1819042Y-0047188
M00
X0057933Y0066811
X0051043Y0144095
X0153405Y0144095
X0160295Y0066811
X0262657Y0066811
X0255767Y0144095
X0358129Y0144095
X0365019Y0066811
X0508130Y0144095
X0515020Y0066811
X0617382Y0066811
X0610492Y0144095
X0712854Y0144095
X0719744Y0066811
X0822106Y0066811
X0815216Y0144095
X0965216Y0144095
X0972106Y0066811
X1067578Y0144095
X1074468Y0066811
X1176830Y0066811
X1169940Y0144095
X1272302Y0144095
X1279192Y0066811
X1429193Y0066811
X1422303Y0144095
X1524665Y0144095
X1531555Y0066811
X1633917Y0066811
X1627027Y0144095
X1729389Y0144095
X1736279Y0066811
M00
X0190325Y0374862
X0183435Y0630650
X0279360Y0630650
X0286250Y0374862
X0647411Y0374862
X0640521Y0630650
X0736446Y0630650
X0743336Y0374862
X1097608Y0630650
X1104498Y0374862
X1200423Y0374862
X1193533Y0630650
X1554695Y0630650
X1561585Y0374862
X1657510Y0374862
X1650620Y0630650
M00
X0909360Y0230906
X0909360Y0274606
M00
X1817323Y1567323
M00
X0026789Y1373669
X0184851Y0334492
X1809883Y0120792
X1796847Y1517889
M00
X0235433Y1580079
X0235433Y1606142
X0235433Y1626339
X0581890Y1580079
X0581890Y1606142
X0581890Y1626339
X1259055Y1580079
X1259055Y1606142
X1259055Y1626339
X1605512Y1580079
X1605512Y1606142
X1605512Y1626339
M00
X0820079Y0388583
X0770472Y1490945
X1020866Y0388583
X1070472Y1490945
M00
X0116731Y1263386
X0116731Y1066535
X0352952Y1263386
X0352952Y1066535
X0573818Y1066535
X0573818Y1263386
X0810038Y1066535
X0810038Y1263386
X1030905Y1066535
X1030905Y1263386
X1267125Y1066535
X1267125Y1263386
X1487991Y1263386
X1487991Y1066535
X1724212Y1263386
X1724212Y1066535
M30
